G04 ================== begin FILE IDENTIFICATION RECORD ==================*
G04 Layout Name:  14545-sa.brd*
G04 Film Name:    TSILK*
G04 File Format:  Gerber RS274X*
G04 File Origin:  Cadence Allegro 16.5-S056*
G04 Origin Date:  Fri Aug 01 17:58:24 2014*
G04 *
G04 Layer:  VIA CLASS/FILMMASKTOP*
G04 Layer:  REF DES/ASSEMBLY_TOP*
G04 Layer:  PACKAGE GEOMETRY/SILKSCREEN_TOP*
G04 Layer:  DRAWING FORMAT/LAYER_PCB_STORY*
G04 Layer:  DRAWING FORMAT/LAYER_SILK_T*
G04 Layer:  BOARD GEOMETRY/SILKSCREEN_TOP*
G04 *
G04 Offset:    (0.00 0.00)*
G04 Mirror:    No*
G04 Mode:      Positive*
G04 Rotation:  0*
G04 FullContactRelief:  No*
G04 UndefLineWidth:     6.00*
G04 ================== end FILE IDENTIFICATION RECORD ====================*
%FSLAX35Y35*MOIN*%
%IR0*IPPOS*OFA0.00000B0.00000*MIA0B0*SFA1.00000B1.00000*%
%ADD10C,.01*%
%ADD11C,.02*%
%ADD12C,.012*%
%ADD13C,.013*%
%ADD14C,.015*%
%ADD15C,.016*%
%ADD16C,.019*%
%ADD17C,.0005*%
%ADD18C,.002*%
%ADD19C,.006*%
%ADD20C,.008*%
G75*
%LPD*%
G75*
G36*
G01X26143Y172165D02*
X28143Y174165D01*
Y170165D01*
X26143Y172165D01*
G37*
G36*
G01X91885Y166146D02*
X94385Y163646D01*
Y168646D01*
X91885Y166146D01*
G37*
G36*
G01X23443Y369717D02*
Y374717D01*
X20943Y372217D01*
X23443Y369717D01*
G37*
G36*
G01X91885Y571658D02*
X94385Y569158D01*
Y574158D01*
X91885Y571658D01*
G37*
G36*
G01X26143Y781614D02*
X28143Y783614D01*
Y779614D01*
X26143Y781614D01*
G37*
G36*
G01X91885Y977170D02*
X94385Y974670D01*
Y979670D01*
X91885Y977170D01*
G37*
G36*
G01X89399Y1137250D02*
X100599D01*
Y1119800D01*
X89399D01*
Y1137250D01*
G37*
G36*
G01X26143Y1156417D02*
X28143Y1158417D01*
Y1154417D01*
X26143Y1156417D01*
G37*
G36*
G01X23443Y1353969D02*
Y1358969D01*
X20943Y1356469D01*
X23443Y1353969D01*
G37*
G36*
G01X91885Y1382682D02*
X94385Y1380182D01*
Y1385182D01*
X91885Y1382682D01*
G37*
G36*
G01X26143Y1765866D02*
X28143Y1767866D01*
Y1763866D01*
X26143Y1765866D01*
G37*
G36*
G01X91885Y1788194D02*
X94385Y1785694D01*
Y1790694D01*
X91885Y1788194D01*
G37*
G36*
G01X30368Y1932862D02*
X34418D01*
X30368Y1936912D01*
Y1932862D01*
G37*
G36*
G01X144336Y203932D02*
X141836Y206432D01*
Y201432D01*
X144336Y203932D01*
G37*
G36*
G01X172267Y537378D02*
Y545378D01*
X163167D01*
Y537378D01*
X172267D01*
G37*
G36*
G01X144336Y609444D02*
X141836Y611944D01*
Y606944D01*
X144336Y609444D01*
G37*
G36*
G01Y1014956D02*
X141836Y1017456D01*
Y1012456D01*
X144336Y1014956D01*
G37*
G36*
G01X154099Y1214913D02*
X142899D01*
Y1232363D01*
X154099D01*
Y1214913D01*
G37*
G36*
G01X155299Y1292713D02*
Y1281513D01*
X172699D01*
Y1292713D01*
X155299D01*
G37*
G36*
G01X144336Y1420468D02*
X141836Y1422968D01*
Y1417968D01*
X144336Y1420468D01*
G37*
G36*
G01X116755Y1489071D02*
Y1497071D01*
X107655D01*
Y1489071D01*
X116755D01*
G37*
G36*
G01X172899Y1641813D02*
X184099D01*
Y1624363D01*
X172899D01*
Y1641813D01*
G37*
G36*
G01X156299Y1715713D02*
Y1704513D01*
X173699D01*
Y1715713D01*
X156299D01*
G37*
G36*
G01X144336Y1825980D02*
X141836Y1828480D01*
Y1823480D01*
X144336Y1825980D01*
G37*
G36*
G01X196826Y86528D02*
Y82478D01*
X200876Y86528D01*
X196826D01*
G37*
G36*
G01X269598Y311314D02*
X258398D01*
Y293914D01*
X269598D01*
Y311314D01*
G37*
G36*
G01X189599Y428850D02*
X178399D01*
Y446300D01*
X189599D01*
Y428850D01*
G37*
G36*
G01X190299Y529713D02*
Y518513D01*
X207699D01*
Y529713D01*
X190299D01*
G37*
G36*
G01X270099Y717750D02*
X258899D01*
Y700350D01*
X270099D01*
Y717750D01*
G37*
G36*
G01X214099Y827413D02*
X202899D01*
Y844863D01*
X214099D01*
Y827413D01*
G37*
G36*
G01X213799Y928213D02*
Y917013D01*
X231199D01*
Y928213D01*
X213799D01*
G37*
G36*
G01X231099Y1152250D02*
Y1141050D01*
X248499D01*
Y1152250D01*
X231099D01*
G37*
G36*
G01X268599Y1529250D02*
X257399D01*
Y1511850D01*
X268599D01*
Y1529250D01*
G37*
G36*
G01X271377Y1933391D02*
X260177D01*
Y1915991D01*
X271377D01*
Y1933391D01*
G37*
G36*
G01X284399Y367250D02*
X295599D01*
Y349800D01*
X284399D01*
Y367250D01*
G37*
G36*
G01X285399Y773750D02*
X296599D01*
Y756300D01*
X285399D01*
Y773750D01*
G37*
G36*
G01X284399Y1584750D02*
X295599D01*
Y1567300D01*
X284399D01*
Y1584750D01*
G37*
G36*
G01X284177Y1977391D02*
X295377D01*
Y1959941D01*
X284177D01*
Y1977391D01*
G37*
G36*
G01X360899Y37750D02*
X372099D01*
Y20300D01*
X360899D01*
Y37750D01*
G37*
G36*
G01X344799Y102150D02*
Y90950D01*
X362199D01*
Y102150D01*
X344799D01*
G37*
G36*
G01X415049Y1095050D02*
Y1130450D01*
X416049D01*
Y1096050D01*
X631549D01*
Y1095050D01*
X415049D01*
G37*
G36*
G01X428500Y1182500D02*
Y1177500D01*
X448500D01*
Y1182500D01*
X428500D01*
G37*
G36*
G01X833723Y181039D02*
Y189039D01*
X824623D01*
Y181039D01*
X833723D01*
G37*
G36*
G01X807273Y291271D02*
X818473D01*
Y308671D01*
X807273D01*
Y291271D01*
G37*
G36*
G01X793578Y340724D02*
X782378D01*
Y358174D01*
X793578D01*
Y340724D01*
G37*
G36*
G01X805231Y695653D02*
X816431D01*
Y713053D01*
X805231D01*
Y695653D01*
G37*
G36*
G01X792296Y741182D02*
X781096D01*
Y758632D01*
X792296D01*
Y741182D01*
G37*
G36*
G01X805241Y1100016D02*
X816441D01*
Y1117416D01*
X805241D01*
Y1100016D01*
G37*
G36*
G01X792433Y1142692D02*
X781233D01*
Y1160142D01*
X792433D01*
Y1142692D01*
G37*
G36*
G01X806645Y1502522D02*
X817845D01*
Y1519922D01*
X806645D01*
Y1502522D01*
G37*
G36*
G01X794927Y1547596D02*
X783727D01*
Y1565046D01*
X794927D01*
Y1547596D01*
G37*
G36*
G01X833723Y1803087D02*
Y1811087D01*
X824623D01*
Y1803087D01*
X833723D01*
G37*
G36*
G01X805836Y1909165D02*
X817036D01*
Y1926565D01*
X805836D01*
Y1909165D01*
G37*
G36*
G01X792414Y1953513D02*
X781214D01*
Y1970963D01*
X792414D01*
Y1953513D01*
G37*
G36*
G01X914649Y99550D02*
Y95500D01*
X918699Y99550D01*
X914649D01*
G37*
G36*
G01X872682Y203932D02*
X870182Y206432D01*
Y201432D01*
X872682Y203932D01*
G37*
G36*
G01Y609444D02*
X870182Y611944D01*
Y606944D01*
X872682Y609444D01*
G37*
G36*
G01Y1014956D02*
X870182Y1017456D01*
Y1012456D01*
X872682Y1014956D01*
G37*
G36*
G01Y1420468D02*
X870182Y1422968D01*
Y1417968D01*
X872682Y1420468D01*
G37*
G36*
G01X874750Y1711699D02*
X884750D01*
Y1706699D01*
X874750D01*
Y1711699D01*
G37*
G36*
G01X872682Y1825980D02*
X870182Y1828480D01*
Y1823480D01*
X872682Y1825980D01*
G37*
G36*
G01X990391Y1621176D02*
X988391Y1619176D01*
Y1623176D01*
X990391Y1621176D01*
G37*
G54D10*
G01X1112203Y468621D02*
G03Y458149I0J-5236D01*
G01Y500117D02*
G03Y489644I0J-5236D01*
G01Y531612D02*
G03Y521139I0J-5236D01*
G01Y563107D02*
G03Y552634I0J-5236D01*
G01Y594602D02*
G03Y584129I0J-5237D01*
G01Y626097D02*
G03Y615625I0J-5236D01*
G54D20*
G01X23500Y117500D02*
Y121500D01*
G01Y112500D02*
Y116500D01*
G01X17500Y1099500D02*
Y1095500D01*
G01Y1104500D02*
Y1100500D01*
G01X49199Y1969050D02*
X48099D01*
G01X51899D02*
X50799D01*
G01X19299Y1926550D02*
X20399D01*
G01X16599D02*
X17699D01*
G01X136300Y457800D02*
X132300D01*
G01X141499Y491613D02*
X137499D01*
G01X142699Y520613D02*
X141599D01*
G01X145399D02*
X144299D01*
G01X164499Y889113D02*
X160499D01*
G01X164999Y855613D02*
X160999D01*
G01X165699Y919113D02*
X164599D01*
G01X168399D02*
X167299D01*
G01X134600Y1177400D02*
X138600D01*
G01X106499Y1270613D02*
X102499D01*
G01X105999Y1238050D02*
X101999D01*
G01X107199Y1301113D02*
X106099D01*
G01X109899D02*
X108799D01*
G01X107499Y1676113D02*
X103499D01*
G01X104100Y1641500D02*
X100100D01*
G01X108699Y1705613D02*
X107599D01*
G01X111399D02*
X110299D01*
G01X239499Y77350D02*
Y78450D01*
G01Y74650D02*
Y75750D01*
G01X182999Y94250D02*
Y93150D01*
G01Y96950D02*
Y95850D01*
G01X216998Y315114D02*
X220998D01*
G01X222298Y284114D02*
X223398D01*
G01X219598D02*
X220698D01*
G01X211598Y348114D02*
X215598D01*
G01X216499Y722050D02*
X220499D01*
G01X222299Y690550D02*
X223399D01*
G01X219599D02*
X220699D01*
G01X212599Y755050D02*
X216599D01*
G01X215600Y1125000D02*
X219600D01*
G01X218300Y1087000D02*
X219400D01*
G01X215600D02*
X216700D01*
G01X215999Y1532050D02*
X219999D01*
G01X255200Y1537700D02*
X251200D01*
G01X221799Y1500550D02*
X222899D01*
G01X219099D02*
X220199D01*
G01X216814Y1923113D02*
X220814D01*
G01X211600Y1959600D02*
X215600D01*
G01X228614Y1894113D02*
X229714D01*
G01X225914D02*
X227014D01*
G01X295999Y59113D02*
X291999D01*
G01X291099Y26113D02*
X287099D01*
G01X296699Y89613D02*
X295599D01*
G01X299399D02*
X298299D01*
G01X772049Y1812134D02*
X754549D01*
G01X758049Y1799634D02*
Y1812134D01*
G01X772049Y1799634D02*
X758049D01*
G01X772049Y1812134D02*
Y1799634D01*
G01X781049Y1816634D02*
X785049D01*
G01X786049D02*
X790049D01*
G01X765049Y1809634D02*
X767549Y1812134D01*
G01X765049Y1809634D02*
X762549Y1812134D01*
G01X903499Y114250D02*
Y113150D01*
G01Y116950D02*
Y115850D01*
G01X856999Y309050D02*
X860999D01*
G01X854778Y277924D02*
X855878D01*
G01X852078D02*
X853178D01*
G01X862900Y342100D02*
X866900D01*
G01X853696Y709382D02*
X857696D01*
G01X853496Y678882D02*
X854596D01*
G01X850796D02*
X851896D01*
G01X860896Y743582D02*
X864896D01*
G01X853333Y1114892D02*
X857333D01*
G01X853133Y1084392D02*
X854233D01*
G01X850433D02*
X851533D01*
G01X860933Y1146392D02*
X864933D01*
G01X855827Y1519796D02*
X859827D01*
G01X863700Y1549600D02*
X867700D01*
G01X855127Y1489296D02*
X856227D01*
G01X852427D02*
X853527D01*
G01X892500Y1723500D02*
Y1719500D01*
G01X896800Y1707000D02*
X892800D01*
G01X893400Y1715400D02*
Y1714300D01*
G01Y1718100D02*
Y1717000D01*
G01X881401Y1693050D02*
Y1691950D01*
G01Y1695750D02*
Y1694650D01*
G01X855314Y1925613D02*
X859314D01*
G01X862500Y1959400D02*
X866500D01*
G01X855614Y1895113D02*
X856714D01*
G01X852914D02*
X854014D01*
G01X955499Y90350D02*
Y91450D01*
G01Y87650D02*
Y88750D01*
G01X968200Y1663500D02*
Y1667500D01*
G01Y1658500D02*
Y1662500D01*
G54D11*
G01X-71137Y-139897D02*
Y-219897D01*
G01D02*
X1129963D01*
G01X-75137Y-123897D02*
G02I-12000J0D01*
G01X-80287D02*
G02I-6850J0D01*
G01X-87137Y-139897D02*
Y-107897D01*
G01X-71137Y-123897D02*
X-103137D01*
G01X-71137Y-139897D02*
X1129963D01*
G01X-71137Y-175397D02*
X1129963D01*
G01X23500Y131500D02*
Y136500D01*
G01Y123500D02*
Y128500D01*
G01X63198Y204231D02*
Y211831D01*
G01Y609743D02*
Y617343D01*
G01X38500Y727800D02*
Y711200D01*
G01X55500Y741500D02*
Y736500D01*
G01X63198Y1015255D02*
Y1022855D01*
G01X82400Y1110000D02*
Y1116000D01*
G01X17500Y1119500D02*
Y1114500D01*
G01Y1111500D02*
Y1106500D01*
G01X63198Y1420767D02*
Y1428367D01*
G01X94400Y1590800D02*
Y1574200D01*
G01X63198Y1826279D02*
Y1833879D01*
G01X84999Y1898850D02*
Y1882250D01*
G01Y1878350D02*
Y1861750D01*
G01X63268Y1970262D02*
X68268D01*
G01X72068D02*
X77068D01*
G01X81068D02*
X86068D01*
G01X54568D02*
X59568D01*
G01X90068D02*
X95068D01*
G01X35499Y1972550D02*
X40499D01*
G01X146221Y101577D02*
X162821D01*
G01X125221D02*
X141821D01*
G01X173023Y165847D02*
Y158247D01*
G01Y571359D02*
Y563759D01*
G01X174717Y545678D02*
Y553378D01*
G01X173023Y976871D02*
Y969271D01*
G01X145600Y1199000D02*
Y1193000D01*
G01X173023Y1382383D02*
Y1374783D01*
G01X119205Y1497371D02*
Y1505071D01*
G01X107899Y1599650D02*
Y1594650D01*
G01X173023Y1787894D02*
Y1780294D01*
G01X235999Y72050D02*
Y67050D01*
G01Y36050D02*
Y31050D01*
G01Y54050D02*
Y49050D01*
G01Y45050D02*
Y40050D01*
G01Y63050D02*
Y58050D01*
G01X243499Y86050D02*
X238499D01*
G01X189100Y417500D02*
Y411500D01*
G01X216100Y815500D02*
Y809500D01*
G01X213600Y1658500D02*
Y1652500D01*
G01X342463Y-139897D02*
Y-219897D01*
G01X313400Y377000D02*
Y383000D01*
G01X306900Y782500D02*
Y788500D01*
G01Y1594000D02*
Y1600000D01*
G01X333000Y1975100D02*
X339000D01*
G01X356400Y50000D02*
Y56000D01*
G01X396999Y1300050D02*
X643000Y1300000D01*
X672000D01*
G01Y1230500D02*
X394000D01*
X393499Y1230550D01*
X393500Y1231000D01*
X393499Y1300050D01*
X396999D01*
G01X479963Y-139897D02*
Y-219897D01*
G01X594963Y-139897D02*
Y-219897D01*
G01X672000Y1300000D02*
Y1230500D01*
G01X670549Y1817834D02*
X662549D01*
G01X758049Y1812134D02*
X750049D01*
G01X762463Y-139897D02*
Y-219897D01*
G01X836173Y189339D02*
Y197039D01*
G01X765600Y365500D02*
Y359500D01*
G01X768600Y764500D02*
Y758500D01*
G01X765500Y1167800D02*
Y1161800D01*
G01X768100Y1571000D02*
Y1565000D01*
G01X836173Y1811387D02*
Y1819087D01*
G01X768600Y1975000D02*
Y1969000D01*
G01X853699Y108550D02*
X870299D01*
G01X874199D02*
X890799D01*
G01X901369Y165847D02*
Y158247D01*
G01Y571359D02*
Y563759D01*
G01Y976871D02*
Y969271D01*
G01Y1382383D02*
Y1374783D01*
G01X878650Y1724300D02*
X873800D01*
Y1718700D01*
X878650D01*
G01X872000Y1706899D02*
Y1699899D01*
G01X901369Y1787894D02*
Y1780294D01*
G01X932463Y-139897D02*
Y-219897D01*
G01X954999Y48550D02*
Y43550D01*
G01Y66550D02*
Y61550D01*
G01Y57550D02*
Y52550D01*
G01X952999Y104050D02*
Y99050D01*
G01X954999Y75550D02*
Y70550D01*
G01Y84550D02*
Y79550D01*
G01X1129963Y-139897D02*
Y-219897D01*
G01X1157963Y-123897D02*
G02I-12000J0D01*
G01X1152813D02*
G02I-6850J0D01*
G01X1145963Y-139897D02*
Y-107897D01*
G01X1161963Y-123897D02*
X1129963D01*
G54D12*
G01X0Y41772D02*
Y17214D01*
G01X-1Y129516D02*
Y104958D01*
G01Y324003D02*
Y300383D01*
G01X0Y933234D02*
Y905988D01*
G01X-1Y1092625D02*
Y1069005D01*
G01X0Y1309889D02*
Y1280567D01*
G01Y1986547D02*
Y1962927D01*
G01Y1912843D02*
Y1889223D01*
G01X66748Y12647D02*
G02Y21447I0J4400D01*
G01D02*
X71048D01*
G01D02*
G02Y12647I0J-4400D01*
G01D02*
X66748D01*
G01Y185875D02*
G02Y194675I0J4400D01*
G01D02*
X71048D01*
G01D02*
G02Y185875I0J-4400D01*
G01D02*
X66748D01*
G01Y418159D02*
G02Y426959I0J4400D01*
G01D02*
X71048D01*
G01D02*
G02Y418159I0J-4400D01*
G01D02*
X66748D01*
G01Y591387D02*
G02Y600187I0J4400D01*
G01D02*
X71048D01*
G01D02*
G02Y591387I0J-4400D01*
G01D02*
X66748D01*
G01Y823671D02*
G02Y832471I0J4400D01*
G01D02*
X71048D01*
G01D02*
G02Y823671I0J-4400D01*
G01D02*
X66748D01*
G01Y996899D02*
G02Y1005699I0J4400D01*
G01D02*
X71048D01*
G01D02*
G02Y996899I0J-4400D01*
G01D02*
X66748D01*
G01Y1229183D02*
G02Y1237983I0J4400D01*
G01D02*
X71048D01*
G01D02*
G02Y1229183I0J-4400D01*
G01D02*
X66748D01*
G01Y1402411D02*
G02Y1411211I0J4400D01*
G01D02*
X71048D01*
G01D02*
G02Y1402411I0J-4400D01*
G01D02*
X66748D01*
G01Y1634695D02*
G02Y1643495I0J4400D01*
G01X71048D02*
G02Y1634695I0J-4400D01*
G01D02*
X66748D01*
G01Y1643495D02*
X71048D01*
G01X66748Y1807923D02*
G02Y1816723I0J4400D01*
G01D02*
X71048D01*
G01D02*
G02Y1807923I0J-4400D01*
G01D02*
X66748D01*
G01X169473Y184203D02*
G02Y175403I0J-4400D01*
G01D02*
X165173D01*
G01D02*
G02Y184203I0J4400D01*
G01D02*
X169473D01*
G01Y357431D02*
G02Y348631I0J-4400D01*
G01D02*
X165173D01*
G01D02*
G02Y357431I0J4400D01*
G01D02*
X169473D01*
G01Y589715D02*
G02Y580915I0J-4400D01*
G01D02*
X165173D01*
G01D02*
G02Y589715I0J4400D01*
G01D02*
X169473D01*
G01Y762943D02*
G02Y754143I0J-4400D01*
G01D02*
X165173D01*
G01D02*
G02Y762943I0J4400D01*
G01D02*
X169473D01*
G01Y995227D02*
G02Y986427I0J-4400D01*
G01D02*
X165173D01*
G01D02*
G02Y995227I0J4400D01*
G01D02*
X169473D01*
G01Y1168455D02*
G02Y1159655I0J-4400D01*
G01D02*
X165173D01*
G01D02*
G02Y1168455I0J4400D01*
G01D02*
X169473D01*
G01Y1400739D02*
G02Y1391939I0J-4400D01*
G01D02*
X165173D01*
G01D02*
G02Y1400739I0J4400D01*
G01D02*
X169473D01*
G01Y1573967D02*
G02Y1565167I0J-4400D01*
G01D02*
X165173D01*
G01D02*
G02Y1573967I0J4400D01*
G01D02*
X169473D01*
G01Y1806251D02*
G02Y1797451I0J-4400D01*
G01D02*
X165173D01*
G01D02*
G02Y1806251I0J4400D01*
G01D02*
X169473D01*
G01Y1979479D02*
G02Y1970679I0J-4400D01*
G01D02*
X165173D01*
G01D02*
G02Y1979479I0J4400D01*
G01D02*
X169473D01*
G01X897819Y184203D02*
G02Y175403I0J-4400D01*
G01D02*
X893519D01*
G01D02*
G02Y184203I0J4400D01*
G01D02*
X897819D01*
G01Y357431D02*
G02Y348631I0J-4400D01*
G01D02*
X893519D01*
G01D02*
G02Y357431I0J4400D01*
G01D02*
X897819D01*
G01Y589715D02*
G02Y580915I0J-4400D01*
G01D02*
X893519D01*
G01D02*
G02Y589715I0J4400D01*
G01D02*
X897819D01*
G01Y762943D02*
G02Y754143I0J-4400D01*
G01D02*
X893519D01*
G01D02*
G02Y762943I0J4400D01*
G01D02*
X897819D01*
G01Y995227D02*
G02Y986427I0J-4400D01*
G01D02*
X893519D01*
G01D02*
G02Y995227I0J4400D01*
G01D02*
X897819D01*
G01Y1168455D02*
G02Y1159655I0J-4400D01*
G01D02*
X893519D01*
G01D02*
G02Y1168455I0J4400D01*
G01D02*
X897819D01*
G01Y1400739D02*
G02Y1391939I0J-4400D01*
G01D02*
X893519D01*
G01D02*
G02Y1400739I0J4400D01*
G01D02*
X897819D01*
G01Y1573967D02*
G02Y1565167I0J-4400D01*
G01D02*
X893519D01*
G01D02*
G02Y1573967I0J4400D01*
G01D02*
X897819D01*
G01Y1806251D02*
G02Y1797451I0J-4400D01*
G01D02*
X893519D01*
G01D02*
G02Y1806251I0J4400D01*
G01D02*
X897819D01*
G01Y1979479D02*
G02Y1970679I0J-4400D01*
G01D02*
X893519D01*
G01D02*
G02Y1979479I0J4400D01*
G01D02*
X897819D01*
G01X1033464Y48297D02*
Y24677D01*
G01X1033465Y240964D02*
Y217344D01*
G01Y468660D02*
Y445040D01*
G01Y721094D02*
Y697474D01*
G01Y721094D02*
Y697474D01*
G01Y1020472D02*
Y996852D01*
G01Y1367680D02*
Y1344060D01*
G01Y1763340D02*
Y1739720D01*
G01X1033464Y1982862D02*
Y1959242D01*
G54D13*
G01X26193Y171391D02*
Y172891D01*
G01X38799Y210400D02*
Y214800D01*
X42299D01*
G01X91948Y164261D02*
Y168061D01*
G01X20993Y373767D02*
Y370217D01*
G01X77699Y649400D02*
Y645000D01*
X74199D01*
G01X91948Y569773D02*
Y573573D01*
G01X26193Y780840D02*
Y782340D01*
G01X91948Y975285D02*
Y979085D01*
G01X17199Y1058550D02*
Y1062950D01*
X20699D01*
G01X26193Y1155643D02*
Y1157143D01*
G01X20993Y1358019D02*
Y1354469D01*
G01X91948Y1380797D02*
Y1384597D01*
G01X26193Y1765092D02*
Y1766592D01*
G01X91948Y1786309D02*
Y1790109D01*
G01X56799Y1845100D02*
Y1849500D01*
X60299D01*
G01X144273Y205817D02*
Y202017D01*
G01X145399Y423013D02*
X142549D01*
Y425713D01*
G01X173149Y490953D02*
Y493803D01*
X175849D01*
G01X144273Y611329D02*
Y607529D01*
G01X167399Y816513D02*
X164549D01*
Y819213D01*
G01X144273Y1016841D02*
Y1013041D01*
G01X109399Y1075450D02*
X106549D01*
Y1078150D01*
G01X120099Y1093950D02*
Y1091100D01*
X117399D01*
G01X106899Y1206513D02*
X104049D01*
Y1209213D01*
G01X120099Y1315650D02*
X122949D01*
Y1312950D01*
G01X140899Y1349050D02*
Y1344650D01*
X137399D01*
G01X144273Y1422353D02*
Y1418553D01*
G01X113399Y1720150D02*
Y1723000D01*
X116099D01*
G01X132899Y1710950D02*
X130049D01*
Y1713650D01*
G01X144273Y1827865D02*
Y1824065D01*
G01X197199Y158700D02*
Y154300D01*
X193699D01*
G01X197199Y565900D02*
Y561500D01*
X193699D01*
G01X208599Y895650D02*
X211449D01*
Y892950D01*
G01X197199Y969600D02*
Y965200D01*
X193699D01*
G01X211699Y1374300D02*
Y1369900D01*
X208199D01*
G01X197699Y1780000D02*
Y1775600D01*
X194199D01*
G01X284099Y337650D02*
X286949D01*
Y334950D01*
G01X325598Y334014D02*
Y331164D01*
X322898D01*
G01X285099Y744150D02*
X287949D01*
Y741450D01*
G01X327099Y740950D02*
Y738100D01*
X324399D01*
G01X284099Y1555150D02*
X286949D01*
Y1552450D01*
G01X323599Y1554450D02*
Y1551600D01*
X320899D01*
G01X330821Y1944309D02*
Y1941459D01*
X328121D01*
G01X288749Y1946550D02*
X291599D01*
Y1943850D01*
G01X343899Y67150D02*
Y70000D01*
X346599D01*
G01X383899Y56150D02*
Y59000D01*
X386599D01*
G01X790599Y331650D02*
X793449D01*
Y328950D01*
G01X771578Y323824D02*
Y320974D01*
X768878D01*
G01X770796Y724782D02*
Y721932D01*
X768096D01*
G01X790099Y732650D02*
X792949D01*
Y729950D01*
G01X789599Y1135650D02*
X792449D01*
Y1132950D01*
G01X770933Y1126292D02*
Y1123442D01*
X768233D01*
G01X792853Y1539478D02*
X795703D01*
Y1536778D01*
G01X773927Y1531196D02*
Y1528346D01*
X771227D01*
G01X791099Y1946150D02*
X793949D01*
Y1943450D01*
G01X770414Y1937113D02*
Y1934263D01*
X767714D01*
G01X872619Y205817D02*
Y202017D01*
G01X925699Y564400D02*
Y560000D01*
X922199D01*
G01X872619Y611329D02*
Y607529D01*
G01X925699Y968600D02*
Y964200D01*
X922199D01*
G01X872619Y1016841D02*
Y1013041D01*
G01X852799Y1365300D02*
Y1369700D01*
X856299D01*
G01X872619Y1422353D02*
Y1418553D01*
G01X925199Y1778500D02*
Y1774100D01*
X921699D01*
G01X872619Y1827865D02*
Y1824065D01*
G01X943199Y165200D02*
Y160800D01*
X939699D01*
G01X990341Y1621876D02*
Y1620376D01*
G54D14*
G01X153649Y1273563D02*
Y1281313D01*
G01X154649Y1696563D02*
Y1704313D01*
G01X250448Y312964D02*
X258198D01*
G01X188649Y510563D02*
Y518313D01*
G01X250949Y719400D02*
X258699D01*
G01X212149Y909063D02*
Y916813D01*
G01X229449Y1133100D02*
Y1140850D01*
G01X249449Y1530900D02*
X257199D01*
G01X252227Y1935041D02*
X259977D01*
G01X343149Y83000D02*
Y90750D01*
G01X826423Y289621D02*
X818673D01*
G01X824381Y694003D02*
X816631D01*
G01X824391Y1098366D02*
X816641D01*
G01X825795Y1500872D02*
X818045D01*
G01X824986Y1907515D02*
X817236D01*
G54D15*
G01X170499Y447850D02*
X178199D01*
G01X108499Y1118250D02*
X100799D01*
G01X134999Y1233913D02*
X142699D01*
G01X194999Y846413D02*
X202699D01*
G01X191999Y1622813D02*
X184299D01*
G01X303499Y348250D02*
X295799D01*
G01X304499Y754750D02*
X296799D01*
G01X303499Y1565750D02*
X295799D01*
G01X303277Y1958391D02*
X295577D01*
G01X379999Y18750D02*
X372299D01*
G01X774478Y359724D02*
X782178D01*
G01X773196Y760182D02*
X780896D01*
G01X773333Y1161692D02*
X781033D01*
G01X775827Y1566596D02*
X783527D01*
G01X773314Y1972513D02*
X781014D01*
G54D16*
G01X155999Y440613D02*
X159399D01*
G01X138500Y548000D02*
Y551400D01*
G01X115799Y1104200D02*
X112399D01*
G01X120999Y1221113D02*
X124399D01*
G01X149700Y1322100D02*
X146300D01*
G01X177699Y1655427D02*
X181099D01*
G01X169800Y1676100D02*
Y1679500D01*
G01X239600Y272800D02*
Y276200D01*
G01X239000Y680200D02*
Y683600D01*
G01X179499Y839113D02*
X182899D01*
G01X178900Y934800D02*
Y938200D01*
G01X244300Y1066560D02*
X240900D01*
G01X231300Y1480800D02*
X234700D01*
G01X215800Y1885400D02*
X219200D01*
G01X327100Y89900D02*
X323700D01*
G01X313499Y350050D02*
Y353450D01*
G01X314499Y757050D02*
Y760450D01*
G01X313499Y1567550D02*
Y1570950D01*
G01X316640Y1956772D02*
Y1960172D01*
G01X396499Y34050D02*
X393099D01*
G01X756478Y344424D02*
X759878D01*
G01X754696Y744882D02*
X758096D01*
G01X754499Y1149050D02*
X757899D01*
G01X756827Y1551796D02*
X760227D01*
G01X754814Y1957213D02*
X758214D01*
G01X812400Y272500D02*
X815800D01*
G01X810900Y675100D02*
X814300D01*
G01X810600Y1077900D02*
X814000D01*
G01X812400Y1485600D02*
X815800D01*
G01X813000Y1890000D02*
X816400D01*
G54D17*
G01X38811Y211852D02*
Y211749D01*
G01X38736Y211927D02*
Y211674D01*
G01X38661Y212002D02*
Y211599D01*
G01X38586Y212077D02*
Y211524D01*
G01X38511Y212152D02*
Y211449D01*
G01X38436Y212227D02*
Y211374D01*
G01X38361Y212302D02*
Y211299D01*
G01X38286Y212377D02*
Y211224D01*
G01X38211Y212452D02*
Y211149D01*
G01X38136Y212527D02*
Y211074D01*
G01X38061Y212602D02*
Y210999D01*
G01X37986Y212677D02*
Y210924D01*
G01X37911Y212752D02*
Y210849D01*
G01X37836Y212827D02*
Y210774D01*
G01X37752Y210731D02*
X37769Y212884D01*
G01X37726Y212937D02*
X38864Y211800D01*
G01D02*
X37724Y210661D01*
G01Y210720D02*
Y212880D01*
G01Y212936D02*
Y210661D01*
G01X37799Y212864D02*
Y210736D01*
G01X37874Y212789D02*
Y210811D01*
G01X37949Y212714D02*
Y210886D01*
G01X38024Y212639D02*
Y210961D01*
G01X38099Y212564D02*
Y211036D01*
G01X38174Y212489D02*
Y211111D01*
G01X38249Y212414D02*
Y211186D01*
G01X38324Y212339D02*
Y211261D01*
G01X38399Y212264D02*
Y211336D01*
G01X38474Y212189D02*
Y211411D01*
G01X38549Y212114D02*
Y211486D01*
G01X38624Y212039D02*
Y211561D01*
G01X38699Y211964D02*
Y211636D01*
G01X38774Y211889D02*
Y211711D01*
G01X38849Y211814D02*
Y211786D01*
G01X77687Y647948D02*
Y648051D01*
G01X77762Y647873D02*
Y648126D01*
G01X77837Y647798D02*
Y648201D01*
G01X77912Y647723D02*
Y648276D01*
G01X77987Y647648D02*
Y648351D01*
G01X78062Y647573D02*
Y648426D01*
G01X78137Y647498D02*
Y648501D01*
G01X78212Y647423D02*
Y648576D01*
G01X78287Y647348D02*
Y648651D01*
G01X78362Y647273D02*
Y648726D01*
G01X78437Y647198D02*
Y648801D01*
G01X78512Y647123D02*
Y648876D01*
G01X78587Y647048D02*
Y648951D01*
G01X78662Y646973D02*
Y649026D01*
G01X78746Y649069D02*
X78729Y646916D01*
G01X78772Y646863D02*
X77634Y648000D01*
G01D02*
X78774Y649139D01*
G01Y649080D02*
Y646920D01*
G01Y646864D02*
Y649139D01*
G01X78699Y646936D02*
Y649064D01*
G01X78624Y647011D02*
Y648989D01*
G01X78549Y647086D02*
Y648914D01*
G01X78474Y647161D02*
Y648839D01*
G01X78399Y647236D02*
Y648764D01*
G01X78324Y647311D02*
Y648689D01*
G01X78249Y647386D02*
Y648614D01*
G01X78174Y647461D02*
Y648539D01*
G01X78099Y647536D02*
Y648464D01*
G01X78024Y647611D02*
Y648389D01*
G01X77949Y647686D02*
Y648314D01*
G01X77874Y647761D02*
Y648239D01*
G01X77799Y647836D02*
Y648164D01*
G01X77724Y647911D02*
Y648089D01*
G01X77649Y647986D02*
Y648014D01*
G01X17211Y1060002D02*
Y1059899D01*
G01X17136Y1060077D02*
Y1059824D01*
G01X17061Y1060152D02*
Y1059749D01*
G01X16986Y1060227D02*
Y1059674D01*
G01X16911Y1060302D02*
Y1059599D01*
G01X16836Y1060377D02*
Y1059524D01*
G01X16761Y1060452D02*
Y1059449D01*
G01X16686Y1060527D02*
Y1059374D01*
G01X16611Y1060602D02*
Y1059299D01*
G01X16536Y1060677D02*
Y1059224D01*
G01X16461Y1060752D02*
Y1059149D01*
G01X16386Y1060827D02*
Y1059074D01*
G01X16311Y1060902D02*
Y1058999D01*
G01X16236Y1060977D02*
Y1058924D01*
G01X16152Y1058881D02*
X16169Y1061034D01*
G01X16126Y1061087D02*
X17264Y1059950D01*
G01D02*
X16124Y1058811D01*
G01Y1058870D02*
Y1061030D01*
G01Y1061086D02*
Y1058811D01*
G01X16199Y1061014D02*
Y1058886D01*
G01X16274Y1060939D02*
Y1058961D01*
G01X16349Y1060864D02*
Y1059036D01*
G01X16424Y1060789D02*
Y1059111D01*
G01X16499Y1060714D02*
Y1059186D01*
G01X16574Y1060639D02*
Y1059261D01*
G01X16649Y1060564D02*
Y1059336D01*
G01X16724Y1060489D02*
Y1059411D01*
G01X16799Y1060414D02*
Y1059486D01*
G01X16874Y1060339D02*
Y1059561D01*
G01X16949Y1060264D02*
Y1059636D01*
G01X17024Y1060189D02*
Y1059711D01*
G01X17099Y1060114D02*
Y1059786D01*
G01X17174Y1060039D02*
Y1059861D01*
G01X17249Y1059964D02*
Y1059936D01*
G01X56811Y1846552D02*
Y1846449D01*
G01X56736Y1846627D02*
Y1846374D01*
G01X56661Y1846702D02*
Y1846299D01*
G01X56586Y1846777D02*
Y1846224D01*
G01X56511Y1846852D02*
Y1846149D01*
G01X56436Y1846927D02*
Y1846074D01*
G01X56361Y1847002D02*
Y1845999D01*
G01X56286Y1847077D02*
Y1845924D01*
G01X56211Y1847152D02*
Y1845849D01*
G01X56136Y1847227D02*
Y1845774D01*
G01X56061Y1847302D02*
Y1845699D01*
G01X55986Y1847377D02*
Y1845624D01*
G01X55911Y1847452D02*
Y1845549D01*
G01X55836Y1847527D02*
Y1845474D01*
G01X55752Y1845431D02*
X55769Y1847584D01*
G01X55726Y1847637D02*
X56864Y1846500D01*
G01D02*
X55724Y1845361D01*
G01Y1845420D02*
Y1847580D01*
G01Y1847636D02*
Y1845361D01*
G01X55799Y1847564D02*
Y1845436D01*
G01X55874Y1847489D02*
Y1845511D01*
G01X55949Y1847414D02*
Y1845586D01*
G01X56024Y1847339D02*
Y1845661D01*
G01X56099Y1847264D02*
Y1845736D01*
G01X56174Y1847189D02*
Y1845811D01*
G01X56249Y1847114D02*
Y1845886D01*
G01X56324Y1847039D02*
Y1845961D01*
G01X56399Y1846964D02*
Y1846036D01*
G01X56474Y1846889D02*
Y1846111D01*
G01X56549Y1846814D02*
Y1846186D01*
G01X56624Y1846739D02*
Y1846261D01*
G01X56699Y1846664D02*
Y1846336D01*
G01X56774Y1846589D02*
Y1846411D01*
G01X56849Y1846514D02*
Y1846486D01*
G01X140887Y1347598D02*
Y1347701D01*
G01X140962Y1347523D02*
Y1347776D01*
G01X141037Y1347448D02*
Y1347851D01*
G01X141112Y1347373D02*
Y1347926D01*
G01X141187Y1347298D02*
Y1348001D01*
G01X141262Y1347223D02*
Y1348076D01*
G01X141337Y1347148D02*
Y1348151D01*
G01X141412Y1347073D02*
Y1348226D01*
G01X141487Y1346998D02*
Y1348301D01*
G01X141562Y1346923D02*
Y1348376D01*
G01X141637Y1346848D02*
Y1348451D01*
G01X141712Y1346773D02*
Y1348526D01*
G01X141787Y1346698D02*
Y1348601D01*
G01X141862Y1346623D02*
Y1348676D01*
G01X141946Y1348719D02*
X141929Y1346566D01*
G01X141972Y1346513D02*
X140834Y1347650D01*
G01D02*
X141974Y1348789D01*
G01Y1348730D02*
Y1346570D01*
G01Y1346514D02*
Y1348789D01*
G01X141899Y1346586D02*
Y1348714D01*
G01X141824Y1346661D02*
Y1348639D01*
G01X141749Y1346736D02*
Y1348564D01*
G01X141674Y1346811D02*
Y1348489D01*
G01X141599Y1346886D02*
Y1348414D01*
G01X141524Y1346961D02*
Y1348339D01*
G01X141449Y1347036D02*
Y1348264D01*
G01X141374Y1347111D02*
Y1348189D01*
G01X141299Y1347186D02*
Y1348114D01*
G01X141224Y1347261D02*
Y1348039D01*
G01X141149Y1347336D02*
Y1347964D01*
G01X141074Y1347411D02*
Y1347889D01*
G01X140999Y1347486D02*
Y1347814D01*
G01X140924Y1347561D02*
Y1347739D01*
G01X140849Y1347636D02*
Y1347664D01*
G01X197187Y157248D02*
Y157351D01*
G01X197262Y157173D02*
Y157426D01*
G01X197337Y157098D02*
Y157501D01*
G01X197412Y157023D02*
Y157576D01*
G01X197487Y156948D02*
Y157651D01*
G01X197562Y156873D02*
Y157726D01*
G01X197637Y156798D02*
Y157801D01*
G01X197712Y156723D02*
Y157876D01*
G01X197787Y156648D02*
Y157951D01*
G01X197862Y156573D02*
Y158026D01*
G01X197937Y156498D02*
Y158101D01*
G01X198012Y156423D02*
Y158176D01*
G01X198087Y156348D02*
Y158251D01*
G01X198162Y156273D02*
Y158326D01*
G01X198246Y158369D02*
X198229Y156216D01*
G01X198272Y156163D02*
X197134Y157300D01*
G01D02*
X198274Y158439D01*
G01Y158380D02*
Y156220D01*
G01Y156164D02*
Y158439D01*
G01X198199Y156236D02*
Y158364D01*
G01X198124Y156311D02*
Y158289D01*
G01X198049Y156386D02*
Y158214D01*
G01X197974Y156461D02*
Y158139D01*
G01X197899Y156536D02*
Y158064D01*
G01X197824Y156611D02*
Y157989D01*
G01X197749Y156686D02*
Y157914D01*
G01X197674Y156761D02*
Y157839D01*
G01X197599Y156836D02*
Y157764D01*
G01X197524Y156911D02*
Y157689D01*
G01X197449Y156986D02*
Y157614D01*
G01X197374Y157061D02*
Y157539D01*
G01X197299Y157136D02*
Y157464D01*
G01X197224Y157211D02*
Y157389D01*
G01X197149Y157286D02*
Y157314D01*
G01X198272Y563363D02*
X197134Y564500D01*
G01X198274Y563364D02*
Y565639D01*
G01X197187Y564448D02*
Y564551D01*
G01X197262Y564373D02*
Y564626D01*
G01X197337Y564298D02*
Y564701D01*
G01X197412Y564223D02*
Y564776D01*
G01X197487Y564148D02*
Y564851D01*
G01X197562Y564073D02*
Y564926D01*
G01X197637Y563998D02*
Y565001D01*
G01X197712Y563923D02*
Y565076D01*
G01X197787Y563848D02*
Y565151D01*
G01X197862Y563773D02*
Y565226D01*
G01X197937Y563698D02*
Y565301D01*
G01X198012Y563623D02*
Y565376D01*
G01X198087Y563548D02*
Y565451D01*
G01X198162Y563473D02*
Y565526D01*
G01X198246Y565569D02*
X198229Y563416D01*
G01X197134Y564500D02*
X198274Y565639D01*
G01Y565580D02*
Y563420D01*
G01X198199Y563436D02*
Y565564D01*
G01X198124Y563511D02*
Y565489D01*
G01X198049Y563586D02*
Y565414D01*
G01X197974Y563661D02*
Y565339D01*
G01X197899Y563736D02*
Y565264D01*
G01X197824Y563811D02*
Y565189D01*
G01X197749Y563886D02*
Y565114D01*
G01X197674Y563961D02*
Y565039D01*
G01X197599Y564036D02*
Y564964D01*
G01X197524Y564111D02*
Y564889D01*
G01X197449Y564186D02*
Y564814D01*
G01X197374Y564261D02*
Y564739D01*
G01X197299Y564336D02*
Y564664D01*
G01X197224Y564411D02*
Y564589D01*
G01X197149Y564486D02*
Y564514D01*
G01X197187Y968148D02*
Y968251D01*
G01X197262Y968073D02*
Y968326D01*
G01X197337Y967998D02*
Y968401D01*
G01X197412Y967923D02*
Y968476D01*
G01X197487Y967848D02*
Y968551D01*
G01X197562Y967773D02*
Y968626D01*
G01X197637Y967698D02*
Y968701D01*
G01X197712Y967623D02*
Y968776D01*
G01X197787Y967548D02*
Y968851D01*
G01X197862Y967473D02*
Y968926D01*
G01X197937Y967398D02*
Y969001D01*
G01X198012Y967323D02*
Y969076D01*
G01X198087Y967248D02*
Y969151D01*
G01X198162Y967173D02*
Y969226D01*
G01X198246Y969269D02*
X198229Y967116D01*
G01X198272Y967063D02*
X197134Y968200D01*
G01D02*
X198274Y969339D01*
G01Y969280D02*
Y967120D01*
G01Y967064D02*
Y969339D01*
G01X198199Y967136D02*
Y969264D01*
G01X198124Y967211D02*
Y969189D01*
G01X198049Y967286D02*
Y969114D01*
G01X197974Y967361D02*
Y969039D01*
G01X197899Y967436D02*
Y968964D01*
G01X197824Y967511D02*
Y968889D01*
G01X197749Y967586D02*
Y968814D01*
G01X197674Y967661D02*
Y968739D01*
G01X197599Y967736D02*
Y968664D01*
G01X197524Y967811D02*
Y968589D01*
G01X197449Y967886D02*
Y968514D01*
G01X197374Y967961D02*
Y968439D01*
G01X197299Y968036D02*
Y968364D01*
G01X197224Y968111D02*
Y968289D01*
G01X197149Y968186D02*
Y968214D01*
G01X211687Y1372848D02*
Y1372951D01*
G01X211762Y1372773D02*
Y1373026D01*
G01X211837Y1372698D02*
Y1373101D01*
G01X211912Y1372623D02*
Y1373176D01*
G01X211987Y1372548D02*
Y1373251D01*
G01X212062Y1372473D02*
Y1373326D01*
G01X212137Y1372398D02*
Y1373401D01*
G01X212212Y1372323D02*
Y1373476D01*
G01X212287Y1372248D02*
Y1373551D01*
G01X212362Y1372173D02*
Y1373626D01*
G01X212437Y1372098D02*
Y1373701D01*
G01X212512Y1372023D02*
Y1373776D01*
G01X212587Y1371948D02*
Y1373851D01*
G01X212662Y1371873D02*
Y1373926D01*
G01X212746Y1373969D02*
X212729Y1371816D01*
G01X212772Y1371763D02*
X211634Y1372900D01*
G01D02*
X212774Y1374039D01*
G01Y1373980D02*
Y1371820D01*
G01Y1371764D02*
Y1374039D01*
G01X212699Y1371836D02*
Y1373964D01*
G01X212624Y1371911D02*
Y1373889D01*
G01X212549Y1371986D02*
Y1373814D01*
G01X212474Y1372061D02*
Y1373739D01*
G01X212399Y1372136D02*
Y1373664D01*
G01X212324Y1372211D02*
Y1373589D01*
G01X212249Y1372286D02*
Y1373514D01*
G01X212174Y1372361D02*
Y1373439D01*
G01X212099Y1372436D02*
Y1373364D01*
G01X212024Y1372511D02*
Y1373289D01*
G01X211949Y1372586D02*
Y1373214D01*
G01X211874Y1372661D02*
Y1373139D01*
G01X211799Y1372736D02*
Y1373064D01*
G01X211724Y1372811D02*
Y1372989D01*
G01X211649Y1372886D02*
Y1372914D01*
G01X197687Y1778548D02*
Y1778651D01*
G01X197762Y1778473D02*
Y1778726D01*
G01X197837Y1778398D02*
Y1778801D01*
G01X197912Y1778323D02*
Y1778876D01*
G01X197987Y1778248D02*
Y1778951D01*
G01X198062Y1778173D02*
Y1779026D01*
G01X198137Y1778098D02*
Y1779101D01*
G01X198212Y1778023D02*
Y1779176D01*
G01X198287Y1777948D02*
Y1779251D01*
G01X198362Y1777873D02*
Y1779326D01*
G01X198437Y1777798D02*
Y1779401D01*
G01X198512Y1777723D02*
Y1779476D01*
G01X198587Y1777648D02*
Y1779551D01*
G01X198662Y1777573D02*
Y1779626D01*
G01X198746Y1779669D02*
X198729Y1777516D01*
G01X198772Y1777463D02*
X197634Y1778600D01*
G01D02*
X198774Y1779739D01*
G01Y1779680D02*
Y1777520D01*
G01Y1777464D02*
Y1779739D01*
G01X198699Y1777536D02*
Y1779664D01*
G01X198624Y1777611D02*
Y1779589D01*
G01X198549Y1777686D02*
Y1779514D01*
G01X198474Y1777761D02*
Y1779439D01*
G01X198399Y1777836D02*
Y1779364D01*
G01X198324Y1777911D02*
Y1779289D01*
G01X198249Y1777986D02*
Y1779214D01*
G01X198174Y1778061D02*
Y1779139D01*
G01X198099Y1778136D02*
Y1779064D01*
G01X198024Y1778211D02*
Y1778989D01*
G01X197949Y1778286D02*
Y1778914D01*
G01X197874Y1778361D02*
Y1778839D01*
G01X197799Y1778436D02*
Y1778764D01*
G01X197724Y1778511D02*
Y1778689D01*
G01X197649Y1778586D02*
Y1778614D01*
G01X852811Y1366752D02*
Y1366649D01*
G01X852736Y1366827D02*
Y1366574D01*
G01X852661Y1366902D02*
Y1366499D01*
G01X852586Y1366977D02*
Y1366424D01*
G01X852511Y1367052D02*
Y1366349D01*
G01X852436Y1367127D02*
Y1366274D01*
G01X852361Y1367202D02*
Y1366199D01*
G01X852286Y1367277D02*
Y1366124D01*
G01X852211Y1367352D02*
Y1366049D01*
G01X852136Y1367427D02*
Y1365974D01*
G01X852061Y1367502D02*
Y1365899D01*
G01X851986Y1367577D02*
Y1365824D01*
G01X851911Y1367652D02*
Y1365749D01*
G01X851836Y1367727D02*
Y1365674D01*
G01X851752Y1365631D02*
X851769Y1367784D01*
G01X851726Y1367837D02*
X852864Y1366700D01*
G01D02*
X851724Y1365561D01*
G01Y1365620D02*
Y1367780D01*
G01Y1367836D02*
Y1365561D01*
G01X851799Y1367764D02*
Y1365636D01*
G01X851874Y1367689D02*
Y1365711D01*
G01X851949Y1367614D02*
Y1365786D01*
G01X852024Y1367539D02*
Y1365861D01*
G01X852099Y1367464D02*
Y1365936D01*
G01X852174Y1367389D02*
Y1366011D01*
G01X852249Y1367314D02*
Y1366086D01*
G01X852324Y1367239D02*
Y1366161D01*
G01X852399Y1367164D02*
Y1366236D01*
G01X852474Y1367089D02*
Y1366311D01*
G01X852549Y1367014D02*
Y1366386D01*
G01X852624Y1366939D02*
Y1366461D01*
G01X852699Y1366864D02*
Y1366536D01*
G01X852774Y1366789D02*
Y1366611D01*
G01X852849Y1366714D02*
Y1366686D01*
G01X943187Y163748D02*
Y163851D01*
G01X943262Y163673D02*
Y163926D01*
G01X943337Y163598D02*
Y164001D01*
G01X943412Y163523D02*
Y164076D01*
G01X943487Y163448D02*
Y164151D01*
G01X943562Y163373D02*
Y164226D01*
G01X943637Y163298D02*
Y164301D01*
G01X943712Y163223D02*
Y164376D01*
G01X943787Y163148D02*
Y164451D01*
G01X943862Y163073D02*
Y164526D01*
G01X943937Y162998D02*
Y164601D01*
G01X944012Y162923D02*
Y164676D01*
G01X944087Y162848D02*
Y164751D01*
G01X944162Y162773D02*
Y164826D01*
G01X944246Y164869D02*
X944229Y162716D01*
G01X944272Y162663D02*
X943134Y163800D01*
G01D02*
X944274Y164939D01*
G01Y164880D02*
Y162720D01*
G01Y162664D02*
Y164939D01*
G01X944199Y162736D02*
Y164864D01*
G01X944124Y162811D02*
Y164789D01*
G01X944049Y162886D02*
Y164714D01*
G01X943974Y162961D02*
Y164639D01*
G01X943899Y163036D02*
Y164564D01*
G01X943824Y163111D02*
Y164489D01*
G01X943749Y163186D02*
Y164414D01*
G01X943674Y163261D02*
Y164339D01*
G01X943599Y163336D02*
Y164264D01*
G01X943524Y163411D02*
Y164189D01*
G01X943449Y163486D02*
Y164114D01*
G01X943374Y163561D02*
Y164039D01*
G01X943299Y163636D02*
Y163964D01*
G01X943224Y163711D02*
Y163889D01*
G01X943149Y163786D02*
Y163814D01*
G01X925687Y562948D02*
Y563051D01*
G01X925762Y562873D02*
Y563126D01*
G01X925837Y562798D02*
Y563201D01*
G01X925912Y562723D02*
Y563276D01*
G01X925987Y562648D02*
Y563351D01*
G01X926062Y562573D02*
Y563426D01*
G01X926137Y562498D02*
Y563501D01*
G01X926212Y562423D02*
Y563576D01*
G01X926287Y562348D02*
Y563651D01*
G01X926362Y562273D02*
Y563726D01*
G01X926437Y562198D02*
Y563801D01*
G01X926512Y562123D02*
Y563876D01*
G01X926587Y562048D02*
Y563951D01*
G01X926662Y561973D02*
Y564026D01*
G01X926746Y564069D02*
X926729Y561916D01*
G01X926772Y561863D02*
X925634Y563000D01*
G01D02*
X926774Y564139D01*
G01Y564080D02*
Y561920D01*
G01Y561864D02*
Y564139D01*
G01X926699Y561936D02*
Y564064D01*
G01X926624Y562011D02*
Y563989D01*
G01X926549Y562086D02*
Y563914D01*
G01X926474Y562161D02*
Y563839D01*
G01X926399Y562236D02*
Y563764D01*
G01X926324Y562311D02*
Y563689D01*
G01X926249Y562386D02*
Y563614D01*
G01X926174Y562461D02*
Y563539D01*
G01X926099Y562536D02*
Y563464D01*
G01X926024Y562611D02*
Y563389D01*
G01X925949Y562686D02*
Y563314D01*
G01X925874Y562761D02*
Y563239D01*
G01X925799Y562836D02*
Y563164D01*
G01X925724Y562911D02*
Y563089D01*
G01X925649Y562986D02*
Y563014D01*
G01X925687Y967148D02*
Y967251D01*
G01X925762Y967073D02*
Y967326D01*
G01X925837Y966998D02*
Y967401D01*
G01X925912Y966923D02*
Y967476D01*
G01X925987Y966848D02*
Y967551D01*
G01X926062Y966773D02*
Y967626D01*
G01X926137Y966698D02*
Y967701D01*
G01X926212Y966623D02*
Y967776D01*
G01X926287Y966548D02*
Y967851D01*
G01X926362Y966473D02*
Y967926D01*
G01X926437Y966398D02*
Y968001D01*
G01X926512Y966323D02*
Y968076D01*
G01X926587Y966248D02*
Y968151D01*
G01X926662Y966173D02*
Y968226D01*
G01X926746Y968269D02*
X926729Y966116D01*
G01X926772Y966063D02*
X925634Y967200D01*
G01D02*
X926774Y968339D01*
G01Y968280D02*
Y966120D01*
G01Y966064D02*
Y968339D01*
G01X926699Y966136D02*
Y968264D01*
G01X926624Y966211D02*
Y968189D01*
G01X926549Y966286D02*
Y968114D01*
G01X926474Y966361D02*
Y968039D01*
G01X926399Y966436D02*
Y967964D01*
G01X926324Y966511D02*
Y967889D01*
G01X926249Y966586D02*
Y967814D01*
G01X926174Y966661D02*
Y967739D01*
G01X926099Y966736D02*
Y967664D01*
G01X926024Y966811D02*
Y967589D01*
G01X925949Y966886D02*
Y967514D01*
G01X925874Y966961D02*
Y967439D01*
G01X925799Y967036D02*
Y967364D01*
G01X925724Y967111D02*
Y967289D01*
G01X925649Y967186D02*
Y967214D01*
G01X925187Y1777048D02*
Y1777151D01*
G01X925262Y1776973D02*
Y1777226D01*
G01X925337Y1776898D02*
Y1777301D01*
G01X925412Y1776823D02*
Y1777376D01*
G01X925487Y1776748D02*
Y1777451D01*
G01X925562Y1776673D02*
Y1777526D01*
G01X925637Y1776598D02*
Y1777601D01*
G01X925712Y1776523D02*
Y1777676D01*
G01X925787Y1776448D02*
Y1777751D01*
G01X925862Y1776373D02*
Y1777826D01*
G01X925937Y1776298D02*
Y1777901D01*
G01X926012Y1776223D02*
Y1777976D01*
G01X926087Y1776148D02*
Y1778051D01*
G01X926162Y1776073D02*
Y1778126D01*
G01X926246Y1778169D02*
X926229Y1776016D01*
G01X926272Y1775963D02*
X925134Y1777100D01*
G01D02*
X926274Y1778239D01*
G01Y1778180D02*
Y1776020D01*
G01Y1775964D02*
Y1778239D01*
G01X926199Y1776036D02*
Y1778164D01*
G01X926124Y1776111D02*
Y1778089D01*
G01X926049Y1776186D02*
Y1778014D01*
G01X925974Y1776261D02*
Y1777939D01*
G01X925899Y1776336D02*
Y1777864D01*
G01X925824Y1776411D02*
Y1777789D01*
G01X925749Y1776486D02*
Y1777714D01*
G01X925674Y1776561D02*
Y1777639D01*
G01X925599Y1776636D02*
Y1777564D01*
G01X925524Y1776711D02*
Y1777489D01*
G01X925449Y1776786D02*
Y1777414D01*
G01X925374Y1776861D02*
Y1777339D01*
G01X925299Y1776936D02*
Y1777264D01*
G01X925224Y1777011D02*
Y1777189D01*
G01X925149Y1777086D02*
Y1777114D01*
G54D18*
G01X431670Y1187590D02*
X431010D01*
G01X431110Y1187680D02*
X431770D01*
G01X431860Y1187790D02*
X431210D01*
G01X431310Y1187880D02*
X431960D01*
G01X432060Y1187990D02*
X431400D01*
G01X431500Y1188090D02*
X432150D01*
G01X432250Y1188180D02*
X431600D01*
G01X431690Y1188290D02*
X432350D01*
G01X432440Y1188380D02*
X431790D01*
G01X431880Y1188490D02*
X432540D01*
G01X432640Y1188590D02*
X431980D01*
G01X432080Y1188680D02*
X432730D01*
G01X432830Y1188790D02*
X432185D01*
G01X432180D02*
X432230D01*
G01X432270Y1188880D02*
X432310D01*
G01X432270D02*
X432920D01*
G01X433020Y1188990D02*
X432370D01*
G01X432470Y1189090D02*
X433120D01*
G01X433220Y1189180D02*
X432560D01*
G01X432660Y1189290D02*
X433310D01*
G01X433410Y1189380D02*
X432750D01*
G01X432850Y1189490D02*
X433510D01*
G01X433600Y1189590D02*
X432950D01*
G01X433050Y1189680D02*
X433700D01*
G01X433790Y1189790D02*
X433140D01*
G01X433240Y1189880D02*
X433890D01*
G01X433990Y1189990D02*
X433330D01*
G01X433430Y1190090D02*
X434090D01*
G01X434180Y1190180D02*
X433530D01*
G01X433620Y1190290D02*
X434280D01*
G01X434470Y1190490D02*
X433820D01*
G01X434010Y1190680D02*
X434660D01*
G01X429370Y1205100D02*
X429400Y1205120D01*
G01X429370Y1204560D02*
Y1205100D01*
G01X429380Y1204540D02*
X429370Y1204560D01*
G01X429430Y1204430D02*
X429380Y1204540D01*
G01X429440Y1204420D02*
X429430Y1204430D01*
G01X434620Y1198830D02*
X429440Y1204420D01*
G01X429370Y1205090D02*
X429430D01*
G01X429370Y1204990D02*
X429520D01*
G01X429610Y1204880D02*
X429370D01*
G01Y1204790D02*
X429710D01*
G01X429800Y1204680D02*
X429370D01*
G01Y1204590D02*
X429890D01*
G01X429990Y1204490D02*
X429400D01*
G01X429470Y1204380D02*
X430080D01*
G01X430170Y1204290D02*
X429560D01*
G01X429650Y1204180D02*
X430260D01*
G01X430360Y1204090D02*
X429750D01*
G01X429840Y1203990D02*
X430450D01*
G01X430540Y1203880D02*
X429930D01*
G01X430020Y1203790D02*
X430640D01*
G01X430730Y1203680D02*
X430120D01*
G01X430210Y1203590D02*
X430820D01*
G01X430920Y1203490D02*
X430300D01*
G01X430400Y1203380D02*
X431010D01*
G01X431100Y1203290D02*
X430490D01*
G01X430580Y1203180D02*
X431200D01*
G01X431290Y1203090D02*
X430680D01*
G01X430770Y1202990D02*
X431380D01*
G01X431480Y1202880D02*
X430860D01*
G01X430950Y1202790D02*
X431570D01*
G01X431660Y1202680D02*
X431050D01*
G01X431140Y1202590D02*
X431750D01*
G01X431850Y1202490D02*
X431230D01*
G01X431330Y1202380D02*
X431940D01*
G01X432030Y1202290D02*
X431420D01*
G01X431510Y1202180D02*
X432120D01*
G01X432220Y1202090D02*
X431610D01*
G01X431700Y1201990D02*
X432310D01*
G01X432400Y1201880D02*
X431790D01*
G01X431880Y1201790D02*
X432500D01*
G01X432590Y1201680D02*
X431980D01*
G01X432070Y1201590D02*
X432680D01*
G01X432780Y1201490D02*
X432160D01*
G01X432250Y1201380D02*
X432870D01*
G01X432960Y1201290D02*
X432350D01*
G01X432440Y1201180D02*
X433060D01*
G01X433150Y1201090D02*
X432530D01*
G01X432620Y1200990D02*
X433240D01*
G01X433340Y1200880D02*
X432720D01*
G01X432810Y1200790D02*
X433430D01*
G01X433520Y1200680D02*
X432900D01*
G01X432990Y1200590D02*
X433620D01*
G01X433710Y1200490D02*
X433090D01*
G01X433180Y1200380D02*
X433800D01*
G01X433890Y1200290D02*
X433270D01*
G01X433370Y1200180D02*
X433990D01*
G01X434080Y1200090D02*
X433460D01*
G01X433550Y1199990D02*
X434170D01*
G01X434270Y1199880D02*
X433650D01*
G01X433830Y1199680D02*
X435070D01*
G01X435080Y1199490D02*
X434020D01*
G01X433770Y1201780D02*
X434280D01*
G01X433730Y1201740D02*
X433770Y1201780D01*
G01X433730Y1201280D02*
Y1201740D01*
G01X433770Y1201240D02*
X433730Y1201280D01*
G01Y1201680D02*
X443980D01*
G01X443910Y1201490D02*
X433730D01*
G01Y1201290D02*
X443750D01*
G01X436380Y1202590D02*
X434950D01*
G01X434370Y1201850D02*
X434280Y1201780D01*
G01X434390Y1201900D02*
X434370Y1201850D01*
G01X434390Y1201910D02*
Y1201900D01*
G01X434510Y1202160D02*
X434390Y1201910D01*
G01X434530Y1202170D02*
X434510Y1202160D01*
G01X434960Y1202590D02*
X434530Y1202170D01*
G01X434290Y1201790D02*
X435020D01*
G01X435130Y1202120D02*
X435240Y1202190D01*
G01X434960Y1201950D02*
X435130Y1202120D01*
G01X434940Y1201840D02*
X434960Y1201950D01*
G01X435030Y1201780D02*
X434940Y1201840D01*
G01X435100Y1202090D02*
X434480D01*
G01X434430Y1201990D02*
X435000D01*
G01X434950Y1201880D02*
X434380D01*
G01X434640Y1202290D02*
X436320D01*
G01Y1202490D02*
X434850D01*
G01X435200Y1198890D02*
X438430Y1195410D01*
G01X435190Y1198890D02*
X435200D01*
G01X435150Y1198940D02*
X435190Y1198890D01*
G01X435120Y1199000D02*
X435150Y1198940D01*
G01X434940Y1201130D02*
X435120Y1199000D01*
G01X435040Y1201240D02*
X434940Y1201130D01*
G01X435460Y1195090D02*
X434990D01*
G01X434980Y1195290D02*
X435440D01*
G01X435420Y1195490D02*
X434960D01*
G01X434940Y1195680D02*
X435410D01*
G01X435390Y1195880D02*
X434920D01*
G01X434900Y1196090D02*
X435370D01*
G01X435360Y1196290D02*
X434890D01*
G01X434870Y1196490D02*
X435340D01*
G01X435320Y1196680D02*
X434850D01*
G01X434840Y1196880D02*
X435310D01*
G01X435290Y1197090D02*
X434820D01*
G01X434800Y1197290D02*
X435270D01*
G01X435250Y1197490D02*
X434790D01*
G01X434770Y1197680D02*
X435240D01*
G01X435220Y1197880D02*
X434750D01*
G01X434740Y1197990D02*
X435250D01*
G01X435750Y1198290D02*
X434720D01*
G01X434700Y1198490D02*
X435570D01*
G01X434640Y1198800D02*
X434620Y1198830D01*
G01X434680Y1198700D02*
X434640Y1198800D01*
G01X434680Y1198690D02*
Y1198700D01*
G01Y1198680D02*
Y1198690D01*
G01X435380Y1198680D02*
X434680D01*
G01X434580Y1198880D02*
X435200D01*
G01X435130Y1198990D02*
X434480D01*
G01X434390Y1199090D02*
X435120D01*
G01X435110Y1199180D02*
X434300D01*
G01X434200Y1199290D02*
X435100D01*
G01X435090Y1199380D02*
X434110D01*
G01X433920Y1199590D02*
X435070D01*
G01X435060Y1199790D02*
X434580D01*
G01X434370Y1201240D02*
X433770D01*
G01X434470Y1201150D02*
X434370Y1201240D01*
G01X434590Y1199800D02*
X434470Y1201150D01*
G01X434430Y1201180D02*
X434990D01*
G01X434940Y1201090D02*
X434480D01*
G01X434490Y1200990D02*
X434960D01*
G01Y1200880D02*
X434490D01*
G01X434500Y1200790D02*
X434970D01*
G01X434980Y1200680D02*
X434510D01*
G01X434520Y1200590D02*
X434990D01*
G01X435000Y1200490D02*
X434530D01*
G01X434540Y1200380D02*
X435010D01*
G01Y1200290D02*
X434550D01*
G01Y1200180D02*
X435020D01*
G01X435030Y1200090D02*
X434570D01*
G01Y1199990D02*
X435040D01*
G01X435050Y1199880D02*
X434580D01*
G01X434420Y1199730D02*
X429400Y1205120D01*
G01X434530Y1199700D02*
X434420Y1199730D01*
G01X434590Y1199800D02*
X434530Y1199700D01*
G01X433740Y1199790D02*
X434360D01*
G01X434680Y1198680D02*
X435120Y1193530D01*
G01X435130Y1193490D02*
X435600D01*
G01X435610Y1193290D02*
X435140D01*
G01X435160Y1193090D02*
X435630D01*
G01X435650Y1192880D02*
X435180D01*
G01X435200Y1192680D02*
X435670D01*
G01X435710Y1192590D02*
X435210D01*
G01X435220Y1191940D02*
X435120Y1191830D01*
G01X435250Y1192010D02*
X435220Y1191940D01*
G01X435070Y1191790D02*
X435760D01*
G01Y1191590D02*
X434880D01*
G01X434690Y1191380D02*
X435780D01*
G01X435140Y1191180D02*
X434490D01*
G01X434400Y1191090D02*
X435050D01*
G01X434950Y1190990D02*
X434300D01*
G01X434200Y1190880D02*
X434860D01*
G01X434760Y1190790D02*
X434110D01*
G01X433920Y1190590D02*
X434570D01*
G01X434370Y1190380D02*
X433720D01*
G01X435100Y1193790D02*
X435570D01*
G01X435550Y1193990D02*
X435090D01*
G01X435070Y1194180D02*
X435540D01*
G01X435520Y1194380D02*
X435050D01*
G01X435030Y1194590D02*
X435500D01*
G01X435490Y1194790D02*
X435020D01*
G01X435010Y1194880D02*
X435480D01*
G01X435470Y1194990D02*
X435000D01*
G01X434980Y1195180D02*
X435450D01*
G01X435440Y1195380D02*
X434970D01*
G01X434950Y1195590D02*
X435420D01*
G01X435400Y1195790D02*
X434930D01*
G01X434920Y1195990D02*
X435380D01*
G01X435360Y1196180D02*
X434900D01*
G01X434880Y1196380D02*
X435350D01*
G01X435330Y1196590D02*
X434860D01*
G01X434850Y1196790D02*
X435310D01*
G01X435300Y1196990D02*
X434830D01*
G01X434810Y1197180D02*
X435280D01*
G01X435260Y1197380D02*
X434790D01*
G01X434780Y1197590D02*
X435240D01*
G01X435230Y1197790D02*
X434760D01*
G01X435390Y1198010D02*
X438120Y1195070D01*
G01X435270Y1198030D02*
X435390Y1198010D01*
G01X435220Y1197930D02*
X435270Y1198030D01*
G01X435490Y1194680D02*
X435030D01*
G01X435040Y1194490D02*
X435510D01*
G01X435530Y1194290D02*
X435060D01*
G01X435080Y1194090D02*
X435550D01*
G01X435560Y1193880D02*
X435090D01*
G01X435110Y1193680D02*
X435580D01*
G01X435590Y1193590D02*
X435120D01*
G01X435250Y1192070D02*
Y1192010D01*
G01X435120Y1193530D02*
X435250Y1192070D01*
G01X435240Y1191990D02*
X435920D01*
G01X435770Y1191810D02*
X435750Y1191740D01*
G01X435820Y1191890D02*
X435770Y1191810D01*
G01X435750Y1191680D02*
X434980D01*
G01X434790Y1191490D02*
X435770D01*
G01X435790Y1191180D02*
X435290D01*
G01X435260Y1191220D02*
X435160Y1191200D01*
G01X435530Y1188780D02*
X435640D01*
G01X435530Y1188790D02*
Y1188780D01*
G01X435330Y1191140D02*
X435530Y1188790D01*
G01X435260Y1191220D02*
X435330Y1191140D01*
G01X435630Y1188880D02*
X435520D01*
G01X435525D02*
X441120D01*
G01X441185Y1188790D02*
X435530D01*
G01X435770Y1187740D02*
X436660D01*
G01X435730Y1187780D02*
X435770Y1187740D01*
G01X435730Y1188460D02*
Y1187780D01*
G01X435700Y1188530D02*
X435730Y1188460D01*
G01X435550Y1188690D02*
X435700Y1188530D01*
G01X435540Y1188710D02*
X435550Y1188690D01*
G01X435530Y1188770D02*
X435540Y1188710D01*
G01X436700Y1187790D02*
X435730D01*
G01Y1187990D02*
X436700D01*
G01Y1188180D02*
X435730D01*
G01Y1188380D02*
X436700D01*
G01X435980Y1189090D02*
X435510D01*
G01X435490Y1189180D02*
X435960D01*
G01X435950Y1189380D02*
X435480D01*
G01X435460Y1189590D02*
X435930D01*
G01X435910Y1189790D02*
X435440D01*
G01X435430Y1189990D02*
X435900D01*
G01X435880Y1190180D02*
X435410D01*
G01X435390Y1190380D02*
X435860D01*
G01X435850Y1190590D02*
X435380D01*
G01X435360Y1190790D02*
X435830D01*
G01X435810Y1190990D02*
X435350D01*
G01X435240Y1192180D02*
X436110D01*
G01X436300Y1192380D02*
X435220D01*
G01X435190Y1192790D02*
X435660D01*
G01X435670Y1192640D02*
X435220Y1197930D01*
G01X435410Y1197990D02*
X436030D01*
G01X436220Y1197790D02*
X435600D01*
G01X435780Y1197590D02*
X436400D01*
G01X435660Y1198380D02*
X434710D01*
G01X434690Y1198590D02*
X435480D01*
G01X435290Y1198790D02*
X434650D01*
G01X435350Y1202200D02*
X435240Y1202190D01*
G01X435400Y1202110D02*
X435350Y1202200D01*
G01X435400Y1201880D02*
Y1202110D01*
G01X435300Y1201780D02*
X435400Y1201880D01*
G01X435030Y1201780D02*
X435300D01*
G01X435230Y1202180D02*
X434540D01*
G01X435410Y1203170D02*
X435440Y1203190D01*
G01X435400Y1203140D02*
X435410Y1203170D01*
G01X435400Y1202940D02*
Y1203140D01*
G01X435390Y1202900D02*
X435400Y1202940D01*
G01X435370Y1202850D02*
X435390Y1202900D01*
G01X435320Y1202790D02*
X435370Y1202850D01*
G01X435230Y1202750D02*
X435320Y1202790D01*
G01X434960Y1202590D02*
X435230Y1202750D01*
G01X435440Y1203180D02*
X436270D01*
G01X435400Y1202990D02*
X438290D01*
G01X438280Y1202790D02*
X435300D01*
G01X435350Y1202180D02*
X436320D01*
G01Y1201990D02*
X435400D01*
G01X435310Y1201790D02*
X436420D01*
G01X435610Y1193380D02*
X435140D01*
G01X435150Y1193180D02*
X435620D01*
G01X435640Y1192990D02*
X435170D01*
G01X435740Y1192550D02*
X435840Y1192580D01*
G01X435670Y1192640D02*
X435740Y1192550D01*
G01X435650Y1188590D02*
X441430D01*
G01X435970Y1189160D02*
X435750Y1191740D01*
G01X435970Y1189090D02*
Y1189160D01*
G01X436070Y1189000D02*
X435970Y1189090D01*
G01X440170Y1189000D02*
X436070D01*
G01X435820Y1191880D02*
X435170D01*
G01X435250Y1192090D02*
X436010D01*
G01X435830Y1191890D02*
X435820D01*
G01X435830Y1191900D02*
Y1191890D01*
G01Y1191900D02*
X438420Y1194590D01*
G01X438230Y1194380D02*
X437590D01*
G01X437390Y1194180D02*
X438040D01*
G01X437850Y1193990D02*
X437200D01*
G01X437010Y1193790D02*
X437650D01*
G01X437560Y1193680D02*
X436910D01*
G01X436960Y1193740D02*
X435840Y1192580D01*
G01X435850Y1192590D02*
X436490D01*
G01X436400Y1192490D02*
X435220D01*
G01X435230Y1192290D02*
X436210D01*
G01X435950Y1192680D02*
X436590D01*
G01X436690Y1192790D02*
X436050D01*
G01X436140Y1192880D02*
X436790D01*
G01X436880Y1192990D02*
X436240D01*
G01X436330Y1193090D02*
X436980D01*
G01X437070Y1193180D02*
X436430D01*
G01X436530Y1193290D02*
X437170D01*
G01X437270Y1193380D02*
X436620D01*
G01X436720Y1193490D02*
X437360D01*
G01X437460Y1193590D02*
X436810D01*
G01X437640Y1195590D02*
X438270D01*
G01X438080Y1195790D02*
X437460D01*
G01X437270Y1195990D02*
X437890D01*
G01X437710Y1196180D02*
X437080D01*
G01X436990Y1196290D02*
X437610D01*
G01X437520Y1196380D02*
X436900D01*
G01X436810Y1196490D02*
X437430D01*
G01X437330Y1196590D02*
X436710D01*
G01X436620Y1196680D02*
X437240D01*
G01X437150Y1196790D02*
X436530D01*
G01X436430Y1196880D02*
X437060D01*
G01X436960Y1196990D02*
X436340D01*
G01X436250Y1197090D02*
X436870D01*
G01X436780Y1197180D02*
X436150D01*
G01X436060Y1197290D02*
X436680D01*
G01X436590Y1197380D02*
X435970D01*
G01X435880Y1197490D02*
X436500D01*
G01X436310Y1197680D02*
X435690D01*
G01X435500Y1197880D02*
X436120D01*
G01X435940Y1198090D02*
X434740D01*
G01X434730Y1198180D02*
X435850D01*
G01X437700Y1197460D02*
X437740Y1197420D01*
G01X436320Y1201880D02*
X435400D01*
G01X436420Y1201780D02*
X436320Y1201880D01*
G01X435400Y1202090D02*
X436320D01*
G01X437650Y1202790D02*
X437760Y1202680D01*
G01X437380Y1202760D02*
X437650Y1202790D01*
G01X437100Y1202730D02*
X437380Y1202760D01*
G01X436980Y1202720D02*
X437100Y1202730D01*
G01X436880Y1202700D02*
X436980Y1202720D01*
G01X436630Y1202660D02*
X436880Y1202700D01*
G01X436620Y1202660D02*
X436630D01*
G01X436530Y1202640D02*
X436620Y1202660D01*
G01X436520Y1202640D02*
X436530D01*
G01X436400Y1202620D02*
X436520Y1202640D01*
G01X436320Y1202520D02*
X436400Y1202620D01*
G01X436320Y1201880D02*
Y1202520D01*
G01X436260Y1203190D02*
X435440D01*
G01X436280Y1203180D02*
X436260Y1203190D01*
G01X436310Y1203170D02*
X436280Y1203180D01*
G01X436340Y1203150D02*
X436310Y1203170D01*
G01X436420Y1203130D02*
X436340Y1203150D01*
G01X436440Y1203140D02*
X436420Y1203130D01*
G01X436680Y1203180D02*
X436440Y1203140D01*
G01X437180Y1203250D02*
X436680Y1203180D01*
G01X437300Y1203260D02*
X437180Y1203250D01*
G01X437360Y1203260D02*
X437300D01*
G01X437520Y1203280D02*
X437360Y1203260D01*
G01X437660Y1203290D02*
X437520Y1203280D01*
G01X435120Y1202680D02*
X436770D01*
G01X436320Y1202380D02*
X434750D01*
G01X436420Y1201780D02*
X442260D01*
G01X440330Y1203290D02*
X437640D01*
G01X437660D02*
X437760Y1203390D01*
G01X435790Y1191290D02*
X434590D01*
G01X435330Y1191090D02*
X435800D01*
G01X435820Y1190880D02*
X435350D01*
G01X435370Y1190680D02*
X435840D01*
G01X435850Y1190490D02*
X435380D01*
G01X435400Y1190290D02*
X435870D01*
G01X435890Y1190090D02*
X435420D01*
G01X435440Y1189880D02*
X435900D01*
G01X435920Y1189680D02*
X435460D01*
G01X435470Y1189490D02*
X435940D01*
G01X435960Y1189290D02*
X435490D01*
G01X435720Y1188490D02*
X436770D01*
G01X436700Y1187780D02*
X436660Y1187740D01*
G01X436700Y1188420D02*
Y1187780D01*
G01X436800Y1188520D02*
X436700Y1188420D01*
G01Y1187880D02*
X435730D01*
G01Y1188090D02*
X436700D01*
G01Y1188290D02*
X435730D01*
G01X440270Y1189470D02*
Y1189480D01*
G01X440260Y1189400D02*
X440270Y1189470D01*
G01X440260Y1189140D02*
Y1189400D01*
G01X440270Y1189120D02*
X440260Y1189140D01*
G01X440170Y1189000D02*
X440270Y1189120D01*
G01Y1189490D02*
X441040D01*
G01X441000Y1189290D02*
X440260D01*
G01X440240Y1189090D02*
X441040D01*
G01X438880Y1194920D02*
Y1195060D01*
G01X441580Y1192020D02*
X438880Y1194920D01*
G01X438900Y1195090D02*
X438110D01*
G01X438120Y1194930D02*
X436960Y1193740D01*
G01X438120Y1195070D02*
Y1194930D01*
G01X437110Y1193880D02*
X437750D01*
G01X437940Y1194090D02*
X437300D01*
G01X437490Y1194290D02*
X438140D01*
G01X438330Y1194490D02*
X437680D01*
G01X438570Y1194590D02*
X440250Y1192770D01*
G01X438420Y1194590D02*
X438570D01*
G01X437780D02*
X438420D01*
G01X440240Y1192790D02*
X440870D01*
G01X440680Y1192990D02*
X440050D01*
G01X439870Y1193180D02*
X440500D01*
G01X440310Y1193380D02*
X439680D01*
G01X439590Y1193490D02*
X440220D01*
G01X440120Y1193590D02*
X439490D01*
G01X439400Y1193680D02*
X440030D01*
G01X439940Y1193790D02*
X439310D01*
G01X439220Y1193880D02*
X439850D01*
G01X439750Y1193990D02*
X439120D01*
G01X439030Y1194090D02*
X439660D01*
G01X439570Y1194180D02*
X438940D01*
G01X438850Y1194290D02*
X439480D01*
G01X439380Y1194380D02*
X438750D01*
G01X438660Y1194490D02*
X439290D01*
G01X439200Y1194590D02*
X438550D01*
G01X438920Y1194880D02*
X438070D01*
G01X438120Y1194990D02*
X438880D01*
G01X439000Y1195180D02*
X438010D01*
G01X437920Y1195290D02*
X439100D01*
G01X439200Y1195380D02*
X437830D01*
G01X437740Y1195490D02*
X438360D01*
G01X438570Y1195410D02*
X440000Y1196880D01*
G01X438430Y1195410D02*
X438570D01*
G01X439900Y1196790D02*
X440540D01*
G01X440350Y1196590D02*
X439710D01*
G01X439620Y1196490D02*
X440250D01*
G01X440160Y1196380D02*
X439520D01*
G01X439420Y1196290D02*
X440060D01*
G01X439970Y1196180D02*
X439330D01*
G01X439230Y1196090D02*
X439870D01*
G01X439770Y1195990D02*
X439130D01*
G01X439040Y1195880D02*
X439680D01*
G01X439580Y1195790D02*
X438940D01*
G01X438850Y1195680D02*
X439480D01*
G01X439390Y1195590D02*
X438750D01*
G01X438650Y1195490D02*
X439290D01*
G01X439010Y1194790D02*
X437980D01*
G01X437880Y1194680D02*
X439100D01*
G01X438170Y1195680D02*
X437550D01*
G01X437360Y1195880D02*
X437990D01*
G01X437800Y1196090D02*
X437180D01*
G01X437790Y1197420D02*
X440280D01*
G01X437740D02*
X437790D01*
G01X440290Y1197180D02*
X440930D01*
G01X440740Y1196990D02*
X440100D01*
G01X441220Y1197490D02*
X437700D01*
G01X437740Y1198450D02*
X437790D01*
G01X437700Y1198410D02*
X437740Y1198450D01*
G01X437700Y1197460D02*
Y1198410D01*
G01Y1198290D02*
X440960D01*
G01X440990Y1198090D02*
X437700D01*
G01Y1197880D02*
X441610D01*
G01X441410Y1197680D02*
X437700D01*
G01X437760Y1202340D02*
Y1202680D01*
G01X437800Y1202290D02*
X437760Y1202340D01*
G01X437750Y1202680D02*
X440380D01*
G01X440250Y1202290D02*
X437800D01*
G01X440300Y1202340D02*
X440250Y1202290D01*
G01X440300Y1202620D02*
Y1202340D01*
G01X437760Y1202380D02*
X440300D01*
G01Y1202490D02*
X437760D01*
G01Y1202590D02*
X440300D01*
G01X439850Y1202900D02*
Y1202860D01*
G01X439750Y1203000D02*
X439850Y1202900D01*
G01X438310Y1203000D02*
X439750D01*
G01X438210Y1202900D02*
X438310Y1203000D01*
G01X438210Y1202860D02*
Y1202900D01*
G01X438310Y1202750D02*
X438210Y1202860D01*
G01X439750Y1202750D02*
X438310D01*
G01X439850Y1202860D02*
X439750Y1202750D01*
G01X439850Y1202880D02*
X441820D01*
G01X441530Y1202990D02*
X439760D01*
G01X437760Y1203420D02*
Y1203390D01*
G01X437800Y1203460D02*
X437760Y1203420D01*
G01X440250Y1203460D02*
X437800D01*
G01X440300Y1203420D02*
X440250Y1203460D01*
G01X440300Y1203320D02*
Y1203420D01*
G01X437750Y1203380D02*
X440300D01*
G01X438210Y1202880D02*
X435380D01*
G01X435400Y1203090D02*
X441160D01*
G01X440380Y1203220D02*
X440300Y1203320D01*
G01X440430Y1203220D02*
X440380D01*
G01X440990Y1203130D02*
X440430Y1203220D01*
G01X441170Y1203090D02*
X440990Y1203130D01*
G01X440610Y1203180D02*
X436740D01*
G01X440810Y1202650D02*
X441220Y1202560D01*
G01X440520Y1202700D02*
X440810Y1202650D01*
G01X440490Y1202700D02*
X440520D01*
G01X440410Y1202720D02*
X440490Y1202700D01*
G01X440300Y1202620D02*
X440410Y1202720D01*
G01X440600Y1202680D02*
X442190D01*
G01X440910Y1198450D02*
X437790D01*
G01X437700Y1198380D02*
X440960D01*
G01X440950Y1198410D02*
X440910Y1198450D01*
G01X441130Y1198060D02*
X441330Y1198260D01*
G01X441020Y1198030D02*
X441130Y1198060D01*
G01X440960Y1198130D02*
X441020Y1198030D01*
G01X440960Y1198310D02*
Y1198130D01*
G01Y1198320D02*
Y1198310D01*
G01X440950Y1198410D02*
X440960Y1198320D01*
G01X441160Y1198090D02*
X441800D01*
G01X440960Y1198180D02*
X437700D01*
G01X439810Y1196680D02*
X440450D01*
G01X440370Y1197360D02*
X440280Y1197420D01*
G01X440350Y1197250D02*
X440370Y1197360D01*
G01X440000Y1196880D02*
X440350Y1197250D01*
G01X440640Y1196880D02*
X440000D01*
G01X440330Y1197380D02*
X441120D01*
G01X441030Y1197290D02*
X440360D01*
G01X440200Y1197090D02*
X440830D01*
G01X440400Y1193290D02*
X439770D01*
G01X439960Y1193090D02*
X440590D01*
G01X440770Y1192880D02*
X440140D01*
G01X440330Y1192680D02*
X440960D01*
G01X441050Y1192590D02*
X440420D01*
G01X440510Y1192490D02*
X441150D01*
G01X441240Y1192380D02*
X440610D01*
G01X440700Y1192290D02*
X441330D01*
G01X441520Y1192090D02*
X440890D01*
G01X441070Y1191880D02*
X442210D01*
G01X442200Y1191790D02*
X441170D01*
G01X440310Y1189660D02*
X440270Y1189480D01*
G01X440310Y1189670D02*
Y1189660D01*
G01X440420Y1189980D02*
X440310Y1189670D01*
G01X440430Y1189990D02*
X440420Y1189980D01*
G01X440640Y1190300D02*
X440430Y1189990D01*
G01X440650Y1190310D02*
X440640Y1190300D01*
G01X440890Y1190530D02*
X440650Y1190310D01*
G01X440900Y1190530D02*
X440890D01*
G01X441020Y1190610D02*
X440900Y1190530D01*
G01X441030Y1190620D02*
X441020Y1190610D01*
G01X441090Y1190650D02*
X441030Y1190620D01*
G01X441250Y1190720D02*
X441090Y1190650D01*
G01X440260Y1189380D02*
X441020D01*
G01X441060Y1188990D02*
X435510D01*
G01X441050Y1189010D02*
X441060Y1188990D01*
G01X441000Y1189270D02*
X441050Y1189010D01*
G01X441000Y1189280D02*
Y1189270D01*
G01Y1189300D02*
Y1189280D01*
G01X435550Y1188680D02*
X441290D01*
G01X441210Y1188750D02*
X441150Y1188840D01*
G01X441220Y1188740D02*
X441210Y1188750D01*
G01X441230Y1188730D02*
X441220Y1188740D01*
G01X441070Y1188980D02*
X441060Y1188990D01*
G01X441150Y1188850D02*
X441070Y1188980D01*
G01X441020Y1189180D02*
X440260D01*
G01X440290Y1189590D02*
X441060D01*
G01X441050Y1189560D02*
X441000Y1189300D01*
G01X441060Y1189580D02*
X441050Y1189560D01*
G01X441280Y1189310D02*
X441290Y1189330D01*
G01X441230Y1189840D02*
X441450Y1190000D01*
G01X441220Y1189830D02*
X441230Y1189840D01*
G01X441210Y1189810D02*
X441220Y1189830D01*
G01X441070Y1189600D02*
X441210Y1189810D01*
G01X441060Y1189580D02*
X441070Y1189600D01*
G01X441290Y1189880D02*
X440390D01*
G01X440350Y1189790D02*
X441190D01*
G01X441120Y1189680D02*
X440310D01*
G01X440490Y1190090D02*
X441750D01*
G01X441160Y1190680D02*
X442830D01*
G01X442920Y1190590D02*
X440980D01*
G01X440740Y1190380D02*
X443110D01*
G01X443290Y1190180D02*
X440570D01*
G01X441150Y1188790D02*
X441190D01*
G01X441230Y1188730D02*
X441450Y1188570D01*
G01X441020Y1187990D02*
X442570D01*
G01X442730Y1188090D02*
X440840D01*
G01X440400Y1188520D02*
X436800D01*
G01X440480Y1188490D02*
X440400Y1188520D01*
G01X440490Y1188480D02*
X440480Y1188490D01*
G01X440490Y1188470D02*
Y1188480D01*
G01X440530Y1188400D02*
X440490Y1188470D01*
G01X440540Y1188400D02*
X440530D01*
G01X440550Y1188390D02*
X440540Y1188400D01*
G01X440620Y1188290D02*
X440550Y1188390D01*
G01X440630Y1188280D02*
X440620Y1188290D01*
G01X440860Y1188060D02*
X440630Y1188280D01*
G01Y1188290D02*
X442970D01*
G01X440880Y1188050D02*
X440860Y1188060D01*
G01X441680Y1187750D02*
X442020Y1187760D01*
G01X441670Y1187750D02*
X441680D01*
G01X441660D02*
X441670D01*
G01X441500Y1187770D02*
X441660Y1187750D01*
G01X441480Y1187770D02*
X441500D01*
G01X440880Y1188050D02*
X441480Y1187770D01*
G01X442130Y1187790D02*
X441460D01*
G01Y1188560D02*
X441450Y1188570D01*
G01X441480Y1188560D02*
X441460D01*
G01X441650Y1188500D02*
X441480Y1188560D01*
G01X441870Y1188490D02*
X441890D01*
G01X441740D02*
X441870D01*
G01X441670Y1188500D02*
X441740Y1188490D01*
G01X441650Y1188500D02*
X441670D01*
G01X441310Y1189120D02*
X441280Y1189310D01*
G01X441320Y1189090D02*
X441310Y1189120D01*
G01X441490Y1188870D02*
X441320Y1189090D01*
G01X441510Y1188860D02*
X441490Y1188870D01*
G01X441680Y1188780D02*
X441510Y1188860D01*
G01X441690Y1188780D02*
X441680D01*
G01X441730Y1188770D02*
X441690Y1188780D01*
G01X441790Y1188770D02*
X441730D01*
G01X441810D02*
X441790D01*
G01X441840Y1189800D02*
X441850D01*
G01X441750D02*
X441840D01*
G01X441730Y1189790D02*
X441750Y1189800D01*
G01X441420Y1189630D02*
X441730Y1189790D01*
G01X441400Y1189610D02*
X441420Y1189630D01*
G01X441290Y1189330D02*
X441400Y1189610D01*
G01X441460Y1190010D02*
X441450Y1190000D01*
G01X441480Y1190010D02*
X441460D01*
G01X441650Y1190070D02*
X441480Y1190010D01*
G01X441670Y1190070D02*
X441650D01*
G01X441740Y1190080D02*
X441670Y1190070D01*
G01X441760Y1190090D02*
X441740Y1190080D01*
G01X441820Y1190090D02*
X441760D01*
G01X441850Y1190080D02*
X441820Y1190090D01*
G01X441430Y1189990D02*
X440430D01*
G01X441340Y1189470D02*
X442280D01*
G01X442300Y1189270D02*
X441290D01*
G01X441340Y1189070D02*
X442250D01*
G01X442070Y1188870D02*
X441500D01*
G01X441810Y1188770D02*
X441940Y1188790D01*
G01X442140Y1189660D02*
X441490D01*
G01X441890Y1190080D02*
X442090Y1190030D01*
G01X441850Y1190080D02*
X441890D01*
G01X441340Y1190750D02*
X441250Y1190720D01*
G01X441350Y1190760D02*
X441340Y1190750D01*
G01X441490Y1190790D02*
X441350Y1190760D01*
G01X441570Y1190810D02*
X441490Y1190790D01*
G01X441350Y1191590D02*
X440250Y1192770D01*
G01X441610Y1191310D02*
X441350Y1191590D01*
G01X441640Y1191260D02*
X441610Y1191310D01*
G01X441670Y1191110D02*
X441640Y1191260D01*
G01X441680Y1191090D02*
X441670Y1191110D01*
G01X441680Y1191070D02*
Y1191090D01*
G01X441660Y1190900D02*
X441680Y1191070D01*
G01X441660Y1190890D02*
Y1190900D01*
G01X441570Y1190810D02*
X441660Y1190890D01*
G01X440790Y1192180D02*
X441430D01*
G01X441750Y1192080D02*
X442260Y1198310D01*
G01X441690Y1192000D02*
X441750Y1192080D01*
G01X441580Y1192020D02*
X441690Y1192000D01*
G01X441350Y1198290D02*
X441330Y1198260D01*
G01X441990Y1198290D02*
X441350D01*
G01D02*
X442160Y1199130D01*
G01X441740Y1198680D02*
X444000D01*
G01Y1198490D02*
X441550D01*
G01X441250Y1198180D02*
X441890D01*
G01X441700Y1197990D02*
X437700D01*
G01Y1197790D02*
X441510D01*
G01X441310Y1197590D02*
X437700D01*
G01X441920Y1194090D02*
X442380D01*
G01X442370Y1193880D02*
X441900D01*
G01X441880Y1193680D02*
X442350D01*
G01X442340Y1193490D02*
X441870D01*
G01X441850Y1193290D02*
X442320D01*
G01X442310Y1193090D02*
X441840D01*
G01X441820Y1192880D02*
X442290D01*
G01X442270Y1192680D02*
X441810D01*
G01X441790Y1192490D02*
X442250D01*
G01X442240Y1192290D02*
X441770D01*
G01X441750Y1192090D02*
X442220D01*
G01X442180Y1191590D02*
X441350D01*
G01X441540Y1191380D02*
X442180D01*
G01X442360Y1191180D02*
X441660D01*
G01X441670Y1190990D02*
X442550D01*
G01X441500Y1202480D02*
X441220Y1202560D01*
G01X441510Y1202470D02*
X441500Y1202480D01*
G01X441620Y1202440D02*
X441510Y1202470D01*
G01X441620Y1202430D02*
Y1202440D01*
G01X441730Y1202390D02*
X441620Y1202430D01*
G01X441740Y1202380D02*
X441730Y1202390D01*
G01X442600Y1202380D02*
X441740D01*
G01X441460Y1202490D02*
X442490D01*
G01X441290Y1203050D02*
X441170Y1203090D01*
G01X441400Y1203030D02*
X441290Y1203050D01*
G01X441640Y1202950D02*
X441400Y1203030D01*
G01X441750Y1202910D02*
X441640Y1202950D01*
G01X441810Y1202890D02*
X441750Y1202910D01*
G01X441100Y1202590D02*
X442350D01*
G01X442030Y1202790D02*
X439780D01*
G01X442350Y1201830D02*
X442260Y1201780D01*
G01X442340Y1201930D02*
X442350Y1201830D01*
G01X442270Y1202040D02*
X442340Y1201930D01*
G01X442250Y1202060D02*
X442270Y1202040D01*
G01X441950Y1202280D02*
X442250Y1202060D01*
G01X441940Y1202290D02*
X441950Y1202280D01*
G01X441930Y1202290D02*
X441940D01*
G01X441740Y1202380D02*
X441930Y1202290D01*
G01X442270Y1201790D02*
X443990D01*
G01X443970Y1201990D02*
X442310D01*
G01X442080Y1202180D02*
X443890D01*
G01X444000Y1200180D02*
X442220D01*
G01X442190Y1199160D02*
X442160Y1199130D01*
G01X442220Y1199220D02*
X442190Y1199160D01*
G01X442220Y1200240D02*
Y1199220D01*
G01X442120Y1199090D02*
X442790D01*
G01X442960Y1199290D02*
X442220D01*
G01Y1199490D02*
X443150D01*
G01X443340Y1199680D02*
X442220D01*
G01Y1199790D02*
X444000D01*
G01Y1199990D02*
X442220D01*
G01X442330Y1200320D02*
X442430Y1200420D01*
G01X442260Y1200320D02*
X442330D01*
G01X442220Y1200280D02*
X442260Y1200320D01*
G01X442220Y1200240D02*
Y1200280D01*
G01X441930Y1198880D02*
X444000D01*
G01X442720Y1198180D02*
X442250D01*
G01X442090Y1198390D02*
X438880Y1195060D01*
G01X442200Y1198410D02*
X442090Y1198390D01*
G01X442260Y1198310D02*
X442200Y1198410D01*
G01X441980Y1194880D02*
X442450D01*
G01X442460Y1194990D02*
X441990D01*
G01X442010Y1195180D02*
X442480D01*
G01X442490Y1195380D02*
X442030D01*
G01X442040Y1195590D02*
X442510D01*
G01X442520Y1195790D02*
X442060D01*
G01X442070Y1195990D02*
X442540D01*
G01X442560Y1196180D02*
X442090D01*
G01X442110Y1196380D02*
X442570D01*
G01X442590Y1196590D02*
X442120D01*
G01X442140Y1196790D02*
X442610D01*
G01X442620Y1196990D02*
X442160D01*
G01X442170Y1197180D02*
X442640D01*
G01X442650Y1197380D02*
X442190D01*
G01X442200Y1197590D02*
X442670D01*
G01X442690Y1197790D02*
X442220D01*
G01X442240Y1197990D02*
X442700D01*
G01X442090Y1198380D02*
X441450D01*
G01X441970Y1194680D02*
X442440D01*
G01X442420Y1194490D02*
X441950D01*
G01X441940Y1194290D02*
X442400D01*
G01X442390Y1194180D02*
X441930D01*
G01X441910Y1193990D02*
X442380D01*
G01X442360Y1193790D02*
X441890D01*
G01X441880Y1193590D02*
X442350D01*
G01X442330Y1193380D02*
X441860D01*
G01X441850Y1193180D02*
X442310D01*
G01X442300Y1192990D02*
X441830D01*
G01X441810Y1192790D02*
X442280D01*
G01X442260Y1192590D02*
X441800D01*
G01X441780Y1192380D02*
X442250D01*
G01X442230Y1192180D02*
X441760D01*
G01X442220Y1191990D02*
X440980D01*
G01X441260Y1191680D02*
X442190D01*
G01X442180Y1191490D02*
X441450D01*
G01X441620Y1191290D02*
X442260D01*
G01X442200Y1191350D02*
X443160Y1190330D01*
G01X443480Y1189990D02*
X442150D01*
G01X442130Y1190010D02*
X442090Y1190030D01*
G01X442130Y1190010D02*
X442440Y1189750D01*
G01X442210Y1189570D02*
X441380D01*
G01X441300Y1189370D02*
X442290D01*
G01X442100Y1189700D02*
X441850Y1189800D01*
G01X442120Y1189690D02*
X442100Y1189700D01*
G01X442270Y1189490D02*
X442120Y1189690D01*
G01X442280Y1189460D02*
X442270Y1189490D01*
G01X441940Y1189770D02*
X441670D01*
G01X441960Y1188790D02*
X441940D01*
G01X442180Y1188930D02*
X441960Y1188790D01*
G01X442190Y1188950D02*
X442180Y1188930D01*
G01X442300Y1189180D02*
X442190Y1188950D01*
G01X442310Y1189200D02*
X442300Y1189180D01*
G01X442280Y1189460D02*
X442310Y1189200D01*
G01X442150Y1188590D02*
X443170D01*
G01X442030Y1187760D02*
X442020D01*
G01X442320Y1187830D02*
X442030Y1187760D01*
G01X442330Y1187840D02*
X442320Y1187830D01*
G01X442840Y1188150D02*
X442330Y1187840D01*
G01X442090Y1188540D02*
X442130Y1188560D01*
G01X441890Y1188490D02*
X442090Y1188540D01*
G01X442200Y1188970D02*
X441420D01*
G01X441300Y1189160D02*
X442300D01*
G01X442190Y1191370D02*
X442170Y1191440D01*
G01X442200Y1191360D02*
X442190Y1191370D01*
G01X442200Y1191350D02*
Y1191360D01*
G01X441960Y1202830D02*
X441810Y1202890D01*
G01X441970Y1202820D02*
X441960Y1202830D01*
G01X443220Y1202540D02*
X443280Y1202550D01*
G01X443210Y1202540D02*
X443220D01*
G01X443100Y1202510D02*
X443210Y1202540D01*
G01X443090Y1202510D02*
X443100D01*
G01X442960Y1202460D02*
X443090Y1202510D01*
G01X442960Y1202450D02*
Y1202460D01*
G01X442900Y1202420D02*
X442960Y1202450D01*
G01X442880Y1202400D02*
X442900Y1202420D01*
G01X442820Y1202350D02*
X442880Y1202400D01*
G01X442800Y1202330D02*
X442820Y1202350D01*
G01X442660Y1202330D02*
X442800D01*
G01X442480Y1202500D02*
X442660Y1202330D01*
G01X442470Y1202510D02*
X442480Y1202500D01*
G01X441970Y1202820D02*
X442470Y1202510D01*
G01X443030Y1202490D02*
X443550D01*
G01X443600Y1201180D02*
X442440D01*
G01X442490Y1201130D02*
X442430Y1200420D01*
G01X442400Y1200380D02*
X442950D01*
G01X443240Y1201110D02*
X443270Y1201100D01*
G01X443160Y1201120D02*
X443240Y1201110D01*
G01X443090Y1201140D02*
X443160Y1201120D01*
G01X443080Y1201140D02*
X443090D01*
G01X442950Y1201050D02*
X443080Y1201140D01*
G01X442900Y1200440D02*
X442950Y1201050D01*
G01X443000Y1200330D02*
X442900Y1200440D01*
G01X443000Y1201090D02*
X442490D01*
G01X442390Y1201240D02*
X435040D01*
G01X442490Y1201130D02*
X442390Y1201240D01*
G01X442030Y1198990D02*
X442850D01*
G01X442820Y1199140D02*
X443370Y1199720D01*
G01X442790Y1199090D02*
X442820Y1199140D01*
G01X442790Y1199050D02*
Y1199090D01*
G01X442890Y1198940D02*
X442790Y1199050D01*
G01X443250Y1199590D02*
X442220D01*
G01Y1199380D02*
X443050D01*
G01X442860Y1199180D02*
X442200D01*
G01X442220Y1198380D02*
X442750D01*
G01X442740Y1198370D02*
X442170Y1191440D01*
G01X442450Y1191090D02*
X441680D01*
G01X441650Y1190880D02*
X442640D01*
G01X442730Y1190790D02*
X441460D01*
G01X440850Y1190490D02*
X443010D01*
G01X443200Y1190290D02*
X440630D01*
G01X440480Y1188490D02*
X443110D01*
G01X442930Y1188240D02*
X442840Y1188150D01*
G01X442990Y1188310D02*
X442930Y1188240D01*
G01X443120Y1188500D02*
X442990Y1188310D01*
G01X442880Y1188180D02*
X440730D01*
G01X440550Y1188380D02*
X443040D01*
G01X443240Y1188750D02*
X443300Y1188920D01*
G01X443200Y1188650D02*
X443240Y1188750D01*
G01X443200Y1188640D02*
Y1188650D01*
G01X443130Y1188510D02*
X443200Y1188640D01*
G01X443120Y1188500D02*
X443130Y1188510D01*
G01X443290Y1188880D02*
X442475D01*
G01X442480D02*
X442540D01*
G01X442440Y1188820D02*
X442130Y1188560D01*
G01X442470Y1188870D02*
X442440Y1188820D01*
G01X442270Y1188680D02*
X443220D01*
G01X443250Y1188790D02*
X442460D01*
G01X443220D02*
X443250D01*
G01X442470Y1189700D02*
X442440Y1189750D01*
G01X442590Y1189310D02*
X442470Y1189700D01*
G01X442590Y1189250D02*
Y1189310D01*
G01X442470Y1188870D02*
X442590Y1189250D01*
G01X442400Y1189790D02*
X443660D01*
G01X443850Y1189590D02*
X442510D01*
G01X442570Y1189380D02*
X444030D01*
G01X443330Y1189180D02*
X442570D01*
G01X442510Y1188990D02*
X443310D01*
G01X442400Y1187880D02*
X441240D01*
G01X441940Y1194380D02*
X442410D01*
G01X442430Y1194590D02*
X441960D01*
G01X441980Y1194790D02*
X442440D01*
G01X442470Y1195090D02*
X442000D01*
G01X442010Y1195290D02*
X442480D01*
G01X442500Y1195490D02*
X442030D01*
G01X442050Y1195680D02*
X442510D01*
G01X442530Y1195880D02*
X442070D01*
G01X442080Y1196090D02*
X442550D01*
G01X442570Y1196290D02*
X442100D01*
G01X442110Y1196490D02*
X442580D01*
G01X442600Y1196680D02*
X442130D01*
G01X442150Y1196880D02*
X442610D01*
G01X442630Y1197090D02*
X442160D01*
G01X442180Y1197290D02*
X442640D01*
G01X442660Y1197490D02*
X442200D01*
G01X442210Y1197680D02*
X442680D01*
G01X442700Y1197880D02*
X442230D01*
G01X442240Y1198090D02*
X442710D01*
G01X442730Y1198290D02*
X442260D01*
G01X442740Y1198370D02*
X442830Y1198460D01*
G01X443160Y1200320D02*
X443280D01*
G01X443000Y1200330D02*
X443160Y1200320D01*
G01X442910Y1200490D02*
X442440D01*
G01X442450Y1200590D02*
X442920D01*
G01Y1200680D02*
X442460D01*
G01Y1200790D02*
X442930D01*
G01X442940Y1200880D02*
X442470D01*
G01X442480Y1200990D02*
X442950D01*
G01X443350Y1202550D02*
X443280D01*
G01X443360Y1202540D02*
X443350Y1202550D01*
G01X443620Y1202470D02*
X443360Y1202540D01*
G01X443630Y1202460D02*
X443620Y1202470D01*
G01X443830Y1202290D02*
X443630Y1202460D01*
G01X443840Y1202280D02*
X443830Y1202290D01*
G01X443960Y1202050D02*
X443840Y1202280D01*
G01X443970Y1202030D02*
X443960Y1202050D01*
G01X443990Y1201750D02*
X443970Y1202030D01*
G01X443990Y1201740D02*
Y1201750D01*
G01X443910Y1201480D02*
X443990Y1201740D01*
G01X443900Y1201470D02*
X443910Y1201480D01*
G01X443740Y1201270D02*
X443900Y1201470D01*
G01X443730Y1201250D02*
X443740Y1201270D01*
G01X443500Y1201130D02*
X443730Y1201250D01*
G01X443480Y1201130D02*
X443500D01*
G01X443360Y1201110D02*
X443480Y1201130D01*
G01X443350Y1201110D02*
X443360D01*
G01X443290Y1201100D02*
X443350Y1201110D01*
G01X443270Y1201100D02*
X443290D01*
G01X442860Y1202380D02*
X443720D01*
G01X443830Y1202290D02*
X441940D01*
G01X442220Y1202090D02*
X443940D01*
G01X443980Y1201880D02*
X442350D01*
G01X443840Y1201380D02*
X433730D01*
G01Y1201590D02*
X443940D01*
G01X444250Y1201290D02*
X444880D01*
G01X444980Y1201380D02*
X444350D01*
G01X444440Y1201490D02*
X445080D01*
G01X445170Y1201590D02*
X444540D01*
G01X444640Y1201680D02*
X445270D01*
G01X445360Y1201790D02*
X444740D01*
G01X444830Y1201880D02*
X445460D01*
G01X445560Y1201990D02*
X444930D01*
G01X445030Y1202090D02*
X445660D01*
G01X445850Y1202290D02*
X445220D01*
G01X445410Y1202490D02*
X446040D01*
G01X444790Y1201180D02*
X444160D01*
G01X444060Y1201090D02*
X444690D01*
G01X444590Y1200990D02*
X443960D01*
G01X443860Y1200880D02*
X444500D01*
G01X444400Y1200790D02*
X443770D01*
G01X443670Y1200680D02*
X444310D01*
G01X444210Y1200590D02*
X443580D01*
G01X443480Y1200490D02*
X444110D01*
G01X443960Y1198460D02*
X442830D01*
G01X444000Y1198480D02*
X443960Y1198460D01*
G01X444000Y1198490D02*
Y1198480D01*
G01Y1200310D02*
Y1198490D01*
G01Y1200320D02*
Y1200310D01*
G01X444030Y1200400D02*
X444000Y1200320D01*
G01X443480Y1199740D02*
X443370Y1199720D01*
G01X443540Y1199640D02*
X443480Y1199740D01*
G01X443540Y1199040D02*
Y1199640D01*
G01X443440Y1198940D02*
X443540Y1199040D01*
G01X442890Y1198940D02*
X443440D01*
G01X443510Y1199680D02*
X444000D01*
G01Y1199590D02*
X443540D01*
G01Y1199490D02*
X444000D01*
G01Y1199380D02*
X443540D01*
G01Y1199290D02*
X444000D01*
G01Y1199180D02*
X443540D01*
G01Y1199090D02*
X444000D01*
G01Y1198990D02*
X443490D01*
G01X444000Y1198790D02*
X441830D01*
G01X441640Y1198590D02*
X444000D01*
G01Y1199880D02*
X442220D01*
G01Y1200090D02*
X444000D01*
G01Y1200290D02*
X442220D01*
G01X443280Y1200320D02*
X443350Y1200350D01*
G01X443380Y1200380D02*
X444020D01*
G01X443380Y1190090D02*
X441830D01*
G01X442270Y1189880D02*
X443570D01*
G01X443750Y1189680D02*
X442480D01*
G01X442530Y1189490D02*
X443940D01*
G01X444130Y1189290D02*
X443440D01*
G01X443300Y1188940D02*
Y1188920D01*
G01X443340Y1189210D02*
X443300Y1188940D01*
G01X443400Y1189290D02*
X443340Y1189210D01*
G01X443320Y1189090D02*
X442540D01*
G01X443400Y1189290D02*
X443510Y1189270D01*
G01X442590Y1189290D02*
X443400D01*
G01X443590Y1189180D02*
X444220D01*
G01X444310Y1189090D02*
X443680D01*
G01X443770Y1188990D02*
X444410D01*
G01X444460Y1188880D02*
X444500D01*
G01X444510D02*
X443870D01*
G01X443960Y1188790D02*
X444595D01*
G01X444590D02*
X444540D01*
G01X444695Y1188680D02*
X444050D01*
G01X444140Y1188590D02*
X444780D01*
G01X444870Y1188490D02*
X444235D01*
G01X444335Y1188380D02*
X444970D01*
G01X445060Y1188290D02*
X444420D01*
G01X444525Y1188180D02*
X445150D01*
G01X445250Y1188090D02*
X444610D01*
G01X444700Y1187990D02*
X445340D01*
G01X445430Y1187880D02*
X444790D01*
G01X444880Y1187790D02*
X445530D01*
G01X445710Y1187590D02*
X445070D01*
G01X444980Y1187680D02*
X445620D01*
G01X445800Y1187490D02*
X445160D01*
G01X445260Y1187380D02*
X445900D01*
G01X445990Y1187290D02*
X445350D01*
G01X445440Y1187180D02*
X446080D01*
G01X446180Y1187090D02*
X445530D01*
G01X445630Y1186990D02*
X446270D01*
G01X446360Y1186880D02*
X445720D01*
G01X445810Y1186790D02*
X446460D01*
G01X446550Y1186680D02*
X445910D01*
G01X446000Y1186590D02*
X446640D01*
G01X446830Y1186380D02*
X446190D01*
G01X446370Y1186180D02*
X446980D01*
G01X446970Y1186240D02*
X443160Y1190330D01*
G01X446640Y1185900D02*
X446660Y1185880D01*
G01X443510Y1189270D02*
X446640Y1185900D01*
G01X446560Y1185990D02*
X446780D01*
G01X429700Y1186220D02*
X435120Y1191830D01*
G01X429670Y1186190D02*
X429700Y1186220D01*
G01X429680Y1186170D02*
X429670Y1186190D01*
G01X429990Y1185900D02*
X429680Y1186170D01*
G01X430020Y1185890D02*
X429990Y1185900D01*
G01X430040D02*
X430020Y1185890D01*
G01X435160Y1191200D02*
X430040Y1185900D01*
G01X430120Y1185990D02*
X429890D01*
G01X429770Y1186090D02*
X430220D01*
G01X430320Y1186180D02*
X429670D01*
G01X429760Y1186290D02*
X430420D01*
G01X430510Y1186380D02*
X429860D01*
G01X429950Y1186490D02*
X430610D01*
G01X430700Y1186590D02*
X430050D01*
G01X430140Y1186680D02*
X430800D01*
G01X430900Y1186790D02*
X430240D01*
G01X430340Y1186880D02*
X430990D01*
G01X431090Y1186990D02*
X430440D01*
G01X430530Y1187090D02*
X431190D01*
G01X431280Y1187180D02*
X430630D01*
G01X430730Y1187290D02*
X431380D01*
G01X431480Y1187380D02*
X430820D01*
G01X430920Y1187490D02*
X431570D01*
G01X443350Y1200350D02*
X447930Y1205090D01*
G01X447960Y1204480D02*
X444030Y1200400D01*
G01X445120Y1202180D02*
X445750D01*
G01X445940Y1202380D02*
X445310D01*
G01X445510Y1202590D02*
X446140D01*
G01X446240Y1202680D02*
X445610D01*
G01X445700Y1202790D02*
X446330D01*
G01X446430Y1202880D02*
X445800D01*
G01X445900Y1202990D02*
X446520D01*
G01X446620Y1203090D02*
X445990D01*
G01X446180Y1203290D02*
X446810D01*
G01X447010Y1203490D02*
X446380D01*
G01X446570Y1203680D02*
X447200D01*
G01X447100Y1203590D02*
X446480D01*
G01X446670Y1203790D02*
X447290D01*
G01X447390Y1203880D02*
X446760D01*
G01X446860Y1203990D02*
X447490D01*
G01X447590Y1204090D02*
X446960D01*
G01X447050Y1204180D02*
X447680D01*
G01X447780Y1204290D02*
X447150D01*
G01X447250Y1204380D02*
X447870D01*
G01X447980Y1204590D02*
X447440D01*
G01X447970Y1204510D02*
X447980Y1204590D01*
G01X447960Y1204480D02*
X447970Y1204510D01*
G01X447350Y1204490D02*
X447960D01*
G01X447980Y1205080D02*
X447930Y1205090D01*
G01X447980Y1204590D02*
Y1205080D01*
G01X447920Y1205090D02*
X447960D01*
G01X447980Y1204990D02*
X447830D01*
G01X447730Y1204880D02*
X447980D01*
G01Y1204790D02*
X447630D01*
G01X447540Y1204680D02*
X447980D01*
G01X446910Y1203380D02*
X446280D01*
G01X446090Y1203180D02*
X446720D01*
G01X446740Y1186490D02*
X446090D01*
G01X446280Y1186290D02*
X446920D01*
G01X446690Y1185900D02*
X446660Y1185880D01*
G01X446980Y1186190D02*
X446690Y1185900D01*
G01X446990Y1186210D02*
X446980Y1186190D01*
G01Y1186220D02*
X446990Y1186210D01*
G01X446970Y1186240D02*
X446980Y1186220D01*
G01X446460Y1186090D02*
X446880D01*
G54D19*
G01X-89222Y-207897D02*
Y-190397D01*
G01X-80052D02*
Y-207897D01*
G01Y-199147D02*
X-89222D01*
G01X-67137Y-207897D02*
X-68447Y-207605D01*
X-69757Y-206439D01*
X-70631Y-204397D01*
X-71067Y-202064D01*
X-70631Y-199730D01*
X-69757Y-197689D01*
X-68447Y-196522D01*
X-67137Y-196231D01*
X-65827Y-196522D01*
X-64517Y-197689D01*
X-63644Y-199730D01*
X-63425Y-202064D01*
X-63644Y-204397D01*
X-64517Y-206439D01*
X-65827Y-207605D01*
X-67137Y-207897D01*
G01X-53349D02*
Y-196231D01*
G01Y-199147D02*
X-52475Y-197689D01*
X-51165Y-196522D01*
X-49419Y-196231D01*
X-47891Y-196522D01*
X-46580Y-197689D01*
X-45925Y-199730D01*
Y-207897D01*
G01X-35412Y-200022D02*
X-28425D01*
X-29080Y-197980D01*
X-30172Y-196814D01*
X-31700Y-196231D01*
X-33229Y-196522D01*
X-34539Y-197397D01*
X-35412Y-199439D01*
X-35849Y-201189D01*
Y-202939D01*
X-35412Y-204689D01*
X-34320Y-206439D01*
X-33010Y-207605D01*
X-31482Y-207897D01*
X-29954Y-207314D01*
X-28425Y-205564D01*
G01X-19222Y-213147D02*
X-17912Y-213730D01*
X-16165Y-213147D01*
X-15074Y-211981D01*
X-14200Y-210522D01*
X-12891Y-205856D01*
X-10052Y-196231D01*
G01X-17039D02*
X-12891Y-205856D01*
G01X22109Y-198564D02*
X22983Y-197689D01*
X23638Y-196231D01*
X24075Y-194188D01*
X23638Y-192439D01*
X22765Y-191272D01*
X21236Y-190397D01*
X15341D01*
Y-207897D01*
X22546D01*
X24075Y-206731D01*
X24948Y-204980D01*
X25385Y-202939D01*
X24948Y-200897D01*
X23638Y-199147D01*
X22109Y-198564D01*
X15341D01*
G01X41793Y-207897D02*
Y-196231D01*
G01Y-198272D02*
X40920Y-197106D01*
X39609Y-196522D01*
X38081Y-196231D01*
X36553Y-196814D01*
X35243Y-197980D01*
X34369Y-199730D01*
X33933Y-202064D01*
X34369Y-204397D01*
X35243Y-206147D01*
X36553Y-207314D01*
X38081Y-207897D01*
X39609Y-207605D01*
X40920Y-206731D01*
X41793Y-205564D01*
G01X59293Y-190397D02*
Y-207897D01*
G01Y-205273D02*
X58420Y-206731D01*
X57109Y-207605D01*
X55581Y-207897D01*
X53835Y-207314D01*
X52525Y-205856D01*
X51651Y-204106D01*
X51433Y-202064D01*
X51651Y-200022D01*
X52525Y-198272D01*
X53835Y-196814D01*
X55581Y-196231D01*
X57109Y-196522D01*
X58201Y-197106D01*
X59293Y-198272D01*
G01X69806Y-212272D02*
X71335Y-213439D01*
X73081Y-213730D01*
X74609Y-213439D01*
X75920Y-211981D01*
X76793Y-209939D01*
Y-196231D01*
G01Y-198564D02*
X75920Y-197397D01*
X74609Y-196522D01*
X73081Y-196231D01*
X71335Y-196814D01*
X70243Y-197980D01*
X69369Y-200022D01*
X68933Y-202064D01*
X69151Y-203814D01*
X70025Y-205856D01*
X71335Y-207314D01*
X73081Y-207897D01*
X74391Y-207605D01*
X75920Y-206439D01*
X76793Y-205273D01*
G01X87088Y-200022D02*
X94075D01*
X93420Y-197980D01*
X92328Y-196814D01*
X90800Y-196231D01*
X89271Y-196522D01*
X87961Y-197397D01*
X87088Y-199439D01*
X86651Y-201189D01*
Y-202939D01*
X87088Y-204689D01*
X88180Y-206439D01*
X89490Y-207605D01*
X91018Y-207897D01*
X92546Y-207314D01*
X94075Y-205564D01*
G01X104806Y-207897D02*
Y-196231D01*
G01Y-198564D02*
X105898Y-197397D01*
X106990Y-196522D01*
X108518Y-196231D01*
X109609Y-196522D01*
X110920Y-197397D01*
G01X138060Y-207897D02*
Y-190397D01*
X142426D01*
X144173Y-191272D01*
X145483Y-192439D01*
X146575Y-194188D01*
X147448Y-196231D01*
X147666Y-199147D01*
X147448Y-202064D01*
X146575Y-204106D01*
X145483Y-205856D01*
X144173Y-207022D01*
X142426Y-207897D01*
X138060D01*
G01X155996D02*
Y-190397D01*
X161236D01*
X162983Y-191272D01*
X164293Y-193314D01*
X164730Y-195647D01*
X164293Y-197980D01*
X163201Y-199730D01*
X161236Y-200606D01*
X155996D01*
G01X179609Y-198564D02*
X180483Y-197689D01*
X181138Y-196231D01*
X181575Y-194188D01*
X181138Y-192439D01*
X180265Y-191272D01*
X178736Y-190397D01*
X172841D01*
Y-207897D01*
X180046D01*
X181575Y-206731D01*
X182448Y-204980D01*
X182885Y-202939D01*
X182448Y-200897D01*
X181138Y-199147D01*
X179609Y-198564D01*
X172841D01*
G01X208496Y-190397D02*
Y-207897D01*
X217230D01*
G01X230363D02*
X229053Y-207605D01*
X227743Y-206439D01*
X226869Y-204397D01*
X226433Y-202064D01*
X226869Y-199730D01*
X227743Y-197689D01*
X229053Y-196522D01*
X230363Y-196231D01*
X231673Y-196522D01*
X232983Y-197689D01*
X233856Y-199730D01*
X234075Y-202064D01*
X233856Y-204397D01*
X232983Y-206439D01*
X231673Y-207605D01*
X230363Y-207897D01*
G01X242404Y-196231D02*
X245025Y-207897D01*
X247863Y-196231D01*
X250701Y-207897D01*
X253322Y-196231D01*
G01X278496Y-190397D02*
Y-207897D01*
X287230D01*
G01X300363D02*
X299053Y-207605D01*
X297743Y-206439D01*
X296869Y-204397D01*
X296433Y-202064D01*
X296869Y-199730D01*
X297743Y-197689D01*
X299053Y-196522D01*
X300363Y-196231D01*
X301673Y-196522D01*
X302983Y-197689D01*
X303856Y-199730D01*
X304075Y-202064D01*
X303856Y-204397D01*
X302983Y-206439D01*
X301673Y-207605D01*
X300363Y-207897D01*
G01X314588Y-205856D02*
X315680Y-207022D01*
X317208Y-207897D01*
X318518D01*
X319828Y-207314D01*
X320701Y-206439D01*
X321138Y-205273D01*
X320920Y-203522D01*
X320046Y-202647D01*
X316116Y-200897D01*
X315243Y-198855D01*
X315680Y-197397D01*
X316553Y-196522D01*
X317863Y-196231D01*
X319173Y-196522D01*
X320483Y-197397D01*
G01X332088Y-205856D02*
X333180Y-207022D01*
X334708Y-207897D01*
X336018D01*
X337328Y-207314D01*
X338201Y-206439D01*
X338638Y-205273D01*
X338420Y-203522D01*
X337546Y-202647D01*
X333616Y-200897D01*
X332743Y-198855D01*
X333180Y-197397D01*
X334053Y-196522D01*
X335363Y-196231D01*
X336673Y-196522D01*
X337983Y-197397D01*
G01X94686Y-164897D02*
Y-147397D01*
X100363Y-161980D01*
X106040Y-147397D01*
Y-164897D01*
G01X117863D02*
X116553Y-164605D01*
X115243Y-163439D01*
X114369Y-161397D01*
X113933Y-159064D01*
X114369Y-156730D01*
X115243Y-154689D01*
X116553Y-153522D01*
X117863Y-153231D01*
X119173Y-153522D01*
X120483Y-154689D01*
X121356Y-156730D01*
X121575Y-159064D01*
X121356Y-161397D01*
X120483Y-163439D01*
X119173Y-164605D01*
X117863Y-164897D01*
G01X139293Y-147397D02*
Y-164897D01*
G01Y-162273D02*
X138420Y-163731D01*
X137109Y-164605D01*
X135581Y-164897D01*
X133835Y-164314D01*
X132525Y-162856D01*
X131651Y-161106D01*
X131433Y-159064D01*
X131651Y-157022D01*
X132525Y-155272D01*
X133835Y-153814D01*
X135581Y-153231D01*
X137109Y-153522D01*
X138201Y-154106D01*
X139293Y-155272D01*
G01X149588Y-157022D02*
X156575D01*
X155920Y-154980D01*
X154828Y-153814D01*
X153300Y-153231D01*
X151771Y-153522D01*
X150461Y-154397D01*
X149588Y-156439D01*
X149151Y-158189D01*
Y-159939D01*
X149588Y-161689D01*
X150680Y-163439D01*
X151990Y-164605D01*
X153518Y-164897D01*
X155046Y-164314D01*
X156575Y-162564D01*
G01X170363Y-164897D02*
Y-147397D01*
G01X376163Y-209897D02*
Y-192397D01*
X373543Y-195897D01*
G01Y-209897D02*
X378783D01*
G01X396283D02*
Y-192397D01*
X388204Y-204939D01*
X399122D01*
G01X406360Y-207273D02*
X407669Y-208731D01*
X409198Y-209605D01*
X411163Y-209897D01*
X413128Y-209314D01*
X414656Y-208147D01*
X415748Y-206106D01*
X415966Y-203772D01*
X415530Y-201439D01*
X414438Y-199980D01*
X412909Y-198814D01*
X411381Y-198522D01*
X409853Y-198814D01*
X407888Y-199980D01*
X408543Y-192397D01*
X414438D01*
G01X431283Y-209897D02*
Y-192397D01*
X423204Y-204939D01*
X434122D01*
G01X441360Y-207273D02*
X442669Y-208731D01*
X444198Y-209605D01*
X446163Y-209897D01*
X448128Y-209314D01*
X449656Y-208147D01*
X450748Y-206106D01*
X450966Y-203772D01*
X450530Y-201439D01*
X449438Y-199980D01*
X447909Y-198814D01*
X446381Y-198522D01*
X444853Y-198814D01*
X442888Y-199980D01*
X443543Y-192397D01*
X449438D01*
G01X363046Y-164897D02*
Y-147397D01*
X368286D01*
X370033Y-148272D01*
X371343Y-150314D01*
X371780Y-152647D01*
X371343Y-154980D01*
X370251Y-156730D01*
X368286Y-157606D01*
X363046D01*
G01X389716Y-148856D02*
X388406Y-147980D01*
X386878Y-147397D01*
X385131D01*
X383166Y-148272D01*
X381638Y-149730D01*
X380546Y-151481D01*
X379673Y-154397D01*
X379454Y-157022D01*
X379891Y-159647D01*
X380546Y-161397D01*
X381856Y-163147D01*
X383385Y-164314D01*
X384913Y-164897D01*
X386441D01*
X387970Y-164314D01*
X389280Y-163439D01*
X390372Y-162273D01*
G01X404159Y-155564D02*
X405033Y-154689D01*
X405688Y-153231D01*
X406125Y-151188D01*
X405688Y-149439D01*
X404815Y-148272D01*
X403286Y-147397D01*
X397391D01*
Y-164897D01*
X404596D01*
X406125Y-163731D01*
X406998Y-161980D01*
X407435Y-159939D01*
X406998Y-157897D01*
X405688Y-156147D01*
X404159Y-155564D01*
X397391D01*
G01X413363Y-170730D02*
X426463D01*
G01X432391Y-164897D02*
Y-147397D01*
X442435Y-164897D01*
Y-147397D01*
G01X454913Y-164897D02*
X453166Y-164605D01*
X451638Y-163439D01*
X450328Y-161689D01*
X449454Y-159647D01*
X449018Y-157314D01*
Y-154980D01*
X449454Y-152647D01*
X450328Y-150605D01*
X451638Y-148856D01*
X453166Y-147689D01*
X454913Y-147397D01*
X456659Y-147689D01*
X458188Y-148856D01*
X459498Y-150605D01*
X460372Y-152647D01*
X460808Y-154980D01*
Y-157314D01*
X460372Y-159647D01*
X459498Y-161689D01*
X458188Y-163439D01*
X456659Y-164605D01*
X454913Y-164897D01*
G01X505754Y-147397D02*
X511213Y-164897D01*
X516672Y-147397D01*
G01X533080Y-164897D02*
X524346D01*
Y-147397D01*
X533080D01*
G01X529586Y-155855D02*
X524346D01*
G01X541846Y-164897D02*
Y-147397D01*
X547305D01*
X549051Y-148272D01*
X550143Y-149439D01*
X550580Y-151772D01*
X550143Y-154106D01*
X548833Y-155564D01*
X547305Y-156439D01*
X541846D01*
G01X547305D02*
X550580Y-164897D01*
G01X563713Y-165480D02*
X563276Y-165189D01*
Y-164605D01*
X563713Y-164314D01*
X564150Y-164605D01*
Y-165189D01*
X563713Y-165480D01*
G01X524128Y-207564D02*
X525875Y-209022D01*
X527840Y-209897D01*
X529586D01*
X531333Y-209022D01*
X532643Y-207564D01*
X533298Y-205522D01*
X532861Y-203481D01*
X531770Y-201730D01*
X529805Y-200564D01*
X527185Y-199980D01*
X525656Y-198814D01*
X525001Y-196772D01*
X525438Y-194730D01*
X526530Y-193272D01*
X528058Y-192397D01*
X529586D01*
X531115Y-192980D01*
X532425Y-194439D01*
G01X540754Y-209897D02*
X546213Y-192397D01*
X551672Y-209897D01*
G01X549706Y-203772D02*
X542719D01*
G01X643663Y-192397D02*
Y-209897D01*
G01X638641Y-192397D02*
X648685D01*
G01X656578Y-207564D02*
X658325Y-209022D01*
X660290Y-209897D01*
X662036D01*
X663783Y-209022D01*
X665093Y-207564D01*
X665748Y-205522D01*
X665311Y-203481D01*
X664220Y-201730D01*
X662255Y-200564D01*
X659635Y-199980D01*
X658106Y-198814D01*
X657451Y-196772D01*
X657888Y-194730D01*
X658980Y-193272D01*
X660508Y-192397D01*
X662036D01*
X663565Y-192980D01*
X664875Y-194439D01*
G01X676043Y-192397D02*
X681283D01*
G01X678663D02*
Y-209897D01*
G01X676043D02*
X681283D01*
G01X691796Y-192397D02*
Y-209897D01*
X700530D01*
G01X708860D02*
Y-192397D01*
G01X717156D02*
X708860Y-203189D01*
G01X718466Y-209897D02*
X712571Y-198231D01*
G01X630546Y-147397D02*
Y-164897D01*
X639280D01*
G01X656343D02*
Y-153231D01*
G01Y-155272D02*
X655470Y-154106D01*
X654159Y-153522D01*
X652631Y-153231D01*
X651103Y-153814D01*
X649793Y-154980D01*
X648919Y-156730D01*
X648483Y-159064D01*
X648919Y-161397D01*
X649793Y-163147D01*
X651103Y-164314D01*
X652631Y-164897D01*
X654159Y-164605D01*
X655470Y-163731D01*
X656343Y-162564D01*
G01X665328Y-170147D02*
X666638Y-170730D01*
X668385Y-170147D01*
X669476Y-168981D01*
X670350Y-167522D01*
X671659Y-162856D01*
X674498Y-153231D01*
G01X667511D02*
X671659Y-162856D01*
G01X684138Y-157022D02*
X691125D01*
X690470Y-154980D01*
X689378Y-153814D01*
X687850Y-153231D01*
X686321Y-153522D01*
X685011Y-154397D01*
X684138Y-156439D01*
X683701Y-158189D01*
Y-159939D01*
X684138Y-161689D01*
X685230Y-163439D01*
X686540Y-164605D01*
X688068Y-164897D01*
X689596Y-164314D01*
X691125Y-162564D01*
G01X701856Y-164897D02*
Y-153231D01*
G01Y-155564D02*
X702948Y-154397D01*
X704040Y-153522D01*
X705568Y-153231D01*
X706659Y-153522D01*
X707970Y-154397D01*
G01X719138Y-162856D02*
X720230Y-164022D01*
X721758Y-164897D01*
X723068D01*
X724378Y-164314D01*
X725251Y-163439D01*
X725688Y-162273D01*
X725470Y-160522D01*
X724596Y-159647D01*
X720666Y-157897D01*
X719793Y-155855D01*
X720230Y-154397D01*
X721103Y-153522D01*
X722413Y-153231D01*
X723723Y-153522D01*
X725033Y-154397D01*
G01X790596Y-209897D02*
Y-192397D01*
X796055D01*
X797801Y-193272D01*
X798893Y-194439D01*
X799330Y-196772D01*
X798893Y-199106D01*
X797583Y-200564D01*
X796055Y-201439D01*
X790596D01*
G01X796055D02*
X799330Y-209897D01*
G01X809188Y-202022D02*
X816175D01*
X815520Y-199980D01*
X814428Y-198814D01*
X812900Y-198231D01*
X811371Y-198522D01*
X810061Y-199397D01*
X809188Y-201439D01*
X808751Y-203189D01*
Y-204939D01*
X809188Y-206689D01*
X810280Y-208439D01*
X811590Y-209605D01*
X813118Y-209897D01*
X814646Y-209314D01*
X816175Y-207564D01*
G01X826033Y-209897D02*
Y-192397D01*
G01Y-201147D02*
X827125Y-199397D01*
X828435Y-198522D01*
X829745Y-198231D01*
X831709Y-198814D01*
X833020Y-199980D01*
X833893Y-202022D01*
Y-204355D01*
X833456Y-206689D01*
X832583Y-208439D01*
X831055Y-209605D01*
X829745Y-209897D01*
X828435Y-209605D01*
X827125Y-208731D01*
X826033Y-207273D01*
G01X844188Y-202022D02*
X851175D01*
X850520Y-199980D01*
X849428Y-198814D01*
X847900Y-198231D01*
X846371Y-198522D01*
X845061Y-199397D01*
X844188Y-201439D01*
X843751Y-203189D01*
Y-204939D01*
X844188Y-206689D01*
X845280Y-208439D01*
X846590Y-209605D01*
X848118Y-209897D01*
X849646Y-209314D01*
X851175Y-207564D01*
G01X868456Y-199689D02*
X866928Y-198522D01*
X865618Y-198231D01*
X863871Y-198814D01*
X862561Y-199980D01*
X861688Y-202022D01*
X861469Y-204064D01*
X861688Y-206106D01*
X862561Y-207856D01*
X863871Y-209314D01*
X865618Y-209897D01*
X867146Y-209314D01*
X868456Y-208147D01*
G01X885956Y-199689D02*
X884428Y-198522D01*
X883118Y-198231D01*
X881371Y-198814D01*
X880061Y-199980D01*
X879188Y-202022D01*
X878969Y-204064D01*
X879188Y-206106D01*
X880061Y-207856D01*
X881371Y-209314D01*
X883118Y-209897D01*
X884646Y-209314D01*
X885956Y-208147D01*
G01X903893Y-209897D02*
Y-198231D01*
G01Y-200272D02*
X903020Y-199106D01*
X901709Y-198522D01*
X900181Y-198231D01*
X898653Y-198814D01*
X897343Y-199980D01*
X896469Y-201730D01*
X896033Y-204064D01*
X896469Y-206397D01*
X897343Y-208147D01*
X898653Y-209314D01*
X900181Y-209897D01*
X901709Y-209605D01*
X903020Y-208731D01*
X903893Y-207564D01*
G01X781410Y-164897D02*
Y-147397D01*
X785776D01*
X787523Y-148272D01*
X788833Y-149439D01*
X789925Y-151188D01*
X790798Y-153231D01*
X791016Y-156147D01*
X790798Y-159064D01*
X789925Y-161106D01*
X788833Y-162856D01*
X787523Y-164022D01*
X785776Y-164897D01*
X781410D01*
G01X800438Y-157022D02*
X807425D01*
X806770Y-154980D01*
X805678Y-153814D01*
X804150Y-153231D01*
X802621Y-153522D01*
X801311Y-154397D01*
X800438Y-156439D01*
X800001Y-158189D01*
Y-159939D01*
X800438Y-161689D01*
X801530Y-163439D01*
X802840Y-164605D01*
X804368Y-164897D01*
X805896Y-164314D01*
X807425Y-162564D01*
G01X817938Y-162856D02*
X819030Y-164022D01*
X820558Y-164897D01*
X821868D01*
X823178Y-164314D01*
X824051Y-163439D01*
X824488Y-162273D01*
X824270Y-160522D01*
X823396Y-159647D01*
X819466Y-157897D01*
X818593Y-155855D01*
X819030Y-154397D01*
X819903Y-153522D01*
X821213Y-153231D01*
X822523Y-153522D01*
X823833Y-154397D01*
G01X838713Y-153231D02*
Y-164897D01*
G01Y-148564D02*
X838276Y-148272D01*
Y-147689D01*
X838713Y-147397D01*
X839150Y-147689D01*
Y-148272D01*
X838713Y-148564D01*
G01X853156Y-169272D02*
X854685Y-170439D01*
X856431Y-170730D01*
X857959Y-170439D01*
X859270Y-168981D01*
X860143Y-166939D01*
Y-153231D01*
G01Y-155564D02*
X859270Y-154397D01*
X857959Y-153522D01*
X856431Y-153231D01*
X854685Y-153814D01*
X853593Y-154980D01*
X852719Y-157022D01*
X852283Y-159064D01*
X852501Y-160814D01*
X853375Y-162856D01*
X854685Y-164314D01*
X856431Y-164897D01*
X857741Y-164605D01*
X859270Y-163439D01*
X860143Y-162273D01*
G01X870001Y-164897D02*
Y-153231D01*
G01Y-156147D02*
X870875Y-154689D01*
X872185Y-153522D01*
X873931Y-153231D01*
X875459Y-153522D01*
X876770Y-154689D01*
X877425Y-156730D01*
Y-164897D01*
G01X887938Y-157022D02*
X894925D01*
X894270Y-154980D01*
X893178Y-153814D01*
X891650Y-153231D01*
X890121Y-153522D01*
X888811Y-154397D01*
X887938Y-156439D01*
X887501Y-158189D01*
Y-159939D01*
X887938Y-161689D01*
X889030Y-163439D01*
X890340Y-164605D01*
X891868Y-164897D01*
X893396Y-164314D01*
X894925Y-162564D01*
G01X905656Y-164897D02*
Y-153231D01*
G01Y-155564D02*
X906748Y-154397D01*
X907840Y-153522D01*
X909368Y-153231D01*
X910459Y-153522D01*
X911770Y-154397D01*
G01X952413Y-192397D02*
X950666Y-192980D01*
X949356Y-194439D01*
X948483Y-196188D01*
X947828Y-198522D01*
X947610Y-201147D01*
X947828Y-203772D01*
X948483Y-206106D01*
X949356Y-207856D01*
X950666Y-209314D01*
X952413Y-209897D01*
X954159Y-209314D01*
X955470Y-207856D01*
X956343Y-206106D01*
X956998Y-203772D01*
X957216Y-201147D01*
X956998Y-198522D01*
X956343Y-196188D01*
X955470Y-194439D01*
X954159Y-192980D01*
X952413Y-192397D01*
G01X969913Y-209897D02*
X971441Y-209605D01*
X973188Y-208731D01*
X974280Y-207273D01*
X974716Y-205230D01*
X974280Y-203189D01*
X972970Y-201439D01*
X971005Y-200564D01*
X968821D01*
X967511Y-199980D01*
X966419Y-198522D01*
X965983Y-196481D01*
X966638Y-194439D01*
X968166Y-192980D01*
X969913Y-192397D01*
X971659Y-192980D01*
X973188Y-194439D01*
X973843Y-196481D01*
X973406Y-198522D01*
X972315Y-199980D01*
X971005Y-200564D01*
X968821D01*
X966856Y-201439D01*
X965546Y-203189D01*
X965110Y-205230D01*
X965546Y-207273D01*
X966638Y-208731D01*
X968385Y-209605D01*
X969913Y-209897D01*
G01X983483Y-210480D02*
X991343Y-192397D01*
G01X1004913D02*
X1003166Y-192980D01*
X1001856Y-194439D01*
X1000983Y-196188D01*
X1000328Y-198522D01*
X1000110Y-201147D01*
X1000328Y-203772D01*
X1000983Y-206106D01*
X1001856Y-207856D01*
X1003166Y-209314D01*
X1004913Y-209897D01*
X1006659Y-209314D01*
X1007970Y-207856D01*
X1008843Y-206106D01*
X1009498Y-203772D01*
X1009716Y-201147D01*
X1009498Y-198522D01*
X1008843Y-196188D01*
X1007970Y-194439D01*
X1006659Y-192980D01*
X1004913Y-192397D01*
G01X1022413Y-209897D02*
Y-192397D01*
X1019793Y-195897D01*
G01Y-209897D02*
X1025033D01*
G01X1035983Y-210480D02*
X1043843Y-192397D01*
G01X1053265Y-195314D02*
X1054575Y-193564D01*
X1056103Y-192689D01*
X1057850Y-192397D01*
X1060033Y-192980D01*
X1061561Y-194439D01*
X1061998Y-196188D01*
X1061780Y-197939D01*
X1060906Y-199397D01*
X1056540Y-202314D01*
X1054575Y-204355D01*
X1053265Y-207273D01*
X1052828Y-209897D01*
X1061998D01*
G01X1074913Y-192397D02*
X1073166Y-192980D01*
X1071856Y-194439D01*
X1070983Y-196188D01*
X1070328Y-198522D01*
X1070110Y-201147D01*
X1070328Y-203772D01*
X1070983Y-206106D01*
X1071856Y-207856D01*
X1073166Y-209314D01*
X1074913Y-209897D01*
X1076659Y-209314D01*
X1077970Y-207856D01*
X1078843Y-206106D01*
X1079498Y-203772D01*
X1079716Y-201147D01*
X1079498Y-198522D01*
X1078843Y-196188D01*
X1077970Y-194439D01*
X1076659Y-192980D01*
X1074913Y-192397D01*
G01X1092413Y-209897D02*
Y-192397D01*
X1089793Y-195897D01*
G01Y-209897D02*
X1095033D01*
G01X1112533D02*
Y-192397D01*
X1104454Y-204939D01*
X1115372D01*
G01X1000110Y-164897D02*
Y-147397D01*
X1004476D01*
X1006223Y-148272D01*
X1007533Y-149439D01*
X1008625Y-151188D01*
X1009498Y-153231D01*
X1009716Y-156147D01*
X1009498Y-159064D01*
X1008625Y-161106D01*
X1007533Y-162856D01*
X1006223Y-164022D01*
X1004476Y-164897D01*
X1000110D01*
G01X1026343D02*
Y-153231D01*
G01Y-155272D02*
X1025470Y-154106D01*
X1024159Y-153522D01*
X1022631Y-153231D01*
X1021103Y-153814D01*
X1019793Y-154980D01*
X1018919Y-156730D01*
X1018483Y-159064D01*
X1018919Y-161397D01*
X1019793Y-163147D01*
X1021103Y-164314D01*
X1022631Y-164897D01*
X1024159Y-164605D01*
X1025470Y-163731D01*
X1026343Y-162564D01*
G01X1039913Y-147397D02*
Y-164897D01*
G01X1036856Y-153231D02*
X1042970D01*
G01X1054138Y-157022D02*
X1061125D01*
X1060470Y-154980D01*
X1059378Y-153814D01*
X1057850Y-153231D01*
X1056321Y-153522D01*
X1055011Y-154397D01*
X1054138Y-156439D01*
X1053701Y-158189D01*
Y-159939D01*
X1054138Y-161689D01*
X1055230Y-163439D01*
X1056540Y-164605D01*
X1058068Y-164897D01*
X1059596Y-164314D01*
X1061125Y-162564D01*
G01X19842Y213601D02*
X1970D01*
X1Y211632D01*
Y142932D01*
X1970Y140963D01*
X25843D01*
Y277971D01*
X1970D01*
X1Y276002D01*
Y223050D01*
X1970Y221081D01*
X19883D01*
G02Y213601I0J-3740D01*
G01X19842D01*
G01X-11458Y209141D02*
X-11791Y208608D01*
X-11991Y208008D01*
Y207474D01*
X-11791Y206941D01*
X-11458Y206541D01*
X-10991Y206341D01*
X-10524Y206474D01*
X-10124Y206808D01*
X-9858Y207408D01*
X-9724Y208208D01*
X-9458Y208674D01*
X-8991Y208874D01*
X-8524Y208741D01*
X-8191Y208408D01*
X-7991Y207941D01*
Y207474D01*
X-8124Y207008D01*
X-8458Y206608D01*
G01X-11991Y203141D02*
X-7991D01*
G01X-9324Y198541D02*
X-11991D01*
G01X-8258D02*
X-8191Y198674D01*
X-8058D01*
X-7991Y198541D01*
X-8058Y198408D01*
X-8191D01*
X-8258Y198541D01*
G01X-7991Y193941D02*
X-11991D01*
G01X-9324Y194874D02*
Y193008D01*
G01X0Y339917D02*
X25843D01*
Y367517D01*
X20643D01*
Y703317D01*
X25843D01*
Y730917D01*
X0D01*
Y423026D01*
X1969Y421057D01*
X19883D01*
G02Y413577I0J-3740D01*
G01X1969D01*
X0Y411608D01*
Y339917D01*
G01X-11324Y516942D02*
X-11532Y516609D01*
X-11657Y516234D01*
Y515900D01*
X-11532Y515567D01*
X-11324Y515317D01*
X-11032Y515192D01*
X-10740Y515275D01*
X-10490Y515484D01*
X-10324Y515859D01*
X-10240Y516359D01*
X-10074Y516650D01*
X-9782Y516775D01*
X-9490Y516692D01*
X-9282Y516484D01*
X-9157Y516192D01*
Y515900D01*
X-9240Y515609D01*
X-9449Y515359D01*
G01X-11657Y512967D02*
X-9157D01*
G01X-9990Y509867D02*
X-11657D01*
G01X-9324D02*
X-9282Y509950D01*
X-9199D01*
X-9157Y509867D01*
X-9199Y509784D01*
X-9282D01*
X-9324Y509867D01*
G01X-9157Y506767D02*
X-11657D01*
G01X-9990Y507350D02*
Y506184D01*
G01X-11658Y818815D02*
X-11866Y818482D01*
X-11991Y818107D01*
Y817773D01*
X-11866Y817440D01*
X-11658Y817190D01*
X-11366Y817065D01*
X-11074Y817148D01*
X-10824Y817357D01*
X-10658Y817732D01*
X-10574Y818232D01*
X-10408Y818523D01*
X-10116Y818648D01*
X-9824Y818565D01*
X-9616Y818357D01*
X-9491Y818065D01*
Y817773D01*
X-9574Y817482D01*
X-9783Y817232D01*
G01X-11991Y814840D02*
X-9491D01*
G01X-10324Y811740D02*
X-11991D01*
G01X-9658D02*
X-9616Y811823D01*
X-9533D01*
X-9491Y811740D01*
X-9533Y811657D01*
X-9616D01*
X-9658Y811740D01*
G01X-9491Y808640D02*
X-11991D01*
G01X-10324Y809223D02*
Y808057D01*
G01X19842Y823050D02*
X1970D01*
X1Y821081D01*
Y752381D01*
X1970Y750412D01*
X25843D01*
Y887420D01*
X1970D01*
X1Y885451D01*
Y832499D01*
X1970Y830530D01*
X19883D01*
G02Y823050I0J-3740D01*
G01X19842D01*
G01X7300Y1006200D02*
X17300Y999200D01*
G01Y1006200D02*
X7300Y999200D01*
G01Y992100D02*
X17300D01*
X15300Y994100D01*
G01X7300D02*
Y990100D01*
G01Y984833D02*
X17300D01*
Y980833D01*
X16800Y979500D01*
X15633Y978500D01*
X14300Y978167D01*
X12967Y978500D01*
X11967Y979333D01*
X11466Y980833D01*
Y984833D01*
G01X16467Y967233D02*
X16967Y968233D01*
X17300Y969400D01*
Y970733D01*
X16800Y972234D01*
X15967Y973400D01*
X14967Y974233D01*
X13300Y974900D01*
X11800Y975067D01*
X10300Y974733D01*
X9300Y974233D01*
X8300Y973233D01*
X7633Y972067D01*
X7300Y970900D01*
Y969733D01*
X7633Y968567D01*
X8133Y967567D01*
X8800Y966733D01*
G01X17300Y962300D02*
Y958300D01*
G01Y960300D02*
X7300D01*
G01Y962300D02*
Y958300D01*
G01Y946367D02*
Y953033D01*
X17300D01*
Y946367D01*
G01X12467Y949033D02*
Y953033D01*
G01X3967Y944100D02*
Y934100D01*
G01X12633Y927167D02*
X13133Y926500D01*
X13966Y926000D01*
X15133Y925667D01*
X16133Y926000D01*
X16800Y926667D01*
X17300Y927833D01*
Y932333D01*
X7300D01*
Y926833D01*
X7967Y925667D01*
X8967Y925000D01*
X10133Y924667D01*
X11300Y925000D01*
X12300Y926000D01*
X12633Y927167D01*
Y932333D01*
G01X5800Y1054300D02*
X5467Y1054342D01*
X5175Y1054508D01*
X4925Y1054758D01*
X4758Y1055050D01*
X4675Y1055383D01*
Y1055717D01*
X4758Y1056050D01*
X4925Y1056342D01*
X5175Y1056592D01*
X5467Y1056758D01*
X5800Y1056800D01*
X6133Y1056758D01*
X6425Y1056592D01*
X6675Y1056342D01*
X6842Y1056050D01*
X6925Y1055717D01*
Y1055383D01*
X6842Y1055050D01*
X6675Y1054758D01*
X6425Y1054508D01*
X6133Y1054342D01*
X5800Y1054300D01*
G01X6133Y1054967D02*
X6633Y1054300D01*
G01X9400D02*
Y1056800D01*
X7858Y1055008D01*
X9942D01*
G01X11208Y1055342D02*
X11500Y1055633D01*
X11750Y1055800D01*
X12083Y1055883D01*
X12375Y1055800D01*
X12583Y1055633D01*
X12750Y1055383D01*
X12792Y1055092D01*
X12750Y1054842D01*
X12583Y1054592D01*
X12333Y1054383D01*
X12042Y1054300D01*
X11708Y1054383D01*
X11417Y1054633D01*
X11250Y1055008D01*
X11208Y1055425D01*
X11292Y1055967D01*
X11417Y1056258D01*
X11625Y1056550D01*
X11917Y1056758D01*
X12208Y1056800D01*
X12500Y1056717D01*
X12708Y1056508D01*
G01X8100Y1072217D02*
X5600D01*
Y1073258D01*
X5725Y1073592D01*
X5892Y1073800D01*
X6225Y1073883D01*
X6558Y1073800D01*
X6767Y1073550D01*
X6892Y1073258D01*
Y1072217D01*
G01Y1073258D02*
X8100Y1073883D01*
G01X7725Y1075233D02*
X7933Y1075483D01*
X8058Y1075775D01*
X8100Y1076150D01*
X8017Y1076525D01*
X7850Y1076817D01*
X7558Y1077025D01*
X7225Y1077067D01*
X6892Y1076983D01*
X6683Y1076775D01*
X6517Y1076483D01*
X6475Y1076192D01*
X6517Y1075900D01*
X6683Y1075525D01*
X5600Y1075650D01*
Y1076775D01*
G01X8100Y1079750D02*
X5600D01*
X7392Y1078208D01*
Y1080292D01*
G01X6017Y1081558D02*
X5767Y1081808D01*
X5642Y1082100D01*
X5600Y1082433D01*
X5683Y1082850D01*
X5892Y1083142D01*
X6142Y1083225D01*
X6392Y1083183D01*
X6600Y1083017D01*
X7017Y1082183D01*
X7308Y1081808D01*
X7725Y1081558D01*
X8100Y1081475D01*
Y1083225D01*
G01X25000Y1090000D02*
X12000D01*
G01Y1064000D02*
X25000D01*
G01X12000Y1090000D02*
Y1064000D01*
G01X19842Y1197853D02*
X1970D01*
X1Y1195884D01*
Y1127184D01*
X1970Y1125215D01*
X25843D01*
Y1262223D01*
X1970D01*
X1Y1260254D01*
Y1207302D01*
X1970Y1205333D01*
X19883D01*
G02Y1197853I0J-3740D01*
G01X19842D01*
G01X-11458Y1193393D02*
X-11791Y1192860D01*
X-11991Y1192260D01*
Y1191726D01*
X-11791Y1191193D01*
X-11458Y1190793D01*
X-10991Y1190593D01*
X-10524Y1190726D01*
X-10124Y1191060D01*
X-9858Y1191660D01*
X-9724Y1192460D01*
X-9458Y1192926D01*
X-8991Y1193126D01*
X-8524Y1192993D01*
X-8191Y1192660D01*
X-7991Y1192193D01*
Y1191726D01*
X-8124Y1191260D01*
X-8458Y1190860D01*
G01X-11991Y1187393D02*
X-7991D01*
G01X-9324Y1182793D02*
X-11991D01*
G01X-8258D02*
X-8191Y1182926D01*
X-8058D01*
X-7991Y1182793D01*
X-8058Y1182660D01*
X-8191D01*
X-8258Y1182793D01*
G01X-7991Y1178193D02*
X-11991D01*
G01X-9324Y1179126D02*
Y1177260D01*
G01X0Y1324169D02*
X25843D01*
Y1351769D01*
X20643D01*
Y1687569D01*
X25843D01*
Y1715169D01*
X0D01*
Y1407278D01*
X1969Y1405309D01*
X19883D01*
G02Y1397829I0J-3740D01*
G01X1969D01*
X0Y1395860D01*
Y1324169D01*
G01X-11324Y1501194D02*
X-11532Y1500861D01*
X-11657Y1500486D01*
Y1500152D01*
X-11532Y1499819D01*
X-11324Y1499569D01*
X-11032Y1499444D01*
X-10740Y1499527D01*
X-10490Y1499736D01*
X-10324Y1500111D01*
X-10240Y1500611D01*
X-10074Y1500902D01*
X-9782Y1501027D01*
X-9490Y1500944D01*
X-9282Y1500736D01*
X-9157Y1500444D01*
Y1500152D01*
X-9240Y1499861D01*
X-9449Y1499611D01*
G01X-11657Y1497219D02*
X-9157D01*
G01X-9990Y1494119D02*
X-11657D01*
G01X-9324D02*
X-9282Y1494202D01*
X-9199D01*
X-9157Y1494119D01*
X-9199Y1494036D01*
X-9282D01*
X-9324Y1494119D01*
G01X-9157Y1491019D02*
X-11657D01*
G01X-9990Y1491602D02*
Y1490436D01*
G01X-11658Y1803067D02*
X-11866Y1802734D01*
X-11991Y1802359D01*
Y1802025D01*
X-11866Y1801692D01*
X-11658Y1801442D01*
X-11366Y1801317D01*
X-11074Y1801400D01*
X-10824Y1801609D01*
X-10658Y1801984D01*
X-10574Y1802484D01*
X-10408Y1802775D01*
X-10116Y1802900D01*
X-9824Y1802817D01*
X-9616Y1802609D01*
X-9491Y1802317D01*
Y1802025D01*
X-9574Y1801734D01*
X-9783Y1801484D01*
G01X-11991Y1799092D02*
X-9491D01*
G01X-10324Y1795992D02*
X-11991D01*
G01X-9658D02*
X-9616Y1796075D01*
X-9533D01*
X-9491Y1795992D01*
X-9533Y1795909D01*
X-9616D01*
X-9658Y1795992D01*
G01X-9491Y1792892D02*
X-11991D01*
G01X-10324Y1793475D02*
Y1792309D01*
G01X19842Y1807302D02*
X1970D01*
X1Y1805333D01*
Y1736633D01*
X1970Y1734664D01*
X25843D01*
Y1871672D01*
X1970D01*
X1Y1869703D01*
Y1816751D01*
X1970Y1814782D01*
X19883D01*
G02Y1807302I0J-3740D01*
G01X19842D01*
G01X3917Y1954500D02*
Y1957000D01*
X4917D01*
X5250Y1956875D01*
X5500Y1956583D01*
X5583Y1956250D01*
X5500Y1955917D01*
X5292Y1955667D01*
X4917Y1955542D01*
X3917D01*
G01X8767Y1956792D02*
X8517Y1956917D01*
X8225Y1957000D01*
X7892D01*
X7517Y1956875D01*
X7225Y1956667D01*
X7017Y1956417D01*
X6850Y1956000D01*
X6808Y1955625D01*
X6892Y1955250D01*
X7017Y1955000D01*
X7267Y1954750D01*
X7558Y1954583D01*
X7850Y1954500D01*
X8142D01*
X8433Y1954583D01*
X8683Y1954708D01*
X8892Y1954875D01*
G01X10033Y1955000D02*
X10283Y1954708D01*
X10617Y1954542D01*
X10992Y1954500D01*
X11325Y1954542D01*
X11658Y1954750D01*
X11867Y1955000D01*
X11908Y1955250D01*
X11825Y1955542D01*
X11533Y1955750D01*
X11242Y1955833D01*
X10867D01*
G01X11242D02*
X11492Y1955958D01*
X11700Y1956167D01*
X11783Y1956417D01*
X11700Y1956667D01*
X11492Y1956875D01*
X11117Y1957000D01*
X10742Y1956958D01*
X10367Y1956792D01*
G01X13258Y1956583D02*
X13508Y1956833D01*
X13800Y1956958D01*
X14133Y1957000D01*
X14550Y1956917D01*
X14842Y1956708D01*
X14925Y1956458D01*
X14883Y1956208D01*
X14717Y1956000D01*
X13883Y1955583D01*
X13508Y1955292D01*
X13258Y1954875D01*
X13175Y1954500D01*
X14925D01*
G01X8454Y1959816D02*
X5954D01*
Y1960816D01*
X6079Y1961149D01*
X6371Y1961399D01*
X6704Y1961482D01*
X7037Y1961399D01*
X7287Y1961191D01*
X7412Y1960816D01*
Y1959816D01*
G01X8454Y1962916D02*
X5954D01*
Y1963957D01*
X6079Y1964291D01*
X6246Y1964499D01*
X6579Y1964582D01*
X6912Y1964499D01*
X7121Y1964249D01*
X7246Y1963957D01*
Y1962916D01*
G01Y1963957D02*
X8454Y1964582D01*
G01X7954Y1965932D02*
X8246Y1966182D01*
X8412Y1966516D01*
X8454Y1966891D01*
X8412Y1967224D01*
X8204Y1967557D01*
X7954Y1967766D01*
X7704Y1967807D01*
X7412Y1967724D01*
X7204Y1967432D01*
X7121Y1967141D01*
Y1966766D01*
G01Y1967141D02*
X6996Y1967391D01*
X6787Y1967599D01*
X6537Y1967682D01*
X6287Y1967599D01*
X6079Y1967391D01*
X5954Y1967016D01*
X5996Y1966641D01*
X6162Y1966266D01*
G01X8454Y1970449D02*
X5954D01*
X7746Y1968907D01*
Y1970991D01*
G01X3425Y1942650D02*
Y1945150D01*
X4425D01*
X4758Y1945025D01*
X5008Y1944733D01*
X5091Y1944400D01*
X5008Y1944067D01*
X4800Y1943817D01*
X4425Y1943692D01*
X3425D01*
G01X6525Y1942650D02*
Y1945150D01*
X7566D01*
X7900Y1945025D01*
X8108Y1944858D01*
X8191Y1944525D01*
X8108Y1944192D01*
X7858Y1943983D01*
X7566Y1943858D01*
X6525D01*
G01X7566D02*
X8191Y1942650D01*
G01X10958D02*
Y1945150D01*
X9416Y1943358D01*
X11500D01*
G01X13558Y1942650D02*
Y1945150D01*
X13058Y1944650D01*
G01Y1942650D02*
X14058D01*
G01X3425Y1946650D02*
Y1949150D01*
X4425D01*
X4758Y1949025D01*
X5008Y1948733D01*
X5091Y1948400D01*
X5008Y1948067D01*
X4800Y1947817D01*
X4425Y1947692D01*
X3425D01*
G01X6525Y1946650D02*
Y1949150D01*
X7566D01*
X7900Y1949025D01*
X8108Y1948858D01*
X8191Y1948525D01*
X8108Y1948192D01*
X7858Y1947983D01*
X7566Y1947858D01*
X6525D01*
G01X7566D02*
X8191Y1946650D01*
G01X10958D02*
Y1949150D01*
X9416Y1947358D01*
X11500D01*
G01X12641Y1947150D02*
X12891Y1946858D01*
X13225Y1946692D01*
X13600Y1946650D01*
X13933Y1946692D01*
X14266Y1946900D01*
X14475Y1947150D01*
X14516Y1947400D01*
X14433Y1947692D01*
X14141Y1947900D01*
X13850Y1947983D01*
X13475D01*
G01X13850D02*
X14100Y1948108D01*
X14308Y1948317D01*
X14391Y1948567D01*
X14308Y1948817D01*
X14100Y1949025D01*
X13725Y1949150D01*
X13350Y1949108D01*
X12975Y1948942D01*
G01X3425Y1950650D02*
Y1953150D01*
X4425D01*
X4758Y1953025D01*
X5008Y1952733D01*
X5091Y1952400D01*
X5008Y1952067D01*
X4800Y1951817D01*
X4425Y1951692D01*
X3425D01*
G01X6525Y1950650D02*
Y1953150D01*
X7566D01*
X7900Y1953025D01*
X8108Y1952858D01*
X8191Y1952525D01*
X8108Y1952192D01*
X7858Y1951983D01*
X7566Y1951858D01*
X6525D01*
G01X7566D02*
X8191Y1950650D01*
G01X10958D02*
Y1953150D01*
X9416Y1951358D01*
X11500D01*
G01X12641Y1951025D02*
X12891Y1950817D01*
X13183Y1950692D01*
X13558Y1950650D01*
X13933Y1950733D01*
X14225Y1950900D01*
X14433Y1951192D01*
X14475Y1951525D01*
X14391Y1951858D01*
X14183Y1952067D01*
X13891Y1952233D01*
X13600Y1952275D01*
X13308Y1952233D01*
X12933Y1952067D01*
X13058Y1953150D01*
X14183D01*
G01X12454Y1959816D02*
X9954D01*
Y1960816D01*
X10079Y1961149D01*
X10371Y1961399D01*
X10704Y1961482D01*
X11037Y1961399D01*
X11287Y1961191D01*
X11412Y1960816D01*
Y1959816D01*
G01X12454Y1962916D02*
X9954D01*
Y1963957D01*
X10079Y1964291D01*
X10246Y1964499D01*
X10579Y1964582D01*
X10912Y1964499D01*
X11121Y1964249D01*
X11246Y1963957D01*
Y1962916D01*
G01Y1963957D02*
X12454Y1964582D01*
G01Y1967349D02*
X9954D01*
X11746Y1965807D01*
Y1967891D01*
G01X11412Y1969157D02*
X11121Y1969449D01*
X10954Y1969699D01*
X10871Y1970032D01*
X10954Y1970324D01*
X11121Y1970532D01*
X11371Y1970699D01*
X11662Y1970741D01*
X11912Y1970699D01*
X12162Y1970532D01*
X12371Y1970282D01*
X12454Y1969991D01*
X12371Y1969657D01*
X12121Y1969366D01*
X11746Y1969199D01*
X11329Y1969157D01*
X10787Y1969241D01*
X10496Y1969366D01*
X10204Y1969574D01*
X9996Y1969866D01*
X9954Y1970157D01*
X10037Y1970449D01*
X10246Y1970657D01*
G01X4900Y1960117D02*
X2400D01*
Y1961117D01*
X2525Y1961450D01*
X2817Y1961700D01*
X3150Y1961783D01*
X3483Y1961700D01*
X3733Y1961492D01*
X3858Y1961117D01*
Y1960117D01*
G01X4900Y1963217D02*
X2400D01*
Y1964258D01*
X2525Y1964592D01*
X2692Y1964800D01*
X3025Y1964883D01*
X3358Y1964800D01*
X3567Y1964550D01*
X3692Y1964258D01*
Y1963217D01*
G01Y1964258D02*
X4900Y1964883D01*
G01X4400Y1966233D02*
X4692Y1966483D01*
X4858Y1966817D01*
X4900Y1967192D01*
X4858Y1967525D01*
X4650Y1967858D01*
X4400Y1968067D01*
X4150Y1968108D01*
X3858Y1968025D01*
X3650Y1967733D01*
X3567Y1967442D01*
Y1967067D01*
G01Y1967442D02*
X3442Y1967692D01*
X3233Y1967900D01*
X2983Y1967983D01*
X2733Y1967900D01*
X2525Y1967692D01*
X2400Y1967317D01*
X2442Y1966942D01*
X2608Y1966567D01*
G01X4900Y1970250D02*
X4858Y1970542D01*
X4733Y1970875D01*
X4525Y1971083D01*
X4233Y1971167D01*
X3942Y1971083D01*
X3692Y1970833D01*
X3567Y1970458D01*
Y1970042D01*
X3483Y1969792D01*
X3275Y1969583D01*
X2983Y1969500D01*
X2692Y1969625D01*
X2483Y1969917D01*
X2400Y1970250D01*
X2483Y1970583D01*
X2692Y1970875D01*
X2983Y1971000D01*
X3275Y1970917D01*
X3483Y1970708D01*
X3567Y1970458D01*
Y1970042D01*
X3692Y1969667D01*
X3942Y1969417D01*
X4233Y1969333D01*
X4525Y1969417D01*
X4733Y1969625D01*
X4858Y1969958D01*
X4900Y1970250D01*
G01X3517Y1933800D02*
Y1936300D01*
X4517D01*
X4850Y1936175D01*
X5100Y1935883D01*
X5183Y1935550D01*
X5100Y1935217D01*
X4892Y1934967D01*
X4517Y1934842D01*
X3517D01*
G01X6617Y1933800D02*
Y1936300D01*
X7658D01*
X7992Y1936175D01*
X8200Y1936008D01*
X8283Y1935675D01*
X8200Y1935342D01*
X7950Y1935133D01*
X7658Y1935008D01*
X6617D01*
G01X7658D02*
X8283Y1933800D01*
G01X9633Y1934300D02*
X9883Y1934008D01*
X10217Y1933842D01*
X10592Y1933800D01*
X10925Y1933842D01*
X11258Y1934050D01*
X11467Y1934300D01*
X11508Y1934550D01*
X11425Y1934842D01*
X11133Y1935050D01*
X10842Y1935133D01*
X10467D01*
G01X10842D02*
X11092Y1935258D01*
X11300Y1935467D01*
X11383Y1935717D01*
X11300Y1935967D01*
X11092Y1936175D01*
X10717Y1936300D01*
X10342Y1936258D01*
X9967Y1936092D01*
G01X12942Y1934092D02*
X13233Y1933883D01*
X13567Y1933800D01*
X13900Y1933883D01*
X14192Y1934133D01*
X14400Y1934508D01*
X14483Y1934883D01*
Y1935342D01*
X14400Y1935717D01*
X14192Y1936050D01*
X13942Y1936217D01*
X13650Y1936300D01*
X13317Y1936217D01*
X13067Y1936050D01*
X12900Y1935800D01*
X12817Y1935467D01*
X12900Y1935175D01*
X13108Y1934883D01*
X13358Y1934717D01*
X13650Y1934675D01*
X13983Y1934758D01*
X14233Y1934967D01*
X14483Y1935342D01*
G01X13400Y1919917D02*
X10900D01*
Y1920917D01*
X11025Y1921250D01*
X11317Y1921500D01*
X11650Y1921583D01*
X11983Y1921500D01*
X12233Y1921292D01*
X12358Y1920917D01*
Y1919917D01*
G01X13400Y1923017D02*
X10900D01*
Y1924058D01*
X11025Y1924392D01*
X11192Y1924600D01*
X11525Y1924683D01*
X11858Y1924600D01*
X12067Y1924350D01*
X12192Y1924058D01*
Y1923017D01*
G01Y1924058D02*
X13400Y1924683D01*
G01Y1927450D02*
X10900D01*
X12692Y1925908D01*
Y1927992D01*
G01X13400Y1929967D02*
X12858Y1930050D01*
X12400Y1930175D01*
X11983Y1930342D01*
X11525Y1930550D01*
X10900Y1930883D01*
Y1929217D01*
G01X3517Y1938300D02*
Y1940800D01*
X4558D01*
X4892Y1940675D01*
X5100Y1940508D01*
X5183Y1940175D01*
X5100Y1939842D01*
X4850Y1939633D01*
X4558Y1939508D01*
X3517D01*
G01X4558D02*
X5183Y1938300D01*
G01X7950D02*
Y1940800D01*
X6408Y1939008D01*
X8492D01*
G01X10550Y1938300D02*
X10842Y1938342D01*
X11175Y1938467D01*
X11383Y1938675D01*
X11467Y1938967D01*
X11383Y1939258D01*
X11133Y1939508D01*
X10758Y1939633D01*
X10342D01*
X10092Y1939717D01*
X9883Y1939925D01*
X9800Y1940217D01*
X9925Y1940508D01*
X10217Y1940717D01*
X10550Y1940800D01*
X10883Y1940717D01*
X11175Y1940508D01*
X11300Y1940217D01*
X11217Y1939925D01*
X11008Y1939717D01*
X10758Y1939633D01*
X10342D01*
X9967Y1939508D01*
X9717Y1939258D01*
X9633Y1938967D01*
X9717Y1938675D01*
X9925Y1938467D01*
X10258Y1938342D01*
X10550Y1938300D01*
G01X13567D02*
X13650Y1938842D01*
X13775Y1939300D01*
X13942Y1939717D01*
X14150Y1940175D01*
X14483Y1940800D01*
X12817D01*
G01X9200Y1919717D02*
X6700D01*
Y1920717D01*
X6825Y1921050D01*
X7117Y1921300D01*
X7450Y1921383D01*
X7783Y1921300D01*
X8033Y1921092D01*
X8158Y1920717D01*
Y1919717D01*
G01X9200Y1922817D02*
X6700D01*
Y1923858D01*
X6825Y1924192D01*
X6992Y1924400D01*
X7325Y1924483D01*
X7658Y1924400D01*
X7867Y1924150D01*
X7992Y1923858D01*
Y1922817D01*
G01Y1923858D02*
X9200Y1924483D01*
G01Y1927250D02*
X6700D01*
X8492Y1925708D01*
Y1927792D01*
G01X9200Y1929850D02*
X9158Y1930142D01*
X9033Y1930475D01*
X8825Y1930683D01*
X8533Y1930767D01*
X8242Y1930683D01*
X7992Y1930433D01*
X7867Y1930058D01*
Y1929642D01*
X7783Y1929392D01*
X7575Y1929183D01*
X7283Y1929100D01*
X6992Y1929225D01*
X6783Y1929517D01*
X6700Y1929850D01*
X6783Y1930183D01*
X6992Y1930475D01*
X7283Y1930600D01*
X7575Y1930517D01*
X7783Y1930308D01*
X7867Y1930058D01*
Y1929642D01*
X7992Y1929267D01*
X8242Y1929017D01*
X8533Y1928933D01*
X8825Y1929017D01*
X9033Y1929225D01*
X9158Y1929558D01*
X9200Y1929850D01*
G01X4800Y1919817D02*
X2300D01*
Y1920858D01*
X2425Y1921192D01*
X2592Y1921400D01*
X2925Y1921483D01*
X3258Y1921400D01*
X3467Y1921150D01*
X3592Y1920858D01*
Y1919817D01*
G01Y1920858D02*
X4800Y1921483D01*
G01Y1924250D02*
X2300D01*
X4092Y1922708D01*
Y1924792D01*
G01X4800Y1926850D02*
X4758Y1927142D01*
X4633Y1927475D01*
X4425Y1927683D01*
X4133Y1927767D01*
X3842Y1927683D01*
X3592Y1927433D01*
X3467Y1927058D01*
Y1926642D01*
X3383Y1926392D01*
X3175Y1926183D01*
X2883Y1926100D01*
X2592Y1926225D01*
X2383Y1926517D01*
X2300Y1926850D01*
X2383Y1927183D01*
X2592Y1927475D01*
X2883Y1927600D01*
X3175Y1927517D01*
X3383Y1927308D01*
X3467Y1927058D01*
Y1926642D01*
X3592Y1926267D01*
X3842Y1926017D01*
X4133Y1925933D01*
X4425Y1926017D01*
X4633Y1926225D01*
X4758Y1926558D01*
X4800Y1926850D01*
G01X3758Y1929158D02*
X3467Y1929450D01*
X3300Y1929700D01*
X3217Y1930033D01*
X3300Y1930325D01*
X3467Y1930533D01*
X3717Y1930700D01*
X4008Y1930742D01*
X4258Y1930700D01*
X4508Y1930533D01*
X4717Y1930283D01*
X4800Y1929992D01*
X4717Y1929658D01*
X4467Y1929367D01*
X4092Y1929200D01*
X3675Y1929158D01*
X3133Y1929242D01*
X2842Y1929367D01*
X2550Y1929575D01*
X2342Y1929867D01*
X2300Y1930158D01*
X2383Y1930450D01*
X2592Y1930658D01*
G01X97165Y110250D02*
X107165D01*
G01Y103250D02*
X97165D01*
G01X102165D02*
Y110250D01*
G01X97165Y99817D02*
X107165D01*
Y96483D01*
X106665Y95150D01*
X105998Y94150D01*
X104998Y93317D01*
X103831Y92650D01*
X102165Y92483D01*
X100498Y92650D01*
X99332Y93317D01*
X98331Y94150D01*
X97665Y95150D01*
X97165Y96483D01*
Y99817D01*
G01Y89217D02*
X107165D01*
Y85883D01*
X106665Y84550D01*
X105998Y83550D01*
X104998Y82717D01*
X103831Y82050D01*
X102165Y81883D01*
X100498Y82050D01*
X99332Y82717D01*
X98331Y83550D01*
X97665Y84550D01*
X97165Y85883D01*
Y89217D01*
G01Y74950D02*
X107165D01*
X105165Y76950D01*
G01X97165D02*
Y72950D01*
G01Y62350D02*
X107165D01*
X99998Y68517D01*
Y60183D01*
G01X17567Y66092D02*
X17317Y66217D01*
X17025Y66300D01*
X16692D01*
X16317Y66175D01*
X16025Y65967D01*
X15817Y65717D01*
X15650Y65300D01*
X15608Y64925D01*
X15692Y64550D01*
X15817Y64300D01*
X16067Y64050D01*
X16358Y63883D01*
X16650Y63800D01*
X16942D01*
X17233Y63883D01*
X17483Y64008D01*
X17692Y64175D01*
G01X19750Y63800D02*
Y66300D01*
X19250Y65800D01*
G01Y63800D02*
X20250D01*
G01X21933Y64175D02*
X22183Y63967D01*
X22475Y63842D01*
X22850Y63800D01*
X23225Y63883D01*
X23517Y64050D01*
X23725Y64342D01*
X23767Y64675D01*
X23683Y65008D01*
X23475Y65217D01*
X23183Y65383D01*
X22892Y65425D01*
X22600Y65383D01*
X22225Y65217D01*
X22350Y66300D01*
X23475D01*
G01X25867Y63800D02*
X25950Y64342D01*
X26075Y64800D01*
X26242Y65217D01*
X26450Y65675D01*
X26783Y66300D01*
X25117D01*
G01X17567Y61392D02*
X17317Y61517D01*
X17025Y61600D01*
X16692D01*
X16317Y61475D01*
X16025Y61267D01*
X15817Y61017D01*
X15650Y60600D01*
X15608Y60225D01*
X15692Y59850D01*
X15817Y59600D01*
X16067Y59350D01*
X16358Y59183D01*
X16650Y59100D01*
X16942D01*
X17233Y59183D01*
X17483Y59308D01*
X17692Y59475D01*
G01X19750Y59100D02*
Y61600D01*
X19250Y61100D01*
G01Y59100D02*
X20250D01*
G01X21933Y59600D02*
X22183Y59308D01*
X22517Y59142D01*
X22892Y59100D01*
X23225Y59142D01*
X23558Y59350D01*
X23767Y59600D01*
X23808Y59850D01*
X23725Y60142D01*
X23433Y60350D01*
X23142Y60433D01*
X22767D01*
G01X23142D02*
X23392Y60558D01*
X23600Y60767D01*
X23683Y61017D01*
X23600Y61267D01*
X23392Y61475D01*
X23017Y61600D01*
X22642Y61558D01*
X22267Y61392D01*
G01X25158Y61183D02*
X25408Y61433D01*
X25700Y61558D01*
X26033Y61600D01*
X26450Y61517D01*
X26742Y61308D01*
X26825Y61058D01*
X26783Y60808D01*
X26617Y60600D01*
X25783Y60183D01*
X25408Y59892D01*
X25158Y59475D01*
X25075Y59100D01*
X26825D01*
G01X16017Y54100D02*
Y56600D01*
X17058D01*
X17392Y56475D01*
X17600Y56308D01*
X17683Y55975D01*
X17600Y55642D01*
X17350Y55433D01*
X17058Y55308D01*
X16017D01*
G01X17058D02*
X17683Y54100D01*
G01X19158Y55142D02*
X19450Y55433D01*
X19700Y55600D01*
X20033Y55683D01*
X20325Y55600D01*
X20533Y55433D01*
X20700Y55183D01*
X20742Y54892D01*
X20700Y54642D01*
X20533Y54392D01*
X20283Y54183D01*
X19992Y54100D01*
X19658Y54183D01*
X19367Y54433D01*
X19200Y54808D01*
X19158Y55225D01*
X19242Y55767D01*
X19367Y56058D01*
X19575Y56350D01*
X19867Y56558D01*
X20158Y56600D01*
X20450Y56517D01*
X20658Y56308D01*
G01X23050Y56600D02*
X22717Y56517D01*
X22467Y56308D01*
X22300Y56058D01*
X22175Y55725D01*
X22133Y55350D01*
X22175Y54975D01*
X22300Y54642D01*
X22467Y54392D01*
X22717Y54183D01*
X23050Y54100D01*
X23383Y54183D01*
X23633Y54392D01*
X23800Y54642D01*
X23925Y54975D01*
X23967Y55350D01*
X23925Y55725D01*
X23800Y56058D01*
X23633Y56308D01*
X23383Y56517D01*
X23050Y56600D01*
G01X26067Y54100D02*
X26150Y54642D01*
X26275Y55100D01*
X26442Y55517D01*
X26650Y55975D01*
X26983Y56600D01*
X25317D01*
G01X91598Y184261D02*
Y23061D01*
X77998D01*
Y10111D01*
X59798D01*
Y23061D01*
X30898D01*
Y33411D01*
X37598D01*
Y173911D01*
X30898D01*
Y184261D01*
X59798D01*
Y197211D01*
X77998D01*
Y184261D01*
X91598D01*
G01X97266Y150342D02*
X97016Y150467D01*
X96724Y150550D01*
X96391D01*
X96016Y150425D01*
X95724Y150217D01*
X95516Y149967D01*
X95349Y149550D01*
X95307Y149175D01*
X95391Y148800D01*
X95516Y148550D01*
X95766Y148300D01*
X96057Y148133D01*
X96349Y148050D01*
X96641D01*
X96932Y148133D01*
X97182Y148258D01*
X97391Y148425D01*
G01X98532Y148550D02*
X98782Y148258D01*
X99116Y148092D01*
X99491Y148050D01*
X99824Y148092D01*
X100157Y148300D01*
X100366Y148550D01*
X100407Y148800D01*
X100324Y149092D01*
X100032Y149300D01*
X99741Y149383D01*
X99366D01*
G01X99741D02*
X99991Y149508D01*
X100199Y149717D01*
X100282Y149967D01*
X100199Y150217D01*
X99991Y150425D01*
X99616Y150550D01*
X99241Y150508D01*
X98866Y150342D01*
G01X101757Y150133D02*
X102007Y150383D01*
X102299Y150508D01*
X102632Y150550D01*
X103049Y150467D01*
X103341Y150258D01*
X103424Y150008D01*
X103382Y149758D01*
X103216Y149550D01*
X102382Y149133D01*
X102007Y148842D01*
X101757Y148425D01*
X101674Y148050D01*
X103424D01*
G01X105566D02*
X105649Y148592D01*
X105774Y149050D01*
X105941Y149467D01*
X106149Y149925D01*
X106482Y150550D01*
X104816D01*
G01X34500Y106000D02*
X21500D01*
G01X34500Y80000D02*
Y106000D01*
G01X21500Y80000D02*
X34500D01*
G01X21500Y106000D02*
Y80000D01*
G01X16317Y72400D02*
Y74900D01*
X17317D01*
X17650Y74775D01*
X17900Y74483D01*
X17983Y74150D01*
X17900Y73817D01*
X17692Y73567D01*
X17317Y73442D01*
X16317D01*
G01X21167Y74692D02*
X20917Y74817D01*
X20625Y74900D01*
X20292D01*
X19917Y74775D01*
X19625Y74567D01*
X19417Y74317D01*
X19250Y73900D01*
X19208Y73525D01*
X19292Y73150D01*
X19417Y72900D01*
X19667Y72650D01*
X19958Y72483D01*
X20250Y72400D01*
X20542D01*
X20833Y72483D01*
X21083Y72608D01*
X21292Y72775D01*
G01X23850Y72400D02*
Y74900D01*
X22308Y73108D01*
X24392D01*
G01X26367Y72400D02*
X26450Y72942D01*
X26575Y73400D01*
X26742Y73817D01*
X26950Y74275D01*
X27283Y74900D01*
X25617D01*
G01X16117Y68400D02*
Y70900D01*
X17117D01*
X17450Y70775D01*
X17700Y70483D01*
X17783Y70150D01*
X17700Y69817D01*
X17492Y69567D01*
X17117Y69442D01*
X16117D01*
G01X20967Y70692D02*
X20717Y70817D01*
X20425Y70900D01*
X20092D01*
X19717Y70775D01*
X19425Y70567D01*
X19217Y70317D01*
X19050Y69900D01*
X19008Y69525D01*
X19092Y69150D01*
X19217Y68900D01*
X19467Y68650D01*
X19758Y68483D01*
X20050Y68400D01*
X20342D01*
X20633Y68483D01*
X20883Y68608D01*
X21092Y68775D01*
G01X22358Y69442D02*
X22650Y69733D01*
X22900Y69900D01*
X23233Y69983D01*
X23525Y69900D01*
X23733Y69733D01*
X23900Y69483D01*
X23942Y69192D01*
X23900Y68942D01*
X23733Y68692D01*
X23483Y68483D01*
X23192Y68400D01*
X22858Y68483D01*
X22567Y68733D01*
X22400Y69108D01*
X22358Y69525D01*
X22442Y70067D01*
X22567Y70358D01*
X22775Y70650D01*
X23067Y70858D01*
X23358Y70900D01*
X23650Y70817D01*
X23858Y70608D01*
G01X25542Y68692D02*
X25833Y68483D01*
X26167Y68400D01*
X26500Y68483D01*
X26792Y68733D01*
X27000Y69108D01*
X27083Y69483D01*
Y69942D01*
X27000Y70317D01*
X26792Y70650D01*
X26542Y70817D01*
X26250Y70900D01*
X25917Y70817D01*
X25667Y70650D01*
X25500Y70400D01*
X25417Y70067D01*
X25500Y69775D01*
X25708Y69483D01*
X25958Y69317D01*
X26250Y69275D01*
X26583Y69358D01*
X26833Y69567D01*
X27083Y69942D01*
G01X62967Y201562D02*
Y199062D01*
X64633D01*
G01X67733D02*
X66067D01*
Y201562D01*
X67733D01*
G01X67067Y200354D02*
X66067D01*
G01X69083Y199062D02*
Y201562D01*
X69917D01*
X70250Y201437D01*
X70500Y201270D01*
X70708Y201020D01*
X70875Y200729D01*
X70917Y200312D01*
X70875Y199895D01*
X70708Y199604D01*
X70500Y199354D01*
X70250Y199187D01*
X69917Y199062D01*
X69083D01*
G01X73100D02*
Y201562D01*
X72600Y201062D01*
G01Y199062D02*
X73600D01*
G01X75283Y199437D02*
X75533Y199229D01*
X75825Y199104D01*
X76200Y199062D01*
X76575Y199145D01*
X76867Y199312D01*
X77075Y199604D01*
X77117Y199937D01*
X77033Y200270D01*
X76825Y200479D01*
X76533Y200645D01*
X76242Y200687D01*
X75950Y200645D01*
X75575Y200479D01*
X75700Y201562D01*
X76825D01*
G01X63198Y204231D02*
Y211831D01*
X74598D01*
Y204231D01*
X63198D01*
G01X55911Y220292D02*
Y222792D01*
X56952D01*
X57286Y222667D01*
X57494Y222500D01*
X57577Y222167D01*
X57494Y221834D01*
X57244Y221625D01*
X56952Y221500D01*
X55911D01*
G01X56952D02*
X57577Y220292D01*
G01X59052Y222375D02*
X59302Y222625D01*
X59594Y222750D01*
X59927Y222792D01*
X60344Y222709D01*
X60636Y222500D01*
X60719Y222250D01*
X60677Y222000D01*
X60511Y221792D01*
X59677Y221375D01*
X59302Y221084D01*
X59052Y220667D01*
X58969Y220292D01*
X60719D01*
G01X62236Y220584D02*
X62527Y220375D01*
X62861Y220292D01*
X63194Y220375D01*
X63486Y220625D01*
X63694Y221000D01*
X63777Y221375D01*
Y221834D01*
X63694Y222209D01*
X63486Y222542D01*
X63236Y222709D01*
X62944Y222792D01*
X62611Y222709D01*
X62361Y222542D01*
X62194Y222292D01*
X62111Y221959D01*
X62194Y221667D01*
X62402Y221375D01*
X62652Y221209D01*
X62944Y221167D01*
X63277Y221250D01*
X63527Y221459D01*
X63777Y221834D01*
G01X65252Y221334D02*
X65544Y221625D01*
X65794Y221792D01*
X66127Y221875D01*
X66419Y221792D01*
X66627Y221625D01*
X66794Y221375D01*
X66836Y221084D01*
X66794Y220834D01*
X66627Y220584D01*
X66377Y220375D01*
X66086Y220292D01*
X65752Y220375D01*
X65461Y220625D01*
X65294Y221000D01*
X65252Y221417D01*
X65336Y221959D01*
X65461Y222250D01*
X65669Y222542D01*
X65961Y222750D01*
X66252Y222792D01*
X66544Y222709D01*
X66752Y222500D01*
G01X61199Y201550D02*
Y205550D01*
X53799D01*
G01X86016Y204050D02*
Y206550D01*
X87057D01*
X87391Y206425D01*
X87599Y206258D01*
X87682Y205925D01*
X87599Y205592D01*
X87349Y205383D01*
X87057Y205258D01*
X86016D01*
G01X87057D02*
X87682Y204050D01*
G01X89157Y206133D02*
X89407Y206383D01*
X89699Y206508D01*
X90032Y206550D01*
X90449Y206467D01*
X90741Y206258D01*
X90824Y206008D01*
X90782Y205758D01*
X90616Y205550D01*
X89782Y205133D01*
X89407Y204842D01*
X89157Y204425D01*
X89074Y204050D01*
X90824D01*
G01X92341Y204342D02*
X92632Y204133D01*
X92966Y204050D01*
X93299Y204133D01*
X93591Y204383D01*
X93799Y204758D01*
X93882Y205133D01*
Y205592D01*
X93799Y205967D01*
X93591Y206300D01*
X93341Y206467D01*
X93049Y206550D01*
X92716Y206467D01*
X92466Y206300D01*
X92299Y206050D01*
X92216Y205717D01*
X92299Y205425D01*
X92507Y205133D01*
X92757Y204967D01*
X93049Y204925D01*
X93382Y205008D01*
X93632Y205217D01*
X93882Y205592D01*
G01X96066Y204050D02*
X96149Y204592D01*
X96274Y205050D01*
X96441Y205467D01*
X96649Y205925D01*
X96982Y206550D01*
X95316D01*
G01X83199Y202550D02*
Y206550D01*
X75799D01*
G01X55911Y224292D02*
Y226792D01*
X56952D01*
X57286Y226667D01*
X57494Y226500D01*
X57577Y226167D01*
X57494Y225834D01*
X57244Y225625D01*
X56952Y225500D01*
X55911D01*
G01X56952D02*
X57577Y224292D01*
G01X59052Y226375D02*
X59302Y226625D01*
X59594Y226750D01*
X59927Y226792D01*
X60344Y226709D01*
X60636Y226500D01*
X60719Y226250D01*
X60677Y226000D01*
X60511Y225792D01*
X59677Y225375D01*
X59302Y225084D01*
X59052Y224667D01*
X58969Y224292D01*
X60719D01*
G01X62236Y224584D02*
X62527Y224375D01*
X62861Y224292D01*
X63194Y224375D01*
X63486Y224625D01*
X63694Y225000D01*
X63777Y225375D01*
Y225834D01*
X63694Y226209D01*
X63486Y226542D01*
X63236Y226709D01*
X62944Y226792D01*
X62611Y226709D01*
X62361Y226542D01*
X62194Y226292D01*
X62111Y225959D01*
X62194Y225667D01*
X62402Y225375D01*
X62652Y225209D01*
X62944Y225167D01*
X63277Y225250D01*
X63527Y225459D01*
X63777Y225834D01*
G01X66044Y224292D02*
X66336Y224334D01*
X66669Y224459D01*
X66877Y224667D01*
X66961Y224959D01*
X66877Y225250D01*
X66627Y225500D01*
X66252Y225625D01*
X65836D01*
X65586Y225709D01*
X65377Y225917D01*
X65294Y226209D01*
X65419Y226500D01*
X65711Y226709D01*
X66044Y226792D01*
X66377Y226709D01*
X66669Y226500D01*
X66794Y226209D01*
X66711Y225917D01*
X66502Y225709D01*
X66252Y225625D01*
X65836D01*
X65461Y225500D01*
X65211Y225250D01*
X65127Y224959D01*
X65211Y224667D01*
X65419Y224459D01*
X65752Y224334D01*
X66044Y224292D01*
G01X61199Y205550D02*
Y209550D01*
X53799D01*
G01X86016Y208050D02*
Y210550D01*
X87057D01*
X87391Y210425D01*
X87599Y210258D01*
X87682Y209925D01*
X87599Y209592D01*
X87349Y209383D01*
X87057Y209258D01*
X86016D01*
G01X87057D02*
X87682Y208050D01*
G01X89157Y210133D02*
X89407Y210383D01*
X89699Y210508D01*
X90032Y210550D01*
X90449Y210467D01*
X90741Y210258D01*
X90824Y210008D01*
X90782Y209758D01*
X90616Y209550D01*
X89782Y209133D01*
X89407Y208842D01*
X89157Y208425D01*
X89074Y208050D01*
X90824D01*
G01X92341Y208342D02*
X92632Y208133D01*
X92966Y208050D01*
X93299Y208133D01*
X93591Y208383D01*
X93799Y208758D01*
X93882Y209133D01*
Y209592D01*
X93799Y209967D01*
X93591Y210300D01*
X93341Y210467D01*
X93049Y210550D01*
X92716Y210467D01*
X92466Y210300D01*
X92299Y210050D01*
X92216Y209717D01*
X92299Y209425D01*
X92507Y209133D01*
X92757Y208967D01*
X93049Y208925D01*
X93382Y209008D01*
X93632Y209217D01*
X93882Y209592D01*
G01X95441Y208342D02*
X95732Y208133D01*
X96066Y208050D01*
X96399Y208133D01*
X96691Y208383D01*
X96899Y208758D01*
X96982Y209133D01*
Y209592D01*
X96899Y209967D01*
X96691Y210300D01*
X96441Y210467D01*
X96149Y210550D01*
X95816Y210467D01*
X95566Y210300D01*
X95399Y210050D01*
X95316Y209717D01*
X95399Y209425D01*
X95607Y209133D01*
X95857Y208967D01*
X96149Y208925D01*
X96482Y209008D01*
X96732Y209217D01*
X96982Y209592D01*
G01X83199Y206550D02*
Y210550D01*
X75799D01*
G01X55911Y228292D02*
Y230792D01*
X56952D01*
X57286Y230667D01*
X57494Y230500D01*
X57577Y230167D01*
X57494Y229834D01*
X57244Y229625D01*
X56952Y229500D01*
X55911D01*
G01X56952D02*
X57577Y228292D01*
G01X58927Y228792D02*
X59177Y228500D01*
X59511Y228334D01*
X59886Y228292D01*
X60219Y228334D01*
X60552Y228542D01*
X60761Y228792D01*
X60802Y229042D01*
X60719Y229334D01*
X60427Y229542D01*
X60136Y229625D01*
X59761D01*
G01X60136D02*
X60386Y229750D01*
X60594Y229959D01*
X60677Y230209D01*
X60594Y230459D01*
X60386Y230667D01*
X60011Y230792D01*
X59636Y230750D01*
X59261Y230584D01*
G01X62944Y230792D02*
X62611Y230709D01*
X62361Y230500D01*
X62194Y230250D01*
X62069Y229917D01*
X62027Y229542D01*
X62069Y229167D01*
X62194Y228834D01*
X62361Y228584D01*
X62611Y228375D01*
X62944Y228292D01*
X63277Y228375D01*
X63527Y228584D01*
X63694Y228834D01*
X63819Y229167D01*
X63861Y229542D01*
X63819Y229917D01*
X63694Y230250D01*
X63527Y230500D01*
X63277Y230709D01*
X62944Y230792D01*
G01X66044D02*
X65711Y230709D01*
X65461Y230500D01*
X65294Y230250D01*
X65169Y229917D01*
X65127Y229542D01*
X65169Y229167D01*
X65294Y228834D01*
X65461Y228584D01*
X65711Y228375D01*
X66044Y228292D01*
X66377Y228375D01*
X66627Y228584D01*
X66794Y228834D01*
X66919Y229167D01*
X66961Y229542D01*
X66919Y229917D01*
X66794Y230250D01*
X66627Y230500D01*
X66377Y230709D01*
X66044Y230792D01*
G01X61199Y209550D02*
Y213550D01*
X53799D01*
G01X32771Y223738D02*
Y226238D01*
X33812D01*
X34146Y226113D01*
X34354Y225946D01*
X34437Y225613D01*
X34354Y225280D01*
X34104Y225071D01*
X33812Y224946D01*
X32771D01*
G01X33812D02*
X34437Y223738D01*
G01X35787Y224113D02*
X36037Y223905D01*
X36329Y223780D01*
X36704Y223738D01*
X37079Y223821D01*
X37371Y223988D01*
X37579Y224280D01*
X37621Y224613D01*
X37537Y224946D01*
X37329Y225155D01*
X37037Y225321D01*
X36746Y225363D01*
X36454Y225321D01*
X36079Y225155D01*
X36204Y226238D01*
X37329D01*
G01X39804D02*
X39471Y226155D01*
X39221Y225946D01*
X39054Y225696D01*
X38929Y225363D01*
X38887Y224988D01*
X38929Y224613D01*
X39054Y224280D01*
X39221Y224030D01*
X39471Y223821D01*
X39804Y223738D01*
X40137Y223821D01*
X40387Y224030D01*
X40554Y224280D01*
X40679Y224613D01*
X40721Y224988D01*
X40679Y225363D01*
X40554Y225696D01*
X40387Y225946D01*
X40137Y226155D01*
X39804Y226238D01*
G01X43404Y223738D02*
Y226238D01*
X41862Y224446D01*
X43946D01*
G01X46399Y219100D02*
Y215100D01*
X53799D01*
G01X29808Y193917D02*
X29683Y193667D01*
X29600Y193375D01*
Y193042D01*
X29725Y192667D01*
X29933Y192375D01*
X30183Y192167D01*
X30600Y192000D01*
X30975Y191958D01*
X31350Y192042D01*
X31600Y192167D01*
X31850Y192417D01*
X32017Y192708D01*
X32100Y193000D01*
Y193292D01*
X32017Y193583D01*
X31892Y193833D01*
X31725Y194042D01*
G01X32100Y195142D02*
X29600D01*
X32100Y197058D01*
X29600D01*
G01X31808Y198492D02*
X32017Y198783D01*
X32100Y199117D01*
X32017Y199450D01*
X31767Y199742D01*
X31392Y199950D01*
X31017Y200033D01*
X30558D01*
X30183Y199950D01*
X29850Y199742D01*
X29683Y199492D01*
X29600Y199200D01*
X29683Y198867D01*
X29850Y198617D01*
X30100Y198450D01*
X30433Y198367D01*
X30725Y198450D01*
X31017Y198658D01*
X31183Y198908D01*
X31225Y199200D01*
X31142Y199533D01*
X30933Y199783D01*
X30558Y200033D01*
G01X35999Y205450D02*
X35957Y205117D01*
X35791Y204825D01*
X35541Y204575D01*
X35249Y204408D01*
X34916Y204325D01*
X34582D01*
X34249Y204408D01*
X33957Y204575D01*
X33707Y204825D01*
X33541Y205117D01*
X33499Y205450D01*
X33541Y205783D01*
X33707Y206075D01*
X33957Y206325D01*
X34249Y206492D01*
X34582Y206575D01*
X34916D01*
X35249Y206492D01*
X35541Y206325D01*
X35791Y206075D01*
X35957Y205783D01*
X35999Y205450D01*
G01X35332Y205783D02*
X35999Y206283D01*
G01Y209050D02*
X33499D01*
X35291Y207508D01*
Y209592D01*
G01X35999Y211650D02*
X35957Y211942D01*
X35832Y212275D01*
X35624Y212483D01*
X35332Y212567D01*
X35041Y212483D01*
X34791Y212233D01*
X34666Y211858D01*
Y211442D01*
X34582Y211192D01*
X34374Y210983D01*
X34082Y210900D01*
X33791Y211025D01*
X33582Y211317D01*
X33499Y211650D01*
X33582Y211983D01*
X33791Y212275D01*
X34082Y212400D01*
X34374Y212317D01*
X34582Y212108D01*
X34666Y211858D01*
Y211442D01*
X34791Y211067D01*
X35041Y210817D01*
X35332Y210733D01*
X35624Y210817D01*
X35832Y211025D01*
X35957Y211358D01*
X35999Y211650D01*
G01X53199Y214400D02*
X39199D01*
G01X53199Y201400D02*
Y214400D01*
G01X39199Y201400D02*
X53199D01*
G01X39199Y214400D02*
Y201400D01*
G01X64500Y404000D02*
X74500Y397000D01*
G01Y404000D02*
X64500Y397000D01*
G01Y389900D02*
X74500D01*
X72500Y391900D01*
G01X64500D02*
Y387900D01*
G01X68666Y382467D02*
X69833Y381300D01*
X70500Y380300D01*
X70833Y378967D01*
X70500Y377800D01*
X69833Y376967D01*
X68833Y376300D01*
X67667Y376133D01*
X66667Y376300D01*
X65666Y376967D01*
X64833Y377967D01*
X64500Y379133D01*
X64833Y380467D01*
X65833Y381633D01*
X67333Y382300D01*
X69000Y382467D01*
X71166Y382133D01*
X72333Y381633D01*
X73500Y380800D01*
X74333Y379633D01*
X74500Y378467D01*
X74167Y377300D01*
X73333Y376467D01*
G01X64500Y372033D02*
X74500D01*
Y368033D01*
X74000Y366700D01*
X72833Y365700D01*
X71500Y365367D01*
X70167Y365700D01*
X69167Y366533D01*
X68666Y368033D01*
Y372033D01*
G01X73667Y354433D02*
X74167Y355433D01*
X74500Y356600D01*
Y357933D01*
X74000Y359434D01*
X73167Y360600D01*
X72167Y361433D01*
X70500Y362100D01*
X69000Y362267D01*
X67500Y361933D01*
X66500Y361433D01*
X65500Y360433D01*
X64833Y359267D01*
X64500Y358100D01*
Y356933D01*
X64833Y355767D01*
X65333Y354767D01*
X66000Y353933D01*
G01X74500Y349500D02*
Y345500D01*
G01Y347500D02*
X64500D01*
G01Y349500D02*
Y345500D01*
G01Y333567D02*
Y340233D01*
X74500D01*
Y333567D01*
G01X69667Y336233D02*
Y340233D01*
G01X61167Y331300D02*
Y321300D01*
G01X69833Y314367D02*
X70333Y313700D01*
X71166Y313200D01*
X72333Y312867D01*
X73333Y313200D01*
X74000Y313867D01*
X74500Y315033D01*
Y319533D01*
X64500D01*
Y314033D01*
X65167Y312867D01*
X66167Y312200D01*
X67333Y311867D01*
X68500Y312200D01*
X69500Y313200D01*
X69833Y314367D01*
Y319533D01*
G01X37300Y266400D02*
Y276400D01*
G01X44300D02*
Y266400D01*
G01Y271400D02*
X37300D01*
G01X47733Y266400D02*
Y276400D01*
X51067D01*
X52400Y275900D01*
X53400Y275233D01*
X54233Y274233D01*
X54900Y273066D01*
X55067Y271400D01*
X54900Y269733D01*
X54233Y268567D01*
X53400Y267566D01*
X52400Y266900D01*
X51067Y266400D01*
X47733D01*
G01X58333D02*
Y276400D01*
X61667D01*
X63000Y275900D01*
X64000Y275233D01*
X64833Y274233D01*
X65500Y273066D01*
X65667Y271400D01*
X65500Y269733D01*
X64833Y268567D01*
X64000Y267566D01*
X63000Y266900D01*
X61667Y266400D01*
X58333D01*
G01X72600D02*
Y276400D01*
X70600Y274400D01*
G01Y266400D02*
X74600D01*
G01X85200D02*
Y276400D01*
X79033Y269233D01*
X87367D01*
G01X88800Y263067D02*
X98800D01*
G01X101067Y276400D02*
Y266400D01*
X107733D01*
G01X118333D02*
X111667D01*
Y276400D01*
X118333D01*
G01X115667Y271567D02*
X111667D01*
G01X121933Y266400D02*
Y276400D01*
X125267D01*
X126600Y275900D01*
X127600Y275233D01*
X128433Y274233D01*
X129100Y273066D01*
X129267Y271400D01*
X129100Y269733D01*
X128433Y268567D01*
X127600Y267566D01*
X126600Y266900D01*
X125267Y266400D01*
X121933D01*
G01X93500Y416000D02*
X103500D01*
G01Y409000D02*
X93500D01*
G01X98500D02*
Y416000D01*
G01X93500Y405567D02*
X103500D01*
Y402233D01*
X103000Y400900D01*
X102333Y399900D01*
X101333Y399067D01*
X100166Y398400D01*
X98500Y398233D01*
X96833Y398400D01*
X95667Y399067D01*
X94666Y399900D01*
X94000Y400900D01*
X93500Y402233D01*
Y405567D01*
G01Y394967D02*
X103500D01*
Y391633D01*
X103000Y390300D01*
X102333Y389300D01*
X101333Y388467D01*
X100166Y387800D01*
X98500Y387633D01*
X96833Y387800D01*
X95667Y388467D01*
X94666Y389300D01*
X94000Y390300D01*
X93500Y391633D01*
Y394967D01*
G01Y380700D02*
X103500D01*
X101500Y382700D01*
G01X93500D02*
Y378700D01*
G01X95500Y373767D02*
X94333Y372767D01*
X93667Y371434D01*
X93500Y369933D01*
X93667Y368600D01*
X94500Y367267D01*
X95500Y366433D01*
X96500Y366267D01*
X97666Y366600D01*
X98500Y367767D01*
X98833Y368933D01*
Y370433D01*
G01Y368933D02*
X99333Y367933D01*
X100166Y367100D01*
X101167Y366767D01*
X102167Y367100D01*
X103000Y367933D01*
X103500Y369433D01*
X103333Y370933D01*
X102667Y372433D01*
G01X47000Y392517D02*
X44500D01*
Y393558D01*
X44625Y393892D01*
X44792Y394100D01*
X45125Y394183D01*
X45458Y394100D01*
X45667Y393850D01*
X45792Y393558D01*
Y392517D01*
G01Y393558D02*
X47000Y394183D01*
G01Y396950D02*
X44500D01*
X46292Y395408D01*
Y397492D01*
G01X44500Y399550D02*
X44583Y399217D01*
X44792Y398967D01*
X45042Y398800D01*
X45375Y398675D01*
X45750Y398633D01*
X46125Y398675D01*
X46458Y398800D01*
X46708Y398967D01*
X46917Y399217D01*
X47000Y399550D01*
X46917Y399883D01*
X46708Y400133D01*
X46458Y400300D01*
X46125Y400425D01*
X45750Y400467D01*
X45375Y400425D01*
X45042Y400300D01*
X44792Y400133D01*
X44583Y399883D01*
X44500Y399550D01*
G01X45958Y401858D02*
X45667Y402150D01*
X45500Y402400D01*
X45417Y402733D01*
X45500Y403025D01*
X45667Y403233D01*
X45917Y403400D01*
X46208Y403442D01*
X46458Y403400D01*
X46708Y403233D01*
X46917Y402983D01*
X47000Y402692D01*
X46917Y402358D01*
X46667Y402067D01*
X46292Y401900D01*
X45875Y401858D01*
X45333Y401942D01*
X45042Y402067D01*
X44750Y402275D01*
X44542Y402567D01*
X44500Y402858D01*
X44583Y403150D01*
X44792Y403358D01*
G01X35899Y379326D02*
Y376826D01*
G01X34941Y379326D02*
X36857D01*
G01X38166Y376826D02*
Y379326D01*
X39166D01*
X39499Y379201D01*
X39749Y378909D01*
X39832Y378576D01*
X39749Y378243D01*
X39541Y377993D01*
X39166Y377868D01*
X38166D01*
G01X41307D02*
X41599Y378159D01*
X41849Y378326D01*
X42182Y378409D01*
X42474Y378326D01*
X42682Y378159D01*
X42849Y377909D01*
X42891Y377618D01*
X42849Y377368D01*
X42682Y377118D01*
X42432Y376909D01*
X42141Y376826D01*
X41807Y376909D01*
X41516Y377159D01*
X41349Y377534D01*
X41307Y377951D01*
X41391Y378493D01*
X41516Y378784D01*
X41724Y379076D01*
X42016Y379284D01*
X42307Y379326D01*
X42599Y379243D01*
X42807Y379034D01*
G01X43000Y392517D02*
X40500D01*
Y393558D01*
X40625Y393892D01*
X40792Y394100D01*
X41125Y394183D01*
X41458Y394100D01*
X41667Y393850D01*
X41792Y393558D01*
Y392517D01*
G01Y393558D02*
X43000Y394183D01*
G01Y396950D02*
X40500D01*
X42292Y395408D01*
Y397492D01*
G01X40500Y399550D02*
X40583Y399217D01*
X40792Y398967D01*
X41042Y398800D01*
X41375Y398675D01*
X41750Y398633D01*
X42125Y398675D01*
X42458Y398800D01*
X42708Y398967D01*
X42917Y399217D01*
X43000Y399550D01*
X42917Y399883D01*
X42708Y400133D01*
X42458Y400300D01*
X42125Y400425D01*
X41750Y400467D01*
X41375Y400425D01*
X41042Y400300D01*
X40792Y400133D01*
X40583Y399883D01*
X40500Y399550D01*
G01X43000Y402567D02*
X42458Y402650D01*
X42000Y402775D01*
X41583Y402942D01*
X41125Y403150D01*
X40500Y403483D01*
Y401817D01*
G01X27102Y331566D02*
Y334066D01*
G01X28852D02*
Y331566D01*
G01Y332816D02*
X27102D01*
G01X30285Y332608D02*
X30577Y332899D01*
X30827Y333066D01*
X31160Y333149D01*
X31452Y333066D01*
X31660Y332899D01*
X31827Y332649D01*
X31869Y332358D01*
X31827Y332108D01*
X31660Y331858D01*
X31410Y331649D01*
X31119Y331566D01*
X30785Y331649D01*
X30494Y331899D01*
X30327Y332274D01*
X30285Y332691D01*
X30369Y333233D01*
X30494Y333524D01*
X30702Y333816D01*
X30994Y334024D01*
X31285Y334066D01*
X31577Y333983D01*
X31785Y333774D01*
G01X27708Y414880D02*
X27583Y414630D01*
X27500Y414338D01*
Y414005D01*
X27625Y413630D01*
X27833Y413338D01*
X28083Y413130D01*
X28500Y412963D01*
X28875Y412921D01*
X29250Y413005D01*
X29500Y413130D01*
X29750Y413380D01*
X29917Y413671D01*
X30000Y413963D01*
Y414255D01*
X29917Y414546D01*
X29792Y414796D01*
X29625Y415005D01*
G01X30000Y416105D02*
X27500D01*
X30000Y418021D01*
X27500D01*
G01X27917Y419371D02*
X27667Y419621D01*
X27542Y419913D01*
X27500Y420246D01*
X27583Y420663D01*
X27792Y420955D01*
X28042Y421038D01*
X28292Y420996D01*
X28500Y420830D01*
X28917Y419996D01*
X29208Y419621D01*
X29625Y419371D01*
X30000Y419288D01*
Y421038D01*
G01X44800Y406900D02*
X48800D01*
Y414300D01*
G01X44700D02*
X40700D01*
Y406900D01*
G01X91598Y589773D02*
Y428573D01*
X77998D01*
Y415623D01*
X59798D01*
Y428573D01*
X30898D01*
Y438923D01*
X37598D01*
Y579423D01*
X30898D01*
Y589773D01*
X59798D01*
Y602723D01*
X77998D01*
Y589773D01*
X91598D01*
G01X95712Y544280D02*
X95462Y544405D01*
X95170Y544488D01*
X94837D01*
X94462Y544363D01*
X94170Y544155D01*
X93962Y543905D01*
X93795Y543488D01*
X93753Y543113D01*
X93837Y542738D01*
X93962Y542488D01*
X94212Y542238D01*
X94503Y542071D01*
X94795Y541988D01*
X95087D01*
X95378Y542071D01*
X95628Y542196D01*
X95837Y542363D01*
G01X96978Y542488D02*
X97228Y542196D01*
X97562Y542030D01*
X97937Y541988D01*
X98270Y542030D01*
X98603Y542238D01*
X98812Y542488D01*
X98853Y542738D01*
X98770Y543030D01*
X98478Y543238D01*
X98187Y543321D01*
X97812D01*
G01X98187D02*
X98437Y543446D01*
X98645Y543655D01*
X98728Y543905D01*
X98645Y544155D01*
X98437Y544363D01*
X98062Y544488D01*
X97687Y544446D01*
X97312Y544280D01*
G01X100995Y541988D02*
Y544488D01*
X100495Y543988D01*
G01Y541988D02*
X101495D01*
G01X104095Y544488D02*
X103762Y544405D01*
X103512Y544196D01*
X103345Y543946D01*
X103220Y543613D01*
X103178Y543238D01*
X103220Y542863D01*
X103345Y542530D01*
X103512Y542280D01*
X103762Y542071D01*
X104095Y541988D01*
X104428Y542071D01*
X104678Y542280D01*
X104845Y542530D01*
X104970Y542863D01*
X105012Y543238D01*
X104970Y543613D01*
X104845Y543946D01*
X104678Y544196D01*
X104428Y544405D01*
X104095Y544488D01*
G01X95712Y540780D02*
X95462Y540905D01*
X95170Y540988D01*
X94837D01*
X94462Y540863D01*
X94170Y540655D01*
X93962Y540405D01*
X93795Y539988D01*
X93753Y539613D01*
X93837Y539238D01*
X93962Y538988D01*
X94212Y538738D01*
X94503Y538571D01*
X94795Y538488D01*
X95087D01*
X95378Y538571D01*
X95628Y538696D01*
X95837Y538863D01*
G01X96978Y538988D02*
X97228Y538696D01*
X97562Y538530D01*
X97937Y538488D01*
X98270Y538530D01*
X98603Y538738D01*
X98812Y538988D01*
X98853Y539238D01*
X98770Y539530D01*
X98478Y539738D01*
X98187Y539821D01*
X97812D01*
G01X98187D02*
X98437Y539946D01*
X98645Y540155D01*
X98728Y540405D01*
X98645Y540655D01*
X98437Y540863D01*
X98062Y540988D01*
X97687Y540946D01*
X97312Y540780D01*
G01X100995Y538488D02*
Y540988D01*
X100495Y540488D01*
G01Y538488D02*
X101495D01*
G01X104095D02*
Y540988D01*
X103595Y540488D01*
G01Y538488D02*
X104595D01*
G01X64467Y607563D02*
Y605063D01*
X66133D01*
G01X69233D02*
X67567D01*
Y607563D01*
X69233D01*
G01X68567Y606355D02*
X67567D01*
G01X70583Y605063D02*
Y607563D01*
X71417D01*
X71750Y607438D01*
X72000Y607271D01*
X72208Y607021D01*
X72375Y606730D01*
X72417Y606313D01*
X72375Y605896D01*
X72208Y605605D01*
X72000Y605355D01*
X71750Y605188D01*
X71417Y605063D01*
X70583D01*
G01X74600D02*
Y607563D01*
X74100Y607063D01*
G01Y605063D02*
X75100D01*
G01X78200D02*
Y607563D01*
X76658Y605771D01*
X78742D01*
G01X63198Y609743D02*
Y617343D01*
X74598D01*
Y609743D01*
X63198D01*
G01X77518Y619450D02*
Y621950D01*
X78559D01*
X78893Y621825D01*
X79101Y621658D01*
X79184Y621325D01*
X79101Y620992D01*
X78851Y620783D01*
X78559Y620658D01*
X77518D01*
G01X78559D02*
X79184Y619450D01*
G01X80659Y621533D02*
X80909Y621783D01*
X81201Y621908D01*
X81534Y621950D01*
X81951Y621867D01*
X82243Y621658D01*
X82326Y621408D01*
X82284Y621158D01*
X82118Y620950D01*
X81284Y620533D01*
X80909Y620242D01*
X80659Y619825D01*
X80576Y619450D01*
X82326D01*
G01X84551D02*
X84843Y619492D01*
X85176Y619617D01*
X85384Y619825D01*
X85468Y620117D01*
X85384Y620408D01*
X85134Y620658D01*
X84759Y620783D01*
X84343D01*
X84093Y620867D01*
X83884Y621075D01*
X83801Y621367D01*
X83926Y621658D01*
X84218Y621867D01*
X84551Y621950D01*
X84884Y621867D01*
X85176Y621658D01*
X85301Y621367D01*
X85218Y621075D01*
X85009Y620867D01*
X84759Y620783D01*
X84343D01*
X83968Y620658D01*
X83718Y620408D01*
X83634Y620117D01*
X83718Y619825D01*
X83926Y619617D01*
X84259Y619492D01*
X84551Y619450D01*
G01X86734Y619950D02*
X86984Y619658D01*
X87318Y619492D01*
X87693Y619450D01*
X88026Y619492D01*
X88359Y619700D01*
X88568Y619950D01*
X88609Y620200D01*
X88526Y620492D01*
X88234Y620700D01*
X87943Y620783D01*
X87568D01*
G01X87943D02*
X88193Y620908D01*
X88401Y621117D01*
X88484Y621367D01*
X88401Y621617D01*
X88193Y621825D01*
X87818Y621950D01*
X87443Y621908D01*
X87068Y621742D01*
G01X83201Y609450D02*
Y613450D01*
X75801D01*
G01X77017Y624500D02*
Y627000D01*
X78058D01*
X78392Y626875D01*
X78600Y626708D01*
X78683Y626375D01*
X78600Y626042D01*
X78350Y625833D01*
X78058Y625708D01*
X77017D01*
G01X78058D02*
X78683Y624500D01*
G01X80158Y626583D02*
X80408Y626833D01*
X80700Y626958D01*
X81033Y627000D01*
X81450Y626917D01*
X81742Y626708D01*
X81825Y626458D01*
X81783Y626208D01*
X81617Y626000D01*
X80783Y625583D01*
X80408Y625292D01*
X80158Y624875D01*
X80075Y624500D01*
X81825D01*
G01X84050D02*
X84342Y624542D01*
X84675Y624667D01*
X84883Y624875D01*
X84967Y625167D01*
X84883Y625458D01*
X84633Y625708D01*
X84258Y625833D01*
X83842D01*
X83592Y625917D01*
X83383Y626125D01*
X83300Y626417D01*
X83425Y626708D01*
X83717Y626917D01*
X84050Y627000D01*
X84383Y626917D01*
X84675Y626708D01*
X84800Y626417D01*
X84717Y626125D01*
X84508Y625917D01*
X84258Y625833D01*
X83842D01*
X83467Y625708D01*
X83217Y625458D01*
X83133Y625167D01*
X83217Y624875D01*
X83425Y624667D01*
X83758Y624542D01*
X84050Y624500D01*
G01X86233Y624875D02*
X86483Y624667D01*
X86775Y624542D01*
X87150Y624500D01*
X87525Y624583D01*
X87817Y624750D01*
X88025Y625042D01*
X88067Y625375D01*
X87983Y625708D01*
X87775Y625917D01*
X87483Y626083D01*
X87192Y626125D01*
X86900Y626083D01*
X86525Y625917D01*
X86650Y627000D01*
X87775D01*
G01X83201Y613450D02*
Y617450D01*
X75801D01*
G01X26017Y643000D02*
Y645500D01*
X27058D01*
X27392Y645375D01*
X27600Y645208D01*
X27683Y644875D01*
X27600Y644542D01*
X27350Y644333D01*
X27058Y644208D01*
X26017D01*
G01X27058D02*
X27683Y643000D01*
G01X29033Y643500D02*
X29283Y643208D01*
X29617Y643042D01*
X29992Y643000D01*
X30325Y643042D01*
X30658Y643250D01*
X30867Y643500D01*
X30908Y643750D01*
X30825Y644042D01*
X30533Y644250D01*
X30242Y644333D01*
X29867D01*
G01X30242D02*
X30492Y644458D01*
X30700Y644667D01*
X30783Y644917D01*
X30700Y645167D01*
X30492Y645375D01*
X30117Y645500D01*
X29742Y645458D01*
X29367Y645292D01*
G01X32133Y643375D02*
X32383Y643167D01*
X32675Y643042D01*
X33050Y643000D01*
X33425Y643083D01*
X33717Y643250D01*
X33925Y643542D01*
X33967Y643875D01*
X33883Y644208D01*
X33675Y644417D01*
X33383Y644583D01*
X33092Y644625D01*
X32800Y644583D01*
X32425Y644417D01*
X32550Y645500D01*
X33675D01*
G01X35358Y644042D02*
X35650Y644333D01*
X35900Y644500D01*
X36233Y644583D01*
X36525Y644500D01*
X36733Y644333D01*
X36900Y644083D01*
X36942Y643792D01*
X36900Y643542D01*
X36733Y643292D01*
X36483Y643083D01*
X36192Y643000D01*
X35858Y643083D01*
X35567Y643333D01*
X35400Y643708D01*
X35358Y644125D01*
X35442Y644667D01*
X35567Y644958D01*
X35775Y645250D01*
X36067Y645458D01*
X36358Y645500D01*
X36650Y645417D01*
X36858Y645208D01*
G01X36699Y609550D02*
Y613550D01*
X29299D01*
G01X40517Y624000D02*
Y626500D01*
X41558D01*
X41892Y626375D01*
X42100Y626208D01*
X42183Y625875D01*
X42100Y625542D01*
X41850Y625333D01*
X41558Y625208D01*
X40517D01*
G01X41558D02*
X42183Y624000D01*
G01X43533Y624500D02*
X43783Y624208D01*
X44117Y624042D01*
X44492Y624000D01*
X44825Y624042D01*
X45158Y624250D01*
X45367Y624500D01*
X45408Y624750D01*
X45325Y625042D01*
X45033Y625250D01*
X44742Y625333D01*
X44367D01*
G01X44742D02*
X44992Y625458D01*
X45200Y625667D01*
X45283Y625917D01*
X45200Y626167D01*
X44992Y626375D01*
X44617Y626500D01*
X44242Y626458D01*
X43867Y626292D01*
G01X46633Y624375D02*
X46883Y624167D01*
X47175Y624042D01*
X47550Y624000D01*
X47925Y624083D01*
X48217Y624250D01*
X48425Y624542D01*
X48467Y624875D01*
X48383Y625208D01*
X48175Y625417D01*
X47883Y625583D01*
X47592Y625625D01*
X47300Y625583D01*
X46925Y625417D01*
X47050Y626500D01*
X48175D01*
G01X50567Y624000D02*
X50650Y624542D01*
X50775Y625000D01*
X50942Y625417D01*
X51150Y625875D01*
X51483Y626500D01*
X49817D01*
G01X43000Y637500D02*
Y633500D01*
X50400D01*
G01X26017Y647000D02*
Y649500D01*
X27058D01*
X27392Y649375D01*
X27600Y649208D01*
X27683Y648875D01*
X27600Y648542D01*
X27350Y648333D01*
X27058Y648208D01*
X26017D01*
G01X27058D02*
X27683Y647000D01*
G01X29033Y647500D02*
X29283Y647208D01*
X29617Y647042D01*
X29992Y647000D01*
X30325Y647042D01*
X30658Y647250D01*
X30867Y647500D01*
X30908Y647750D01*
X30825Y648042D01*
X30533Y648250D01*
X30242Y648333D01*
X29867D01*
G01X30242D02*
X30492Y648458D01*
X30700Y648667D01*
X30783Y648917D01*
X30700Y649167D01*
X30492Y649375D01*
X30117Y649500D01*
X29742Y649458D01*
X29367Y649292D01*
G01X32133Y647375D02*
X32383Y647167D01*
X32675Y647042D01*
X33050Y647000D01*
X33425Y647083D01*
X33717Y647250D01*
X33925Y647542D01*
X33967Y647875D01*
X33883Y648208D01*
X33675Y648417D01*
X33383Y648583D01*
X33092Y648625D01*
X32800Y648583D01*
X32425Y648417D01*
X32550Y649500D01*
X33675D01*
G01X35442Y647292D02*
X35733Y647083D01*
X36067Y647000D01*
X36400Y647083D01*
X36692Y647333D01*
X36900Y647708D01*
X36983Y648083D01*
Y648542D01*
X36900Y648917D01*
X36692Y649250D01*
X36442Y649417D01*
X36150Y649500D01*
X35817Y649417D01*
X35567Y649250D01*
X35400Y649000D01*
X35317Y648667D01*
X35400Y648375D01*
X35608Y648083D01*
X35858Y647917D01*
X36150Y647875D01*
X36483Y647958D01*
X36733Y648167D01*
X36983Y648542D01*
G01X29299Y618050D02*
Y614050D01*
X36699D01*
G01X43000Y641600D02*
Y637600D01*
X50400D01*
G01X83016Y641050D02*
Y643550D01*
X84057D01*
X84391Y643425D01*
X84599Y643258D01*
X84682Y642925D01*
X84599Y642592D01*
X84349Y642383D01*
X84057Y642258D01*
X83016D01*
G01X84057D02*
X84682Y641050D01*
G01X86032Y641425D02*
X86282Y641217D01*
X86574Y641092D01*
X86949Y641050D01*
X87324Y641133D01*
X87616Y641300D01*
X87824Y641592D01*
X87866Y641925D01*
X87782Y642258D01*
X87574Y642467D01*
X87282Y642633D01*
X86991Y642675D01*
X86699Y642633D01*
X86324Y642467D01*
X86449Y643550D01*
X87574D01*
G01X90049D02*
X89716Y643467D01*
X89466Y643258D01*
X89299Y643008D01*
X89174Y642675D01*
X89132Y642300D01*
X89174Y641925D01*
X89299Y641592D01*
X89466Y641342D01*
X89716Y641133D01*
X90049Y641050D01*
X90382Y641133D01*
X90632Y641342D01*
X90799Y641592D01*
X90924Y641925D01*
X90966Y642300D01*
X90924Y642675D01*
X90799Y643008D01*
X90632Y643258D01*
X90382Y643467D01*
X90049Y643550D01*
G01X92232Y641550D02*
X92482Y641258D01*
X92816Y641092D01*
X93191Y641050D01*
X93524Y641092D01*
X93857Y641300D01*
X94066Y641550D01*
X94107Y641800D01*
X94024Y642092D01*
X93732Y642300D01*
X93441Y642383D01*
X93066D01*
G01X93441D02*
X93691Y642508D01*
X93899Y642717D01*
X93982Y642967D01*
X93899Y643217D01*
X93691Y643425D01*
X93316Y643550D01*
X92941Y643508D01*
X92566Y643342D01*
G01X73799Y644550D02*
Y640550D01*
X81199D01*
G01X26017Y639000D02*
Y641500D01*
X27058D01*
X27392Y641375D01*
X27600Y641208D01*
X27683Y640875D01*
X27600Y640542D01*
X27350Y640333D01*
X27058Y640208D01*
X26017D01*
G01X27058D02*
X27683Y639000D01*
G01X29033Y639375D02*
X29283Y639167D01*
X29575Y639042D01*
X29950Y639000D01*
X30325Y639083D01*
X30617Y639250D01*
X30825Y639542D01*
X30867Y639875D01*
X30783Y640208D01*
X30575Y640417D01*
X30283Y640583D01*
X29992Y640625D01*
X29700Y640583D01*
X29325Y640417D01*
X29450Y641500D01*
X30575D01*
G01X33550Y639000D02*
Y641500D01*
X32008Y639708D01*
X34092D01*
G01X35442Y639292D02*
X35733Y639083D01*
X36067Y639000D01*
X36400Y639083D01*
X36692Y639333D01*
X36900Y639708D01*
X36983Y640083D01*
Y640542D01*
X36900Y640917D01*
X36692Y641250D01*
X36442Y641417D01*
X36150Y641500D01*
X35817Y641417D01*
X35567Y641250D01*
X35400Y641000D01*
X35317Y640667D01*
X35400Y640375D01*
X35608Y640083D01*
X35858Y639917D01*
X36150Y639875D01*
X36483Y639958D01*
X36733Y640167D01*
X36983Y640542D01*
G01X33400Y609326D02*
Y605326D01*
X40800D01*
G01X26017Y635000D02*
Y637500D01*
X27058D01*
X27392Y637375D01*
X27600Y637208D01*
X27683Y636875D01*
X27600Y636542D01*
X27350Y636333D01*
X27058Y636208D01*
X26017D01*
G01X27058D02*
X27683Y635000D01*
G01X29033Y635375D02*
X29283Y635167D01*
X29575Y635042D01*
X29950Y635000D01*
X30325Y635083D01*
X30617Y635250D01*
X30825Y635542D01*
X30867Y635875D01*
X30783Y636208D01*
X30575Y636417D01*
X30283Y636583D01*
X29992Y636625D01*
X29700Y636583D01*
X29325Y636417D01*
X29450Y637500D01*
X30575D01*
G01X33550Y635000D02*
Y637500D01*
X32008Y635708D01*
X34092D01*
G01X36150Y635000D02*
X36442Y635042D01*
X36775Y635167D01*
X36983Y635375D01*
X37067Y635667D01*
X36983Y635958D01*
X36733Y636208D01*
X36358Y636333D01*
X35942D01*
X35692Y636417D01*
X35483Y636625D01*
X35400Y636917D01*
X35525Y637208D01*
X35817Y637417D01*
X36150Y637500D01*
X36483Y637417D01*
X36775Y637208D01*
X36900Y636917D01*
X36817Y636625D01*
X36608Y636417D01*
X36358Y636333D01*
X35942D01*
X35567Y636208D01*
X35317Y635958D01*
X35233Y635667D01*
X35317Y635375D01*
X35525Y635167D01*
X35858Y635042D01*
X36150Y635000D01*
G01X33400Y605200D02*
Y601200D01*
X40800D01*
G01X26017Y631000D02*
Y633500D01*
X27058D01*
X27392Y633375D01*
X27600Y633208D01*
X27683Y632875D01*
X27600Y632542D01*
X27350Y632333D01*
X27058Y632208D01*
X26017D01*
G01X27058D02*
X27683Y631000D01*
G01X29033Y631375D02*
X29283Y631167D01*
X29575Y631042D01*
X29950Y631000D01*
X30325Y631083D01*
X30617Y631250D01*
X30825Y631542D01*
X30867Y631875D01*
X30783Y632208D01*
X30575Y632417D01*
X30283Y632583D01*
X29992Y632625D01*
X29700Y632583D01*
X29325Y632417D01*
X29450Y633500D01*
X30575D01*
G01X33550Y631000D02*
Y633500D01*
X32008Y631708D01*
X34092D01*
G01X36067Y631000D02*
X36150Y631542D01*
X36275Y632000D01*
X36442Y632417D01*
X36650Y632875D01*
X36983Y633500D01*
X35317D01*
G01X30100Y599400D02*
Y595400D01*
X37500D01*
G01X26017Y627000D02*
Y629500D01*
X27058D01*
X27392Y629375D01*
X27600Y629208D01*
X27683Y628875D01*
X27600Y628542D01*
X27350Y628333D01*
X27058Y628208D01*
X26017D01*
G01X27058D02*
X27683Y627000D01*
G01X29033Y627375D02*
X29283Y627167D01*
X29575Y627042D01*
X29950Y627000D01*
X30325Y627083D01*
X30617Y627250D01*
X30825Y627542D01*
X30867Y627875D01*
X30783Y628208D01*
X30575Y628417D01*
X30283Y628583D01*
X29992Y628625D01*
X29700Y628583D01*
X29325Y628417D01*
X29450Y629500D01*
X30575D01*
G01X33550Y627000D02*
Y629500D01*
X32008Y627708D01*
X34092D01*
G01X35358Y628042D02*
X35650Y628333D01*
X35900Y628500D01*
X36233Y628583D01*
X36525Y628500D01*
X36733Y628333D01*
X36900Y628083D01*
X36942Y627792D01*
X36900Y627542D01*
X36733Y627292D01*
X36483Y627083D01*
X36192Y627000D01*
X35858Y627083D01*
X35567Y627333D01*
X35400Y627708D01*
X35358Y628125D01*
X35442Y628667D01*
X35567Y628958D01*
X35775Y629250D01*
X36067Y629458D01*
X36358Y629500D01*
X36650Y629417D01*
X36858Y629208D01*
G01X30100Y595300D02*
Y591300D01*
X37500D01*
G01X50000Y596017D02*
X47500D01*
Y597058D01*
X47625Y597392D01*
X47792Y597600D01*
X48125Y597683D01*
X48458Y597600D01*
X48667Y597350D01*
X48792Y597058D01*
Y596017D01*
G01Y597058D02*
X50000Y597683D01*
G01X49625Y599033D02*
X49833Y599283D01*
X49958Y599575D01*
X50000Y599950D01*
X49917Y600325D01*
X49750Y600617D01*
X49458Y600825D01*
X49125Y600867D01*
X48792Y600783D01*
X48583Y600575D01*
X48417Y600283D01*
X48375Y599992D01*
X48417Y599700D01*
X48583Y599325D01*
X47500Y599450D01*
Y600575D01*
G01X50000Y603550D02*
X47500D01*
X49292Y602008D01*
Y604092D01*
G01X49625Y605233D02*
X49833Y605483D01*
X49958Y605775D01*
X50000Y606150D01*
X49917Y606525D01*
X49750Y606817D01*
X49458Y607025D01*
X49125Y607067D01*
X48792Y606983D01*
X48583Y606775D01*
X48417Y606483D01*
X48375Y606192D01*
X48417Y605900D01*
X48583Y605525D01*
X47500Y605650D01*
Y606775D01*
G01X40900Y599400D02*
X44900D01*
Y606800D01*
G01X42017Y591500D02*
Y594000D01*
X43058D01*
X43392Y593875D01*
X43600Y593708D01*
X43683Y593375D01*
X43600Y593042D01*
X43350Y592833D01*
X43058Y592708D01*
X42017D01*
G01X43058D02*
X43683Y591500D01*
G01X45033Y591875D02*
X45283Y591667D01*
X45575Y591542D01*
X45950Y591500D01*
X46325Y591583D01*
X46617Y591750D01*
X46825Y592042D01*
X46867Y592375D01*
X46783Y592708D01*
X46575Y592917D01*
X46283Y593083D01*
X45992Y593125D01*
X45700Y593083D01*
X45325Y592917D01*
X45450Y594000D01*
X46575D01*
G01X49550Y591500D02*
Y594000D01*
X48008Y592208D01*
X50092D01*
G01X52650Y591500D02*
Y594000D01*
X51108Y592208D01*
X53192D01*
G01X37700Y599400D02*
Y595400D01*
X45100D01*
G01X48500Y610850D02*
X51000D01*
G01X48500Y609892D02*
Y611808D01*
G01X51000Y613117D02*
X48500D01*
Y614117D01*
X48625Y614450D01*
X48917Y614700D01*
X49250Y614783D01*
X49583Y614700D01*
X49833Y614492D01*
X49958Y614117D01*
Y613117D01*
G01X51000Y617050D02*
X48500D01*
X49000Y616550D01*
G01X51000D02*
Y617550D01*
G01X48917Y619358D02*
X48667Y619608D01*
X48542Y619900D01*
X48500Y620233D01*
X48583Y620650D01*
X48792Y620942D01*
X49042Y621025D01*
X49292Y620983D01*
X49500Y620817D01*
X49917Y619983D01*
X50208Y619608D01*
X50625Y619358D01*
X51000Y619275D01*
Y621025D01*
G01X63299Y645400D02*
X77299D01*
G01X63299Y658400D02*
Y645400D01*
G01X77299D02*
Y658400D01*
G01X56271Y672078D02*
Y674578D01*
X57312D01*
X57646Y674453D01*
X57854Y674286D01*
X57937Y673953D01*
X57854Y673620D01*
X57604Y673411D01*
X57312Y673286D01*
X56271D01*
G01X57312D02*
X57937Y672078D01*
G01X59412Y674161D02*
X59662Y674411D01*
X59954Y674536D01*
X60287Y674578D01*
X60704Y674495D01*
X60996Y674286D01*
X61079Y674036D01*
X61037Y673786D01*
X60871Y673578D01*
X60037Y673161D01*
X59662Y672870D01*
X59412Y672453D01*
X59329Y672078D01*
X61079D01*
G01X63304D02*
X63596Y672120D01*
X63929Y672245D01*
X64137Y672453D01*
X64221Y672745D01*
X64137Y673036D01*
X63887Y673286D01*
X63512Y673411D01*
X63096D01*
X62846Y673495D01*
X62637Y673703D01*
X62554Y673995D01*
X62679Y674286D01*
X62971Y674495D01*
X63304Y674578D01*
X63637Y674495D01*
X63929Y674286D01*
X64054Y673995D01*
X63971Y673703D01*
X63762Y673495D01*
X63512Y673411D01*
X63096D01*
X62721Y673286D01*
X62471Y673036D01*
X62387Y672745D01*
X62471Y672453D01*
X62679Y672245D01*
X63012Y672120D01*
X63304Y672078D01*
G01X65612Y674161D02*
X65862Y674411D01*
X66154Y674536D01*
X66487Y674578D01*
X66904Y674495D01*
X67196Y674286D01*
X67279Y674036D01*
X67237Y673786D01*
X67071Y673578D01*
X66237Y673161D01*
X65862Y672870D01*
X65612Y672453D01*
X65529Y672078D01*
X67279D01*
G01X55049Y658487D02*
Y654487D01*
X62449D01*
G01X56271Y668078D02*
Y670578D01*
X57312D01*
X57646Y670453D01*
X57854Y670286D01*
X57937Y669953D01*
X57854Y669620D01*
X57604Y669411D01*
X57312Y669286D01*
X56271D01*
G01X57312D02*
X57937Y668078D01*
G01X59412Y670161D02*
X59662Y670411D01*
X59954Y670536D01*
X60287Y670578D01*
X60704Y670495D01*
X60996Y670286D01*
X61079Y670036D01*
X61037Y669786D01*
X60871Y669578D01*
X60037Y669161D01*
X59662Y668870D01*
X59412Y668453D01*
X59329Y668078D01*
X61079D01*
G01X63304D02*
X63596Y668120D01*
X63929Y668245D01*
X64137Y668453D01*
X64221Y668745D01*
X64137Y669036D01*
X63887Y669286D01*
X63512Y669411D01*
X63096D01*
X62846Y669495D01*
X62637Y669703D01*
X62554Y669995D01*
X62679Y670286D01*
X62971Y670495D01*
X63304Y670578D01*
X63637Y670495D01*
X63929Y670286D01*
X64054Y669995D01*
X63971Y669703D01*
X63762Y669495D01*
X63512Y669411D01*
X63096D01*
X62721Y669286D01*
X62471Y669036D01*
X62387Y668745D01*
X62471Y668453D01*
X62679Y668245D01*
X63012Y668120D01*
X63304Y668078D01*
G01X66904D02*
Y670578D01*
X65362Y668786D01*
X67446D01*
G01X55049Y654487D02*
Y650487D01*
X62449D01*
G01X56271Y664078D02*
Y666578D01*
X57312D01*
X57646Y666453D01*
X57854Y666286D01*
X57937Y665953D01*
X57854Y665620D01*
X57604Y665411D01*
X57312Y665286D01*
X56271D01*
G01X57312D02*
X57937Y664078D01*
G01X59412Y666161D02*
X59662Y666411D01*
X59954Y666536D01*
X60287Y666578D01*
X60704Y666495D01*
X60996Y666286D01*
X61079Y666036D01*
X61037Y665786D01*
X60871Y665578D01*
X60037Y665161D01*
X59662Y664870D01*
X59412Y664453D01*
X59329Y664078D01*
X61079D01*
G01X63304D02*
X63596Y664120D01*
X63929Y664245D01*
X64137Y664453D01*
X64221Y664745D01*
X64137Y665036D01*
X63887Y665286D01*
X63512Y665411D01*
X63096D01*
X62846Y665495D01*
X62637Y665703D01*
X62554Y665995D01*
X62679Y666286D01*
X62971Y666495D01*
X63304Y666578D01*
X63637Y666495D01*
X63929Y666286D01*
X64054Y665995D01*
X63971Y665703D01*
X63762Y665495D01*
X63512Y665411D01*
X63096D01*
X62721Y665286D01*
X62471Y665036D01*
X62387Y664745D01*
X62471Y664453D01*
X62679Y664245D01*
X63012Y664120D01*
X63304Y664078D01*
G01X65612Y665120D02*
X65904Y665411D01*
X66154Y665578D01*
X66487Y665661D01*
X66779Y665578D01*
X66987Y665411D01*
X67154Y665161D01*
X67196Y664870D01*
X67154Y664620D01*
X66987Y664370D01*
X66737Y664161D01*
X66446Y664078D01*
X66112Y664161D01*
X65821Y664411D01*
X65654Y664786D01*
X65612Y665203D01*
X65696Y665745D01*
X65821Y666036D01*
X66029Y666328D01*
X66321Y666536D01*
X66612Y666578D01*
X66904Y666495D01*
X67112Y666286D01*
G01X55049Y650487D02*
Y646487D01*
X62449D01*
G01X41570Y648047D02*
Y650547D01*
X42611D01*
X42945Y650422D01*
X43153Y650255D01*
X43236Y649922D01*
X43153Y649589D01*
X42903Y649380D01*
X42611Y649255D01*
X41570D01*
G01X42611D02*
X43236Y648047D01*
G01X44586Y648547D02*
X44836Y648255D01*
X45170Y648089D01*
X45545Y648047D01*
X45878Y648089D01*
X46211Y648297D01*
X46420Y648547D01*
X46461Y648797D01*
X46378Y649089D01*
X46086Y649297D01*
X45795Y649380D01*
X45420D01*
G01X45795D02*
X46045Y649505D01*
X46253Y649714D01*
X46336Y649964D01*
X46253Y650214D01*
X46045Y650422D01*
X45670Y650547D01*
X45295Y650505D01*
X44920Y650339D01*
G01X47811Y649089D02*
X48103Y649380D01*
X48353Y649547D01*
X48686Y649630D01*
X48978Y649547D01*
X49186Y649380D01*
X49353Y649130D01*
X49395Y648839D01*
X49353Y648589D01*
X49186Y648339D01*
X48936Y648130D01*
X48645Y648047D01*
X48311Y648130D01*
X48020Y648380D01*
X47853Y648755D01*
X47811Y649172D01*
X47895Y649714D01*
X48020Y650005D01*
X48228Y650297D01*
X48520Y650505D01*
X48811Y650547D01*
X49103Y650464D01*
X49311Y650255D01*
G01X51703Y650547D02*
X51370Y650464D01*
X51120Y650255D01*
X50953Y650005D01*
X50828Y649672D01*
X50786Y649297D01*
X50828Y648922D01*
X50953Y648589D01*
X51120Y648339D01*
X51370Y648130D01*
X51703Y648047D01*
X52036Y648130D01*
X52286Y648339D01*
X52453Y648589D01*
X52578Y648922D01*
X52620Y649297D01*
X52578Y649672D01*
X52453Y650005D01*
X52286Y650255D01*
X52036Y650464D01*
X51703Y650547D01*
G01X52900Y701000D02*
Y698500D01*
G01X51942Y701000D02*
X53858D01*
G01X56917Y700792D02*
X56667Y700917D01*
X56375Y701000D01*
X56042D01*
X55667Y700875D01*
X55375Y700667D01*
X55167Y700417D01*
X55000Y700000D01*
X54958Y699625D01*
X55042Y699250D01*
X55167Y699000D01*
X55417Y698750D01*
X55708Y698583D01*
X56000Y698500D01*
X56292D01*
X56583Y698583D01*
X56833Y698708D01*
X57042Y698875D01*
G01X58308Y700583D02*
X58558Y700833D01*
X58850Y700958D01*
X59183Y701000D01*
X59600Y700917D01*
X59892Y700708D01*
X59975Y700458D01*
X59933Y700208D01*
X59767Y700000D01*
X58933Y699583D01*
X58558Y699292D01*
X58308Y698875D01*
X58225Y698500D01*
X59975D01*
G01X37800Y710500D02*
X49000D01*
G01X37800Y728500D02*
Y710500D01*
G01X49000Y728500D02*
X37800D01*
G01X76200Y710500D02*
X65000D01*
G01X76200Y728500D02*
Y710500D01*
G01X65000Y728500D02*
X76200D01*
G01X79900Y653000D02*
X79567Y653042D01*
X79275Y653208D01*
X79025Y653458D01*
X78858Y653750D01*
X78775Y654083D01*
Y654417D01*
X78858Y654750D01*
X79025Y655042D01*
X79275Y655292D01*
X79567Y655458D01*
X79900Y655500D01*
X80233Y655458D01*
X80525Y655292D01*
X80775Y655042D01*
X80942Y654750D01*
X81025Y654417D01*
Y654083D01*
X80942Y653750D01*
X80775Y653458D01*
X80525Y653208D01*
X80233Y653042D01*
X79900Y653000D01*
G01X80233Y653667D02*
X80733Y653000D01*
G01X83500D02*
Y655500D01*
X81958Y653708D01*
X84042D01*
G01X86017Y653000D02*
X86100Y653542D01*
X86225Y654000D01*
X86392Y654417D01*
X86600Y654875D01*
X86933Y655500D01*
X85267D01*
G01X77299Y658400D02*
X63299D01*
G01X51767Y747792D02*
X51517Y747917D01*
X51225Y748000D01*
X50892D01*
X50517Y747875D01*
X50225Y747667D01*
X50017Y747417D01*
X49850Y747000D01*
X49808Y746625D01*
X49892Y746250D01*
X50017Y746000D01*
X50267Y745750D01*
X50558Y745583D01*
X50850Y745500D01*
X51142D01*
X51433Y745583D01*
X51683Y745708D01*
X51892Y745875D01*
G01X53033Y746000D02*
X53283Y745708D01*
X53617Y745542D01*
X53992Y745500D01*
X54325Y745542D01*
X54658Y745750D01*
X54867Y746000D01*
X54908Y746250D01*
X54825Y746542D01*
X54533Y746750D01*
X54242Y746833D01*
X53867D01*
G01X54242D02*
X54492Y746958D01*
X54700Y747167D01*
X54783Y747417D01*
X54700Y747667D01*
X54492Y747875D01*
X54117Y748000D01*
X53742Y747958D01*
X53367Y747792D01*
G01X56133Y745875D02*
X56383Y745667D01*
X56675Y745542D01*
X57050Y745500D01*
X57425Y745583D01*
X57717Y745750D01*
X57925Y746042D01*
X57967Y746375D01*
X57883Y746708D01*
X57675Y746917D01*
X57383Y747083D01*
X57092Y747125D01*
X56800Y747083D01*
X56425Y746917D01*
X56550Y748000D01*
X57675D01*
G01X60150Y745500D02*
Y748000D01*
X59650Y747500D01*
G01Y745500D02*
X60650D01*
G01X30708Y807380D02*
X30583Y807130D01*
X30500Y806838D01*
Y806505D01*
X30625Y806130D01*
X30833Y805838D01*
X31083Y805630D01*
X31500Y805463D01*
X31875Y805421D01*
X32250Y805505D01*
X32500Y805630D01*
X32750Y805880D01*
X32917Y806171D01*
X33000Y806463D01*
Y806755D01*
X32917Y807046D01*
X32792Y807296D01*
X32625Y807505D01*
G01X33000Y808605D02*
X30500D01*
X33000Y810521D01*
X30500D01*
G01X31958Y811871D02*
X31667Y812163D01*
X31500Y812413D01*
X31417Y812746D01*
X31500Y813038D01*
X31667Y813246D01*
X31917Y813413D01*
X32208Y813455D01*
X32458Y813413D01*
X32708Y813246D01*
X32917Y812996D01*
X33000Y812705D01*
X32917Y812371D01*
X32667Y812080D01*
X32292Y811913D01*
X31875Y811871D01*
X31333Y811955D01*
X31042Y812080D01*
X30750Y812288D01*
X30542Y812580D01*
X30500Y812871D01*
X30583Y813163D01*
X30792Y813371D01*
G01X28499Y854400D02*
X30999D01*
G01X28499Y853442D02*
Y855358D01*
G01X30999Y856667D02*
X28499D01*
Y857667D01*
X28624Y858000D01*
X28916Y858250D01*
X29249Y858333D01*
X29582Y858250D01*
X29832Y858042D01*
X29957Y857667D01*
Y856667D01*
G01X30999Y860600D02*
X28499D01*
X28999Y860100D01*
G01X30999D02*
Y861100D01*
G01Y863617D02*
X30457Y863700D01*
X29999Y863825D01*
X29582Y863992D01*
X29124Y864200D01*
X28499Y864533D01*
Y862867D01*
G01X91598Y995285D02*
Y834085D01*
X77998D01*
Y821135D01*
X59798D01*
Y834085D01*
X30898D01*
Y844435D01*
X37598D01*
Y984935D01*
X30898D01*
Y995285D01*
X59798D01*
Y1008235D01*
X77998D01*
Y995285D01*
X91598D01*
G01X22917Y935300D02*
Y937800D01*
X23958D01*
X24292Y937675D01*
X24500Y937508D01*
X24583Y937175D01*
X24500Y936842D01*
X24250Y936633D01*
X23958Y936508D01*
X22917D01*
G01X23958D02*
X24583Y935300D01*
G01X26058Y936342D02*
X26350Y936633D01*
X26600Y936800D01*
X26933Y936883D01*
X27225Y936800D01*
X27433Y936633D01*
X27600Y936383D01*
X27642Y936092D01*
X27600Y935842D01*
X27433Y935592D01*
X27183Y935383D01*
X26892Y935300D01*
X26558Y935383D01*
X26267Y935633D01*
X26100Y936008D01*
X26058Y936425D01*
X26142Y936967D01*
X26267Y937258D01*
X26475Y937550D01*
X26767Y937758D01*
X27058Y937800D01*
X27350Y937717D01*
X27558Y937508D01*
G01X29950Y937800D02*
X29617Y937717D01*
X29367Y937508D01*
X29200Y937258D01*
X29075Y936925D01*
X29033Y936550D01*
X29075Y936175D01*
X29200Y935842D01*
X29367Y935592D01*
X29617Y935383D01*
X29950Y935300D01*
X30283Y935383D01*
X30533Y935592D01*
X30700Y935842D01*
X30825Y936175D01*
X30867Y936550D01*
X30825Y936925D01*
X30700Y937258D01*
X30533Y937508D01*
X30283Y937717D01*
X29950Y937800D01*
G01X32342Y935592D02*
X32633Y935383D01*
X32967Y935300D01*
X33300Y935383D01*
X33592Y935633D01*
X33800Y936008D01*
X33883Y936383D01*
Y936842D01*
X33800Y937217D01*
X33592Y937550D01*
X33342Y937717D01*
X33050Y937800D01*
X32717Y937717D01*
X32467Y937550D01*
X32300Y937300D01*
X32217Y936967D01*
X32300Y936675D01*
X32508Y936383D01*
X32758Y936217D01*
X33050Y936175D01*
X33383Y936258D01*
X33633Y936467D01*
X33883Y936842D01*
G01X21000Y899000D02*
X34000D01*
G01X21000Y925000D02*
Y899000D01*
G01X34000Y925000D02*
X21000D01*
G01X34000Y899000D02*
Y925000D01*
G01X47500Y1142500D02*
X57500D01*
G01Y1135500D02*
X47500D01*
G01X52500D02*
Y1142500D01*
G01X47500Y1132067D02*
X57500D01*
Y1128733D01*
X57000Y1127400D01*
X56333Y1126400D01*
X55333Y1125567D01*
X54166Y1124900D01*
X52500Y1124733D01*
X50833Y1124900D01*
X49667Y1125567D01*
X48666Y1126400D01*
X48000Y1127400D01*
X47500Y1128733D01*
Y1132067D01*
G01Y1121467D02*
X57500D01*
Y1118133D01*
X57000Y1116800D01*
X56333Y1115800D01*
X55333Y1114967D01*
X54166Y1114300D01*
X52500Y1114133D01*
X50833Y1114300D01*
X49667Y1114967D01*
X48666Y1115800D01*
X48000Y1116800D01*
X47500Y1118133D01*
Y1121467D01*
G01Y1107200D02*
X57500D01*
X55500Y1109200D01*
G01X47500D02*
Y1105200D01*
G01X55833Y1099767D02*
X56833Y1098767D01*
X57333Y1097600D01*
X57500Y1096267D01*
X57167Y1094600D01*
X56333Y1093433D01*
X55333Y1093100D01*
X54333Y1093267D01*
X53500Y1093933D01*
X51833Y1097267D01*
X50667Y1098767D01*
X49000Y1099767D01*
X47500Y1100100D01*
Y1093100D01*
G01X44167Y1091000D02*
Y1081000D01*
G01X57500Y1078733D02*
X47500D01*
Y1072067D01*
G01Y1061467D02*
Y1068133D01*
X57500D01*
Y1061467D01*
G01X52667Y1064133D02*
Y1068133D01*
G01X47500Y1057867D02*
X57500D01*
Y1054533D01*
X57000Y1053200D01*
X56333Y1052200D01*
X55333Y1051367D01*
X54166Y1050700D01*
X52500Y1050533D01*
X50833Y1050700D01*
X49667Y1051367D01*
X48666Y1052200D01*
X48000Y1053200D01*
X47500Y1054533D01*
Y1057867D01*
G01X62967Y1035500D02*
Y1033000D01*
X64633D01*
G01X67733D02*
X66067D01*
Y1035500D01*
X67733D01*
G01X67067Y1034292D02*
X66067D01*
G01X69083Y1033000D02*
Y1035500D01*
X69917D01*
X70250Y1035375D01*
X70500Y1035208D01*
X70708Y1034958D01*
X70875Y1034667D01*
X70917Y1034250D01*
X70875Y1033833D01*
X70708Y1033542D01*
X70500Y1033292D01*
X70250Y1033125D01*
X69917Y1033000D01*
X69083D01*
G01X73100D02*
Y1035500D01*
X72600Y1035000D01*
G01Y1033000D02*
X73600D01*
G01X75283Y1033500D02*
X75533Y1033208D01*
X75867Y1033042D01*
X76242Y1033000D01*
X76575Y1033042D01*
X76908Y1033250D01*
X77117Y1033500D01*
X77158Y1033750D01*
X77075Y1034042D01*
X76783Y1034250D01*
X76492Y1034333D01*
X76117D01*
G01X76492D02*
X76742Y1034458D01*
X76950Y1034667D01*
X77033Y1034917D01*
X76950Y1035167D01*
X76742Y1035375D01*
X76367Y1035500D01*
X75992Y1035458D01*
X75617Y1035292D01*
G01X63198Y1015255D02*
Y1022855D01*
X74598D01*
Y1015255D01*
X63198D01*
G01X40951Y998915D02*
Y1001415D01*
X41992D01*
X42326Y1001290D01*
X42534Y1001123D01*
X42617Y1000790D01*
X42534Y1000457D01*
X42284Y1000248D01*
X41992Y1000123D01*
X40951D01*
G01X41992D02*
X42617Y998915D01*
G01X44092Y1000998D02*
X44342Y1001248D01*
X44634Y1001373D01*
X44967Y1001415D01*
X45384Y1001332D01*
X45676Y1001123D01*
X45759Y1000873D01*
X45717Y1000623D01*
X45551Y1000415D01*
X44717Y999998D01*
X44342Y999707D01*
X44092Y999290D01*
X44009Y998915D01*
X45759D01*
G01X47192Y999957D02*
X47484Y1000248D01*
X47734Y1000415D01*
X48067Y1000498D01*
X48359Y1000415D01*
X48567Y1000248D01*
X48734Y999998D01*
X48776Y999707D01*
X48734Y999457D01*
X48567Y999207D01*
X48317Y998998D01*
X48026Y998915D01*
X47692Y998998D01*
X47401Y999248D01*
X47234Y999623D01*
X47192Y1000040D01*
X47276Y1000582D01*
X47401Y1000873D01*
X47609Y1001165D01*
X47901Y1001373D01*
X48192Y1001415D01*
X48484Y1001332D01*
X48692Y1001123D01*
G01X51084Y998915D02*
X51376Y998957D01*
X51709Y999082D01*
X51917Y999290D01*
X52001Y999582D01*
X51917Y999873D01*
X51667Y1000123D01*
X51292Y1000248D01*
X50876D01*
X50626Y1000332D01*
X50417Y1000540D01*
X50334Y1000832D01*
X50459Y1001123D01*
X50751Y1001332D01*
X51084Y1001415D01*
X51417Y1001332D01*
X51709Y1001123D01*
X51834Y1000832D01*
X51751Y1000540D01*
X51542Y1000332D01*
X51292Y1000248D01*
X50876D01*
X50501Y1000123D01*
X50251Y999873D01*
X50167Y999582D01*
X50251Y999290D01*
X50459Y999082D01*
X50792Y998957D01*
X51084Y998915D01*
G01X61699Y1015050D02*
Y1019050D01*
X54299D01*
G01X83517Y1017000D02*
Y1019500D01*
X84558D01*
X84892Y1019375D01*
X85100Y1019208D01*
X85183Y1018875D01*
X85100Y1018542D01*
X84850Y1018333D01*
X84558Y1018208D01*
X83517D01*
G01X84558D02*
X85183Y1017000D01*
G01X86658Y1019083D02*
X86908Y1019333D01*
X87200Y1019458D01*
X87533Y1019500D01*
X87950Y1019417D01*
X88242Y1019208D01*
X88325Y1018958D01*
X88283Y1018708D01*
X88117Y1018500D01*
X87283Y1018083D01*
X86908Y1017792D01*
X86658Y1017375D01*
X86575Y1017000D01*
X88325D01*
G01X89758Y1018042D02*
X90050Y1018333D01*
X90300Y1018500D01*
X90633Y1018583D01*
X90925Y1018500D01*
X91133Y1018333D01*
X91300Y1018083D01*
X91342Y1017792D01*
X91300Y1017542D01*
X91133Y1017292D01*
X90883Y1017083D01*
X90592Y1017000D01*
X90258Y1017083D01*
X89967Y1017333D01*
X89800Y1017708D01*
X89758Y1018125D01*
X89842Y1018667D01*
X89967Y1018958D01*
X90175Y1019250D01*
X90467Y1019458D01*
X90758Y1019500D01*
X91050Y1019417D01*
X91258Y1019208D01*
G01X92942Y1017292D02*
X93233Y1017083D01*
X93567Y1017000D01*
X93900Y1017083D01*
X94192Y1017333D01*
X94400Y1017708D01*
X94483Y1018083D01*
Y1018542D01*
X94400Y1018917D01*
X94192Y1019250D01*
X93942Y1019417D01*
X93650Y1019500D01*
X93317Y1019417D01*
X93067Y1019250D01*
X92900Y1019000D01*
X92817Y1018667D01*
X92900Y1018375D01*
X93108Y1018083D01*
X93358Y1017917D01*
X93650Y1017875D01*
X93983Y1017958D01*
X94233Y1018167D01*
X94483Y1018542D01*
G01X86700Y1006500D02*
Y1010500D01*
X79300D01*
G01X40888Y1002915D02*
Y1005415D01*
X41929D01*
X42263Y1005290D01*
X42471Y1005123D01*
X42554Y1004790D01*
X42471Y1004457D01*
X42221Y1004248D01*
X41929Y1004123D01*
X40888D01*
G01X41929D02*
X42554Y1002915D01*
G01X44029Y1004998D02*
X44279Y1005248D01*
X44571Y1005373D01*
X44904Y1005415D01*
X45321Y1005332D01*
X45613Y1005123D01*
X45696Y1004873D01*
X45654Y1004623D01*
X45488Y1004415D01*
X44654Y1003998D01*
X44279Y1003707D01*
X44029Y1003290D01*
X43946Y1002915D01*
X45696D01*
G01X47838D02*
X47921Y1003457D01*
X48046Y1003915D01*
X48213Y1004332D01*
X48421Y1004790D01*
X48754Y1005415D01*
X47088D01*
G01X51021D02*
X50688Y1005332D01*
X50438Y1005123D01*
X50271Y1004873D01*
X50146Y1004540D01*
X50104Y1004165D01*
X50146Y1003790D01*
X50271Y1003457D01*
X50438Y1003207D01*
X50688Y1002998D01*
X51021Y1002915D01*
X51354Y1002998D01*
X51604Y1003207D01*
X51771Y1003457D01*
X51896Y1003790D01*
X51938Y1004165D01*
X51896Y1004540D01*
X51771Y1004873D01*
X51604Y1005123D01*
X51354Y1005332D01*
X51021Y1005415D01*
G01X61636Y1019050D02*
Y1023050D01*
X54236D01*
G01X83017Y1022500D02*
Y1025000D01*
X84058D01*
X84392Y1024875D01*
X84600Y1024708D01*
X84683Y1024375D01*
X84600Y1024042D01*
X84350Y1023833D01*
X84058Y1023708D01*
X83017D01*
G01X84058D02*
X84683Y1022500D01*
G01X86158Y1024583D02*
X86408Y1024833D01*
X86700Y1024958D01*
X87033Y1025000D01*
X87450Y1024917D01*
X87742Y1024708D01*
X87825Y1024458D01*
X87783Y1024208D01*
X87617Y1024000D01*
X86783Y1023583D01*
X86408Y1023292D01*
X86158Y1022875D01*
X86075Y1022500D01*
X87825D01*
G01X89967D02*
X90050Y1023042D01*
X90175Y1023500D01*
X90342Y1023917D01*
X90550Y1024375D01*
X90883Y1025000D01*
X89217D01*
G01X93150Y1022500D02*
Y1025000D01*
X92650Y1024500D01*
G01Y1022500D02*
X93650D01*
G01X77300Y1015000D02*
Y1011000D01*
X84700D01*
G01X40888Y1006915D02*
Y1009415D01*
X41929D01*
X42263Y1009290D01*
X42471Y1009123D01*
X42554Y1008790D01*
X42471Y1008457D01*
X42221Y1008248D01*
X41929Y1008123D01*
X40888D01*
G01X41929D02*
X42554Y1006915D01*
G01X44029Y1008998D02*
X44279Y1009248D01*
X44571Y1009373D01*
X44904Y1009415D01*
X45321Y1009332D01*
X45613Y1009123D01*
X45696Y1008873D01*
X45654Y1008623D01*
X45488Y1008415D01*
X44654Y1007998D01*
X44279Y1007707D01*
X44029Y1007290D01*
X43946Y1006915D01*
X45696D01*
G01X47838D02*
X47921Y1007457D01*
X48046Y1007915D01*
X48213Y1008332D01*
X48421Y1008790D01*
X48754Y1009415D01*
X47088D01*
G01X50229Y1008998D02*
X50479Y1009248D01*
X50771Y1009373D01*
X51104Y1009415D01*
X51521Y1009332D01*
X51813Y1009123D01*
X51896Y1008873D01*
X51854Y1008623D01*
X51688Y1008415D01*
X50854Y1007998D01*
X50479Y1007707D01*
X50229Y1007290D01*
X50146Y1006915D01*
X51896D01*
G01X61636Y1023050D02*
Y1027050D01*
X54236D01*
G01X91616Y1007450D02*
Y1009950D01*
X92657D01*
X92991Y1009825D01*
X93199Y1009658D01*
X93282Y1009325D01*
X93199Y1008992D01*
X92949Y1008783D01*
X92657Y1008658D01*
X91616D01*
G01X92657D02*
X93282Y1007450D01*
G01X94632Y1007950D02*
X94882Y1007658D01*
X95216Y1007492D01*
X95591Y1007450D01*
X95924Y1007492D01*
X96257Y1007700D01*
X96466Y1007950D01*
X96507Y1008200D01*
X96424Y1008492D01*
X96132Y1008700D01*
X95841Y1008783D01*
X95466D01*
G01X95841D02*
X96091Y1008908D01*
X96299Y1009117D01*
X96382Y1009367D01*
X96299Y1009617D01*
X96091Y1009825D01*
X95716Y1009950D01*
X95341Y1009908D01*
X94966Y1009742D01*
G01X98566Y1007450D02*
X98649Y1007992D01*
X98774Y1008450D01*
X98941Y1008867D01*
X99149Y1009325D01*
X99482Y1009950D01*
X97816D01*
G01X101749Y1007450D02*
Y1009950D01*
X101249Y1009450D01*
G01Y1007450D02*
X102249D01*
G01X81899Y1002450D02*
Y998450D01*
X89299D01*
G01X91616Y1011450D02*
Y1013950D01*
X92657D01*
X92991Y1013825D01*
X93199Y1013658D01*
X93282Y1013325D01*
X93199Y1012992D01*
X92949Y1012783D01*
X92657Y1012658D01*
X91616D01*
G01X92657D02*
X93282Y1011450D01*
G01X94632Y1011950D02*
X94882Y1011658D01*
X95216Y1011492D01*
X95591Y1011450D01*
X95924Y1011492D01*
X96257Y1011700D01*
X96466Y1011950D01*
X96507Y1012200D01*
X96424Y1012492D01*
X96132Y1012700D01*
X95841Y1012783D01*
X95466D01*
G01X95841D02*
X96091Y1012908D01*
X96299Y1013117D01*
X96382Y1013367D01*
X96299Y1013617D01*
X96091Y1013825D01*
X95716Y1013950D01*
X95341Y1013908D01*
X94966Y1013742D01*
G01X98566Y1011450D02*
X98649Y1011992D01*
X98774Y1012450D01*
X98941Y1012867D01*
X99149Y1013325D01*
X99482Y1013950D01*
X97816D01*
G01X100957Y1013533D02*
X101207Y1013783D01*
X101499Y1013908D01*
X101832Y1013950D01*
X102249Y1013867D01*
X102541Y1013658D01*
X102624Y1013408D01*
X102582Y1013158D01*
X102416Y1012950D01*
X101582Y1012533D01*
X101207Y1012242D01*
X100957Y1011825D01*
X100874Y1011450D01*
X102624D01*
G01X81899Y1006450D02*
Y1002450D01*
X89299D01*
G01X36000Y1063700D02*
X32000D01*
Y1056300D01*
G01X31599Y1049550D02*
Y1062550D01*
G01X17599Y1049550D02*
X31599D01*
G01X17599Y1062550D02*
Y1049550D01*
G01X48302Y1041227D02*
Y1043727D01*
G01X50052D02*
Y1041227D01*
G01Y1042477D02*
X48302D01*
G01X52194Y1041227D02*
X52277Y1041769D01*
X52402Y1042227D01*
X52569Y1042644D01*
X52777Y1043102D01*
X53110Y1043727D01*
X51444D01*
G01X69583Y1112100D02*
Y1114600D01*
X70417D01*
X70750Y1114475D01*
X71000Y1114308D01*
X71208Y1114058D01*
X71375Y1113767D01*
X71417Y1113350D01*
X71375Y1112933D01*
X71208Y1112642D01*
X71000Y1112392D01*
X70750Y1112225D01*
X70417Y1112100D01*
X69583D01*
G01X72683Y1112600D02*
X72933Y1112308D01*
X73267Y1112142D01*
X73642Y1112100D01*
X73975Y1112142D01*
X74308Y1112350D01*
X74517Y1112600D01*
X74558Y1112850D01*
X74475Y1113142D01*
X74183Y1113350D01*
X73892Y1113433D01*
X73517D01*
G01X73892D02*
X74142Y1113558D01*
X74350Y1113767D01*
X74433Y1114017D01*
X74350Y1114267D01*
X74142Y1114475D01*
X73767Y1114600D01*
X73392Y1114558D01*
X73017Y1114392D01*
G01X76700Y1114600D02*
X76367Y1114517D01*
X76117Y1114308D01*
X75950Y1114058D01*
X75825Y1113725D01*
X75783Y1113350D01*
X75825Y1112975D01*
X75950Y1112642D01*
X76117Y1112392D01*
X76367Y1112183D01*
X76700Y1112100D01*
X77033Y1112183D01*
X77283Y1112392D01*
X77450Y1112642D01*
X77575Y1112975D01*
X77617Y1113350D01*
X77575Y1113725D01*
X77450Y1114058D01*
X77283Y1114308D01*
X77033Y1114517D01*
X76700Y1114600D01*
G01X82000Y1116500D02*
X98100D01*
G01X82000Y1109500D02*
Y1116500D01*
G01X98100Y1109500D02*
X82000D01*
G01X77767Y1088792D02*
X77517Y1088917D01*
X77225Y1089000D01*
X76892D01*
X76517Y1088875D01*
X76225Y1088667D01*
X76017Y1088417D01*
X75850Y1088000D01*
X75808Y1087625D01*
X75892Y1087250D01*
X76017Y1087000D01*
X76267Y1086750D01*
X76558Y1086583D01*
X76850Y1086500D01*
X77142D01*
X77433Y1086583D01*
X77683Y1086708D01*
X77892Y1086875D01*
G01X79158Y1088583D02*
X79408Y1088833D01*
X79700Y1088958D01*
X80033Y1089000D01*
X80450Y1088917D01*
X80742Y1088708D01*
X80825Y1088458D01*
X80783Y1088208D01*
X80617Y1088000D01*
X79783Y1087583D01*
X79408Y1087292D01*
X79158Y1086875D01*
X79075Y1086500D01*
X80825D01*
G01X83050D02*
Y1089000D01*
X82550Y1088500D01*
G01Y1086500D02*
X83550D01*
G01X85442Y1086792D02*
X85733Y1086583D01*
X86067Y1086500D01*
X86400Y1086583D01*
X86692Y1086833D01*
X86900Y1087208D01*
X86983Y1087583D01*
Y1088042D01*
X86900Y1088417D01*
X86692Y1088750D01*
X86442Y1088917D01*
X86150Y1089000D01*
X85817Y1088917D01*
X85567Y1088750D01*
X85400Y1088500D01*
X85317Y1088167D01*
X85400Y1087875D01*
X85608Y1087583D01*
X85858Y1087417D01*
X86150Y1087375D01*
X86483Y1087458D01*
X86733Y1087667D01*
X86983Y1088042D01*
G01X77267Y1093292D02*
X77017Y1093417D01*
X76725Y1093500D01*
X76392D01*
X76017Y1093375D01*
X75725Y1093167D01*
X75517Y1092917D01*
X75350Y1092500D01*
X75308Y1092125D01*
X75392Y1091750D01*
X75517Y1091500D01*
X75767Y1091250D01*
X76058Y1091083D01*
X76350Y1091000D01*
X76642D01*
X76933Y1091083D01*
X77183Y1091208D01*
X77392Y1091375D01*
G01X78658Y1093083D02*
X78908Y1093333D01*
X79200Y1093458D01*
X79533Y1093500D01*
X79950Y1093417D01*
X80242Y1093208D01*
X80325Y1092958D01*
X80283Y1092708D01*
X80117Y1092500D01*
X79283Y1092083D01*
X78908Y1091792D01*
X78658Y1091375D01*
X78575Y1091000D01*
X80325D01*
G01X82550D02*
Y1093500D01*
X82050Y1093000D01*
G01Y1091000D02*
X83050D01*
G01X84733Y1091500D02*
X84983Y1091208D01*
X85317Y1091042D01*
X85692Y1091000D01*
X86025Y1091042D01*
X86358Y1091250D01*
X86567Y1091500D01*
X86608Y1091750D01*
X86525Y1092042D01*
X86233Y1092250D01*
X85942Y1092333D01*
X85567D01*
G01X85942D02*
X86192Y1092458D01*
X86400Y1092667D01*
X86483Y1092917D01*
X86400Y1093167D01*
X86192Y1093375D01*
X85817Y1093500D01*
X85442Y1093458D01*
X85067Y1093292D01*
G01X27967Y1098692D02*
X27717Y1098817D01*
X27425Y1098900D01*
X27092D01*
X26717Y1098775D01*
X26425Y1098567D01*
X26217Y1098317D01*
X26050Y1097900D01*
X26008Y1097525D01*
X26092Y1097150D01*
X26217Y1096900D01*
X26467Y1096650D01*
X26758Y1096483D01*
X27050Y1096400D01*
X27342D01*
X27633Y1096483D01*
X27883Y1096608D01*
X28092Y1096775D01*
G01X30150Y1096400D02*
Y1098900D01*
X29650Y1098400D01*
G01Y1096400D02*
X30650D01*
G01X33750D02*
Y1098900D01*
X32208Y1097108D01*
X34292D01*
G01X36350Y1096400D02*
X36642Y1096442D01*
X36975Y1096567D01*
X37183Y1096775D01*
X37267Y1097067D01*
X37183Y1097358D01*
X36933Y1097608D01*
X36558Y1097733D01*
X36142D01*
X35892Y1097817D01*
X35683Y1098025D01*
X35600Y1098317D01*
X35725Y1098608D01*
X36017Y1098817D01*
X36350Y1098900D01*
X36683Y1098817D01*
X36975Y1098608D01*
X37100Y1098317D01*
X37017Y1098025D01*
X36808Y1097817D01*
X36558Y1097733D01*
X36142D01*
X35767Y1097608D01*
X35517Y1097358D01*
X35433Y1097067D01*
X35517Y1096775D01*
X35725Y1096567D01*
X36058Y1096442D01*
X36350Y1096400D01*
G01X27967Y1103692D02*
X27717Y1103817D01*
X27425Y1103900D01*
X27092D01*
X26717Y1103775D01*
X26425Y1103567D01*
X26217Y1103317D01*
X26050Y1102900D01*
X26008Y1102525D01*
X26092Y1102150D01*
X26217Y1101900D01*
X26467Y1101650D01*
X26758Y1101483D01*
X27050Y1101400D01*
X27342D01*
X27633Y1101483D01*
X27883Y1101608D01*
X28092Y1101775D01*
G01X30150Y1101400D02*
Y1103900D01*
X29650Y1103400D01*
G01Y1101400D02*
X30650D01*
G01X32458Y1103483D02*
X32708Y1103733D01*
X33000Y1103858D01*
X33333Y1103900D01*
X33750Y1103817D01*
X34042Y1103608D01*
X34125Y1103358D01*
X34083Y1103108D01*
X33917Y1102900D01*
X33083Y1102483D01*
X32708Y1102192D01*
X32458Y1101775D01*
X32375Y1101400D01*
X34125D01*
G01X36850D02*
Y1103900D01*
X35308Y1102108D01*
X37392D01*
G01X25000Y1064000D02*
Y1090000D01*
G01X68017Y1100000D02*
Y1102500D01*
X69058D01*
X69392Y1102375D01*
X69600Y1102208D01*
X69683Y1101875D01*
X69600Y1101542D01*
X69350Y1101333D01*
X69058Y1101208D01*
X68017D01*
G01X69058D02*
X69683Y1100000D01*
G01X71158Y1102083D02*
X71408Y1102333D01*
X71700Y1102458D01*
X72033Y1102500D01*
X72450Y1102417D01*
X72742Y1102208D01*
X72825Y1101958D01*
X72783Y1101708D01*
X72617Y1101500D01*
X71783Y1101083D01*
X71408Y1100792D01*
X71158Y1100375D01*
X71075Y1100000D01*
X72825D01*
G01X75050Y1102500D02*
X74717Y1102417D01*
X74467Y1102208D01*
X74300Y1101958D01*
X74175Y1101625D01*
X74133Y1101250D01*
X74175Y1100875D01*
X74300Y1100542D01*
X74467Y1100292D01*
X74717Y1100083D01*
X75050Y1100000D01*
X75383Y1100083D01*
X75633Y1100292D01*
X75800Y1100542D01*
X75925Y1100875D01*
X75967Y1101250D01*
X75925Y1101625D01*
X75800Y1101958D01*
X75633Y1102208D01*
X75383Y1102417D01*
X75050Y1102500D01*
G01X78650Y1100000D02*
Y1102500D01*
X77108Y1100708D01*
X79192D01*
G01X83999Y1071567D02*
X81499D01*
Y1072608D01*
X81624Y1072942D01*
X81791Y1073150D01*
X82124Y1073233D01*
X82457Y1073150D01*
X82666Y1072900D01*
X82791Y1072608D01*
Y1071567D01*
G01Y1072608D02*
X83999Y1073233D01*
G01X81916Y1074708D02*
X81666Y1074958D01*
X81541Y1075250D01*
X81499Y1075583D01*
X81582Y1076000D01*
X81791Y1076292D01*
X82041Y1076375D01*
X82291Y1076333D01*
X82499Y1076167D01*
X82916Y1075333D01*
X83207Y1074958D01*
X83624Y1074708D01*
X83999Y1074625D01*
Y1076375D01*
G01X81499Y1078600D02*
X81582Y1078267D01*
X81791Y1078017D01*
X82041Y1077850D01*
X82374Y1077725D01*
X82749Y1077683D01*
X83124Y1077725D01*
X83457Y1077850D01*
X83707Y1078017D01*
X83916Y1078267D01*
X83999Y1078600D01*
X83916Y1078933D01*
X83707Y1079183D01*
X83457Y1079350D01*
X83124Y1079475D01*
X82749Y1079517D01*
X82374Y1079475D01*
X82041Y1079350D01*
X81791Y1079183D01*
X81582Y1078933D01*
X81499Y1078600D01*
G01X82957Y1080908D02*
X82666Y1081200D01*
X82499Y1081450D01*
X82416Y1081783D01*
X82499Y1082075D01*
X82666Y1082283D01*
X82916Y1082450D01*
X83207Y1082492D01*
X83457Y1082450D01*
X83707Y1082283D01*
X83916Y1082033D01*
X83999Y1081742D01*
X83916Y1081408D01*
X83666Y1081117D01*
X83291Y1080950D01*
X82874Y1080908D01*
X82332Y1080992D01*
X82041Y1081117D01*
X81749Y1081325D01*
X81541Y1081617D01*
X81499Y1081908D01*
X81582Y1082200D01*
X81791Y1082408D01*
G01X87999Y1071567D02*
X85499D01*
Y1072608D01*
X85624Y1072942D01*
X85791Y1073150D01*
X86124Y1073233D01*
X86457Y1073150D01*
X86666Y1072900D01*
X86791Y1072608D01*
Y1071567D01*
G01Y1072608D02*
X87999Y1073233D01*
G01X85916Y1074708D02*
X85666Y1074958D01*
X85541Y1075250D01*
X85499Y1075583D01*
X85582Y1076000D01*
X85791Y1076292D01*
X86041Y1076375D01*
X86291Y1076333D01*
X86499Y1076167D01*
X86916Y1075333D01*
X87207Y1074958D01*
X87624Y1074708D01*
X87999Y1074625D01*
Y1076375D01*
G01Y1078600D02*
X85499D01*
X85999Y1078100D01*
G01X87999D02*
Y1079100D01*
G01Y1081700D02*
X85499D01*
X85999Y1081200D01*
G01X87999D02*
Y1082200D01*
G01X92116Y1070700D02*
Y1073200D01*
X93157D01*
X93491Y1073075D01*
X93699Y1072908D01*
X93782Y1072575D01*
X93699Y1072242D01*
X93449Y1072033D01*
X93157Y1071908D01*
X92116D01*
G01X93157D02*
X93782Y1070700D01*
G01X96549D02*
Y1073200D01*
X95007Y1071408D01*
X97091D01*
G01X98441Y1070992D02*
X98732Y1070783D01*
X99066Y1070700D01*
X99399Y1070783D01*
X99691Y1071033D01*
X99899Y1071408D01*
X99982Y1071783D01*
Y1072242D01*
X99899Y1072617D01*
X99691Y1072950D01*
X99441Y1073117D01*
X99149Y1073200D01*
X98816Y1073117D01*
X98566Y1072950D01*
X98399Y1072700D01*
X98316Y1072367D01*
X98399Y1072075D01*
X98607Y1071783D01*
X98857Y1071617D01*
X99149Y1071575D01*
X99482Y1071658D01*
X99732Y1071867D01*
X99982Y1072242D01*
G01X101332Y1071075D02*
X101582Y1070867D01*
X101874Y1070742D01*
X102249Y1070700D01*
X102624Y1070783D01*
X102916Y1070950D01*
X103124Y1071242D01*
X103166Y1071575D01*
X103082Y1071908D01*
X102874Y1072117D01*
X102582Y1072283D01*
X102291Y1072325D01*
X101999Y1072283D01*
X101624Y1072117D01*
X101749Y1073200D01*
X102874D01*
G01X92116Y1066400D02*
Y1068900D01*
X93157D01*
X93491Y1068775D01*
X93699Y1068608D01*
X93782Y1068275D01*
X93699Y1067942D01*
X93449Y1067733D01*
X93157Y1067608D01*
X92116D01*
G01X93157D02*
X93782Y1066400D01*
G01X96549D02*
Y1068900D01*
X95007Y1067108D01*
X97091D01*
G01X98441Y1066692D02*
X98732Y1066483D01*
X99066Y1066400D01*
X99399Y1066483D01*
X99691Y1066733D01*
X99899Y1067108D01*
X99982Y1067483D01*
Y1067942D01*
X99899Y1068317D01*
X99691Y1068650D01*
X99441Y1068817D01*
X99149Y1068900D01*
X98816Y1068817D01*
X98566Y1068650D01*
X98399Y1068400D01*
X98316Y1068067D01*
X98399Y1067775D01*
X98607Y1067483D01*
X98857Y1067317D01*
X99149Y1067275D01*
X99482Y1067358D01*
X99732Y1067567D01*
X99982Y1067942D01*
G01X102749Y1066400D02*
Y1068900D01*
X101207Y1067108D01*
X103291D01*
G01X35200Y1067017D02*
X32700D01*
Y1068058D01*
X32825Y1068392D01*
X32992Y1068600D01*
X33325Y1068683D01*
X33658Y1068600D01*
X33867Y1068350D01*
X33992Y1068058D01*
Y1067017D01*
G01Y1068058D02*
X35200Y1068683D01*
G01X34825Y1070033D02*
X35033Y1070283D01*
X35158Y1070575D01*
X35200Y1070950D01*
X35117Y1071325D01*
X34950Y1071617D01*
X34658Y1071825D01*
X34325Y1071867D01*
X33992Y1071783D01*
X33783Y1071575D01*
X33617Y1071283D01*
X33575Y1070992D01*
X33617Y1070700D01*
X33783Y1070325D01*
X32700Y1070450D01*
Y1071575D01*
G01Y1074050D02*
X32783Y1073717D01*
X32992Y1073467D01*
X33242Y1073300D01*
X33575Y1073175D01*
X33950Y1073133D01*
X34325Y1073175D01*
X34658Y1073300D01*
X34908Y1073467D01*
X35117Y1073717D01*
X35200Y1074050D01*
X35117Y1074383D01*
X34908Y1074633D01*
X34658Y1074800D01*
X34325Y1074925D01*
X33950Y1074967D01*
X33575Y1074925D01*
X33242Y1074800D01*
X32992Y1074633D01*
X32783Y1074383D01*
X32700Y1074050D01*
G01X33117Y1076358D02*
X32867Y1076608D01*
X32742Y1076900D01*
X32700Y1077233D01*
X32783Y1077650D01*
X32992Y1077942D01*
X33242Y1078025D01*
X33492Y1077983D01*
X33700Y1077817D01*
X34117Y1076983D01*
X34408Y1076608D01*
X34825Y1076358D01*
X35200Y1076275D01*
Y1078025D01*
G01X67517Y1104800D02*
Y1107300D01*
X68558D01*
X68892Y1107175D01*
X69100Y1107008D01*
X69183Y1106675D01*
X69100Y1106342D01*
X68850Y1106133D01*
X68558Y1106008D01*
X67517D01*
G01X68558D02*
X69183Y1104800D01*
G01X71950D02*
Y1107300D01*
X70408Y1105508D01*
X72492D01*
G01X74550Y1104800D02*
Y1107300D01*
X74050Y1106800D01*
G01Y1104800D02*
X75050D01*
G01X76733Y1105175D02*
X76983Y1104967D01*
X77275Y1104842D01*
X77650Y1104800D01*
X78025Y1104883D01*
X78317Y1105050D01*
X78525Y1105342D01*
X78567Y1105675D01*
X78483Y1106008D01*
X78275Y1106217D01*
X77983Y1106383D01*
X77692Y1106425D01*
X77400Y1106383D01*
X77025Y1106217D01*
X77150Y1107300D01*
X78275D01*
G01X95183Y1097400D02*
Y1095608D01*
X95350Y1095233D01*
X95683Y1094983D01*
X96100Y1094900D01*
X96517Y1094983D01*
X96850Y1095233D01*
X97017Y1095608D01*
Y1097400D01*
G01X98408Y1096983D02*
X98658Y1097233D01*
X98950Y1097358D01*
X99283Y1097400D01*
X99700Y1097317D01*
X99992Y1097108D01*
X100075Y1096858D01*
X100033Y1096608D01*
X99867Y1096400D01*
X99033Y1095983D01*
X98658Y1095692D01*
X98408Y1095275D01*
X98325Y1094900D01*
X100075D01*
G01X102800D02*
Y1097400D01*
X101258Y1095608D01*
X103342D01*
G01X70274Y1134677D02*
Y1132885D01*
X70441Y1132510D01*
X70774Y1132260D01*
X71191Y1132177D01*
X71608Y1132260D01*
X71941Y1132510D01*
X72108Y1132885D01*
Y1134677D01*
G01X73499Y1134260D02*
X73749Y1134510D01*
X74041Y1134635D01*
X74374Y1134677D01*
X74791Y1134594D01*
X75083Y1134385D01*
X75166Y1134135D01*
X75124Y1133885D01*
X74958Y1133677D01*
X74124Y1133260D01*
X73749Y1132969D01*
X73499Y1132552D01*
X73416Y1132177D01*
X75166D01*
G01X76474Y1132677D02*
X76724Y1132385D01*
X77058Y1132219D01*
X77433Y1132177D01*
X77766Y1132219D01*
X78099Y1132427D01*
X78308Y1132677D01*
X78349Y1132927D01*
X78266Y1133219D01*
X77974Y1133427D01*
X77683Y1133510D01*
X77308D01*
G01X77683D02*
X77933Y1133635D01*
X78141Y1133844D01*
X78224Y1134094D01*
X78141Y1134344D01*
X77933Y1134552D01*
X77558Y1134677D01*
X77183Y1134635D01*
X76808Y1134469D01*
G01X92999Y1117750D02*
X94999Y1119750D01*
X96999Y1117750D01*
G01X100599D02*
Y1136950D01*
X89399D01*
Y1117750D01*
X100599D01*
G01X31599Y1062550D02*
X17599D01*
G01X26717Y1116400D02*
Y1118900D01*
X27717D01*
X28050Y1118775D01*
X28300Y1118483D01*
X28383Y1118150D01*
X28300Y1117817D01*
X28092Y1117567D01*
X27717Y1117442D01*
X26717D01*
G01X31567Y1118692D02*
X31317Y1118817D01*
X31025Y1118900D01*
X30692D01*
X30317Y1118775D01*
X30025Y1118567D01*
X29817Y1118317D01*
X29650Y1117900D01*
X29608Y1117525D01*
X29692Y1117150D01*
X29817Y1116900D01*
X30067Y1116650D01*
X30358Y1116483D01*
X30650Y1116400D01*
X30942D01*
X31233Y1116483D01*
X31483Y1116608D01*
X31692Y1116775D01*
G01X32958Y1117442D02*
X33250Y1117733D01*
X33500Y1117900D01*
X33833Y1117983D01*
X34125Y1117900D01*
X34333Y1117733D01*
X34500Y1117483D01*
X34542Y1117192D01*
X34500Y1116942D01*
X34333Y1116692D01*
X34083Y1116483D01*
X33792Y1116400D01*
X33458Y1116483D01*
X33167Y1116733D01*
X33000Y1117108D01*
X32958Y1117525D01*
X33042Y1118067D01*
X33167Y1118358D01*
X33375Y1118650D01*
X33667Y1118858D01*
X33958Y1118900D01*
X34250Y1118817D01*
X34458Y1118608D01*
G01X36850Y1116400D02*
X37142Y1116442D01*
X37475Y1116567D01*
X37683Y1116775D01*
X37767Y1117067D01*
X37683Y1117358D01*
X37433Y1117608D01*
X37058Y1117733D01*
X36642D01*
X36392Y1117817D01*
X36183Y1118025D01*
X36100Y1118317D01*
X36225Y1118608D01*
X36517Y1118817D01*
X36850Y1118900D01*
X37183Y1118817D01*
X37475Y1118608D01*
X37600Y1118317D01*
X37517Y1118025D01*
X37308Y1117817D01*
X37058Y1117733D01*
X36642D01*
X36267Y1117608D01*
X36017Y1117358D01*
X35933Y1117067D01*
X36017Y1116775D01*
X36225Y1116567D01*
X36558Y1116442D01*
X36850Y1116400D01*
G01X26417Y1107800D02*
Y1110300D01*
X27417D01*
X27750Y1110175D01*
X28000Y1109883D01*
X28083Y1109550D01*
X28000Y1109217D01*
X27792Y1108967D01*
X27417Y1108842D01*
X26417D01*
G01X31267Y1110092D02*
X31017Y1110217D01*
X30725Y1110300D01*
X30392D01*
X30017Y1110175D01*
X29725Y1109967D01*
X29517Y1109717D01*
X29350Y1109300D01*
X29308Y1108925D01*
X29392Y1108550D01*
X29517Y1108300D01*
X29767Y1108050D01*
X30058Y1107883D01*
X30350Y1107800D01*
X30642D01*
X30933Y1107883D01*
X31183Y1108008D01*
X31392Y1108175D01*
G01X33950Y1107800D02*
Y1110300D01*
X32408Y1108508D01*
X34492D01*
G01X35758Y1108842D02*
X36050Y1109133D01*
X36300Y1109300D01*
X36633Y1109383D01*
X36925Y1109300D01*
X37133Y1109133D01*
X37300Y1108883D01*
X37342Y1108592D01*
X37300Y1108342D01*
X37133Y1108092D01*
X36883Y1107883D01*
X36592Y1107800D01*
X36258Y1107883D01*
X35967Y1108133D01*
X35800Y1108508D01*
X35758Y1108925D01*
X35842Y1109467D01*
X35967Y1109758D01*
X36175Y1110050D01*
X36467Y1110258D01*
X36758Y1110300D01*
X37050Y1110217D01*
X37258Y1110008D01*
G01X83150Y1227501D02*
X83025Y1227251D01*
X82942Y1226959D01*
Y1226626D01*
X83067Y1226251D01*
X83275Y1225959D01*
X83525Y1225751D01*
X83942Y1225584D01*
X84317Y1225542D01*
X84692Y1225626D01*
X84942Y1225751D01*
X85192Y1226001D01*
X85359Y1226292D01*
X85442Y1226584D01*
Y1226876D01*
X85359Y1227167D01*
X85234Y1227417D01*
X85067Y1227626D01*
G01X83359Y1228892D02*
X83109Y1229142D01*
X82984Y1229434D01*
X82942Y1229767D01*
X83025Y1230184D01*
X83234Y1230476D01*
X83484Y1230559D01*
X83734Y1230517D01*
X83942Y1230351D01*
X84359Y1229517D01*
X84650Y1229142D01*
X85067Y1228892D01*
X85442Y1228809D01*
Y1230559D01*
G01X85150Y1232076D02*
X85359Y1232367D01*
X85442Y1232701D01*
X85359Y1233034D01*
X85109Y1233326D01*
X84734Y1233534D01*
X84359Y1233617D01*
X83900D01*
X83525Y1233534D01*
X83192Y1233326D01*
X83025Y1233076D01*
X82942Y1232784D01*
X83025Y1232451D01*
X83192Y1232201D01*
X83442Y1232034D01*
X83775Y1231951D01*
X84067Y1232034D01*
X84359Y1232242D01*
X84525Y1232492D01*
X84567Y1232784D01*
X84484Y1233117D01*
X84275Y1233367D01*
X83900Y1233617D01*
G01X85442Y1235884D02*
X82942D01*
X83442Y1235384D01*
G01X85442D02*
Y1236384D01*
G01X83417Y1212065D02*
X80917D01*
Y1213106D01*
X81042Y1213440D01*
X81209Y1213648D01*
X81542Y1213731D01*
X81875Y1213648D01*
X82084Y1213398D01*
X82209Y1213106D01*
Y1212065D01*
G01Y1213106D02*
X83417Y1213731D01*
G01X81334Y1215206D02*
X81084Y1215456D01*
X80959Y1215748D01*
X80917Y1216081D01*
X81000Y1216498D01*
X81209Y1216790D01*
X81459Y1216873D01*
X81709Y1216831D01*
X81917Y1216665D01*
X82334Y1215831D01*
X82625Y1215456D01*
X83042Y1215206D01*
X83417Y1215123D01*
Y1216873D01*
G01X83042Y1218181D02*
X83250Y1218431D01*
X83375Y1218723D01*
X83417Y1219098D01*
X83334Y1219473D01*
X83167Y1219765D01*
X82875Y1219973D01*
X82542Y1220015D01*
X82209Y1219931D01*
X82000Y1219723D01*
X81834Y1219431D01*
X81792Y1219140D01*
X81834Y1218848D01*
X82000Y1218473D01*
X80917Y1218598D01*
Y1219723D01*
G01X83125Y1221490D02*
X83334Y1221781D01*
X83417Y1222115D01*
X83334Y1222448D01*
X83084Y1222740D01*
X82709Y1222948D01*
X82334Y1223031D01*
X81875D01*
X81500Y1222948D01*
X81167Y1222740D01*
X81000Y1222490D01*
X80917Y1222198D01*
X81000Y1221865D01*
X81167Y1221615D01*
X81417Y1221448D01*
X81750Y1221365D01*
X82042Y1221448D01*
X82334Y1221656D01*
X82500Y1221906D01*
X82542Y1222198D01*
X82459Y1222531D01*
X82250Y1222781D01*
X81875Y1223031D01*
G01X93917Y1212128D02*
X91417D01*
Y1213169D01*
X91542Y1213503D01*
X91709Y1213711D01*
X92042Y1213794D01*
X92375Y1213711D01*
X92584Y1213461D01*
X92709Y1213169D01*
Y1212128D01*
G01Y1213169D02*
X93917Y1213794D01*
G01X91834Y1215269D02*
X91584Y1215519D01*
X91459Y1215811D01*
X91417Y1216144D01*
X91500Y1216561D01*
X91709Y1216853D01*
X91959Y1216936D01*
X92209Y1216894D01*
X92417Y1216728D01*
X92834Y1215894D01*
X93125Y1215519D01*
X93542Y1215269D01*
X93917Y1215186D01*
Y1216936D01*
G01X92875Y1218369D02*
X92584Y1218661D01*
X92417Y1218911D01*
X92334Y1219244D01*
X92417Y1219536D01*
X92584Y1219744D01*
X92834Y1219911D01*
X93125Y1219953D01*
X93375Y1219911D01*
X93625Y1219744D01*
X93834Y1219494D01*
X93917Y1219203D01*
X93834Y1218869D01*
X93584Y1218578D01*
X93209Y1218411D01*
X92792Y1218369D01*
X92250Y1218453D01*
X91959Y1218578D01*
X91667Y1218786D01*
X91459Y1219078D01*
X91417Y1219369D01*
X91500Y1219661D01*
X91709Y1219869D01*
G01X93417Y1221344D02*
X93709Y1221594D01*
X93875Y1221928D01*
X93917Y1222303D01*
X93875Y1222636D01*
X93667Y1222969D01*
X93417Y1223178D01*
X93167Y1223219D01*
X92875Y1223136D01*
X92667Y1222844D01*
X92584Y1222553D01*
Y1222178D01*
G01Y1222553D02*
X92459Y1222803D01*
X92250Y1223011D01*
X92000Y1223094D01*
X91750Y1223011D01*
X91542Y1222803D01*
X91417Y1222428D01*
X91459Y1222053D01*
X91625Y1221678D01*
G01X90417Y1212128D02*
X87917D01*
Y1213169D01*
X88042Y1213503D01*
X88209Y1213711D01*
X88542Y1213794D01*
X88875Y1213711D01*
X89084Y1213461D01*
X89209Y1213169D01*
Y1212128D01*
G01Y1213169D02*
X90417Y1213794D01*
G01X88334Y1215269D02*
X88084Y1215519D01*
X87959Y1215811D01*
X87917Y1216144D01*
X88000Y1216561D01*
X88209Y1216853D01*
X88459Y1216936D01*
X88709Y1216894D01*
X88917Y1216728D01*
X89334Y1215894D01*
X89625Y1215519D01*
X90042Y1215269D01*
X90417Y1215186D01*
Y1216936D01*
G01X89375Y1218369D02*
X89084Y1218661D01*
X88917Y1218911D01*
X88834Y1219244D01*
X88917Y1219536D01*
X89084Y1219744D01*
X89334Y1219911D01*
X89625Y1219953D01*
X89875Y1219911D01*
X90125Y1219744D01*
X90334Y1219494D01*
X90417Y1219203D01*
X90334Y1218869D01*
X90084Y1218578D01*
X89709Y1218411D01*
X89292Y1218369D01*
X88750Y1218453D01*
X88459Y1218578D01*
X88167Y1218786D01*
X87959Y1219078D01*
X87917Y1219369D01*
X88000Y1219661D01*
X88209Y1219869D01*
G01X89375Y1221469D02*
X89084Y1221761D01*
X88917Y1222011D01*
X88834Y1222344D01*
X88917Y1222636D01*
X89084Y1222844D01*
X89334Y1223011D01*
X89625Y1223053D01*
X89875Y1223011D01*
X90125Y1222844D01*
X90334Y1222594D01*
X90417Y1222303D01*
X90334Y1221969D01*
X90084Y1221678D01*
X89709Y1221511D01*
X89292Y1221469D01*
X88750Y1221553D01*
X88459Y1221678D01*
X88167Y1221886D01*
X87959Y1222178D01*
X87917Y1222469D01*
X88000Y1222761D01*
X88209Y1222969D01*
G01X86917Y1212065D02*
X84417D01*
Y1213106D01*
X84542Y1213440D01*
X84709Y1213648D01*
X85042Y1213731D01*
X85375Y1213648D01*
X85584Y1213398D01*
X85709Y1213106D01*
Y1212065D01*
G01Y1213106D02*
X86917Y1213731D01*
G01X84834Y1215206D02*
X84584Y1215456D01*
X84459Y1215748D01*
X84417Y1216081D01*
X84500Y1216498D01*
X84709Y1216790D01*
X84959Y1216873D01*
X85209Y1216831D01*
X85417Y1216665D01*
X85834Y1215831D01*
X86125Y1215456D01*
X86542Y1215206D01*
X86917Y1215123D01*
Y1216873D01*
G01X85875Y1218306D02*
X85584Y1218598D01*
X85417Y1218848D01*
X85334Y1219181D01*
X85417Y1219473D01*
X85584Y1219681D01*
X85834Y1219848D01*
X86125Y1219890D01*
X86375Y1219848D01*
X86625Y1219681D01*
X86834Y1219431D01*
X86917Y1219140D01*
X86834Y1218806D01*
X86584Y1218515D01*
X86209Y1218348D01*
X85792Y1218306D01*
X85250Y1218390D01*
X84959Y1218515D01*
X84667Y1218723D01*
X84459Y1219015D01*
X84417Y1219306D01*
X84500Y1219598D01*
X84709Y1219806D01*
G01X86917Y1222115D02*
X86375Y1222198D01*
X85917Y1222323D01*
X85500Y1222490D01*
X85042Y1222698D01*
X84417Y1223031D01*
Y1221365D01*
G01X96836Y1196999D02*
X94336D01*
Y1198040D01*
X94461Y1198374D01*
X94628Y1198582D01*
X94961Y1198665D01*
X95294Y1198582D01*
X95503Y1198332D01*
X95628Y1198040D01*
Y1196999D01*
G01Y1198040D02*
X96836Y1198665D01*
G01Y1201432D02*
X94336D01*
X96128Y1199890D01*
Y1201974D01*
G01X95794Y1203240D02*
X95503Y1203532D01*
X95336Y1203782D01*
X95253Y1204115D01*
X95336Y1204407D01*
X95503Y1204615D01*
X95753Y1204782D01*
X96044Y1204824D01*
X96294Y1204782D01*
X96544Y1204615D01*
X96753Y1204365D01*
X96836Y1204074D01*
X96753Y1203740D01*
X96503Y1203449D01*
X96128Y1203282D01*
X95711Y1203240D01*
X95169Y1203324D01*
X94878Y1203449D01*
X94586Y1203657D01*
X94378Y1203949D01*
X94336Y1204240D01*
X94419Y1204532D01*
X94628Y1204740D01*
G01X95794Y1206340D02*
X95503Y1206632D01*
X95336Y1206882D01*
X95253Y1207215D01*
X95336Y1207507D01*
X95503Y1207715D01*
X95753Y1207882D01*
X96044Y1207924D01*
X96294Y1207882D01*
X96544Y1207715D01*
X96753Y1207465D01*
X96836Y1207174D01*
X96753Y1206840D01*
X96503Y1206549D01*
X96128Y1206382D01*
X95711Y1206340D01*
X95169Y1206424D01*
X94878Y1206549D01*
X94586Y1206757D01*
X94378Y1207049D01*
X94336Y1207340D01*
X94419Y1207632D01*
X94628Y1207840D01*
G01X92836Y1196999D02*
X90336D01*
Y1198040D01*
X90461Y1198374D01*
X90628Y1198582D01*
X90961Y1198665D01*
X91294Y1198582D01*
X91503Y1198332D01*
X91628Y1198040D01*
Y1196999D01*
G01Y1198040D02*
X92836Y1198665D01*
G01Y1201432D02*
X90336D01*
X92128Y1199890D01*
Y1201974D01*
G01X91794Y1203240D02*
X91503Y1203532D01*
X91336Y1203782D01*
X91253Y1204115D01*
X91336Y1204407D01*
X91503Y1204615D01*
X91753Y1204782D01*
X92044Y1204824D01*
X92294Y1204782D01*
X92544Y1204615D01*
X92753Y1204365D01*
X92836Y1204074D01*
X92753Y1203740D01*
X92503Y1203449D01*
X92128Y1203282D01*
X91711Y1203240D01*
X91169Y1203324D01*
X90878Y1203449D01*
X90586Y1203657D01*
X90378Y1203949D01*
X90336Y1204240D01*
X90419Y1204532D01*
X90628Y1204740D01*
G01X92836Y1207049D02*
X92294Y1207132D01*
X91836Y1207257D01*
X91419Y1207424D01*
X90961Y1207632D01*
X90336Y1207965D01*
Y1206299D01*
G01X29508Y1190317D02*
X29383Y1190067D01*
X29300Y1189775D01*
Y1189442D01*
X29425Y1189067D01*
X29633Y1188775D01*
X29883Y1188567D01*
X30300Y1188400D01*
X30675Y1188358D01*
X31050Y1188442D01*
X31300Y1188567D01*
X31550Y1188817D01*
X31717Y1189108D01*
X31800Y1189400D01*
Y1189692D01*
X31717Y1189983D01*
X31592Y1190233D01*
X31425Y1190442D01*
G01X31800Y1191542D02*
X29300D01*
X31800Y1193458D01*
X29300D01*
G01X31800Y1195600D02*
X31758Y1195892D01*
X31633Y1196225D01*
X31425Y1196433D01*
X31133Y1196517D01*
X30842Y1196433D01*
X30592Y1196183D01*
X30467Y1195808D01*
Y1195392D01*
X30383Y1195142D01*
X30175Y1194933D01*
X29883Y1194850D01*
X29592Y1194975D01*
X29383Y1195267D01*
X29300Y1195600D01*
X29383Y1195933D01*
X29592Y1196225D01*
X29883Y1196350D01*
X30175Y1196267D01*
X30383Y1196058D01*
X30467Y1195808D01*
Y1195392D01*
X30592Y1195017D01*
X30842Y1194767D01*
X31133Y1194683D01*
X31425Y1194767D01*
X31633Y1194975D01*
X31758Y1195308D01*
X31800Y1195600D01*
G01X95208Y1227767D02*
X95083Y1227517D01*
X95000Y1227225D01*
Y1226892D01*
X95125Y1226517D01*
X95333Y1226225D01*
X95583Y1226017D01*
X96000Y1225850D01*
X96375Y1225808D01*
X96750Y1225892D01*
X97000Y1226017D01*
X97250Y1226267D01*
X97417Y1226558D01*
X97500Y1226850D01*
Y1227142D01*
X97417Y1227433D01*
X97292Y1227683D01*
X97125Y1227892D01*
G01X95417Y1229158D02*
X95167Y1229408D01*
X95042Y1229700D01*
X95000Y1230033D01*
X95083Y1230450D01*
X95292Y1230742D01*
X95542Y1230825D01*
X95792Y1230783D01*
X96000Y1230617D01*
X96417Y1229783D01*
X96708Y1229408D01*
X97125Y1229158D01*
X97500Y1229075D01*
Y1230825D01*
G01Y1233050D02*
X97458Y1233342D01*
X97333Y1233675D01*
X97125Y1233883D01*
X96833Y1233967D01*
X96542Y1233883D01*
X96292Y1233633D01*
X96167Y1233258D01*
Y1232842D01*
X96083Y1232592D01*
X95875Y1232383D01*
X95583Y1232300D01*
X95292Y1232425D01*
X95083Y1232717D01*
X95000Y1233050D01*
X95083Y1233383D01*
X95292Y1233675D01*
X95583Y1233800D01*
X95875Y1233717D01*
X96083Y1233508D01*
X96167Y1233258D01*
Y1232842D01*
X96292Y1232467D01*
X96542Y1232217D01*
X96833Y1232133D01*
X97125Y1232217D01*
X97333Y1232425D01*
X97458Y1232758D01*
X97500Y1233050D01*
G01Y1236150D02*
X97458Y1236442D01*
X97333Y1236775D01*
X97125Y1236983D01*
X96833Y1237067D01*
X96542Y1236983D01*
X96292Y1236733D01*
X96167Y1236358D01*
Y1235942D01*
X96083Y1235692D01*
X95875Y1235483D01*
X95583Y1235400D01*
X95292Y1235525D01*
X95083Y1235817D01*
X95000Y1236150D01*
X95083Y1236483D01*
X95292Y1236775D01*
X95583Y1236900D01*
X95875Y1236817D01*
X96083Y1236608D01*
X96167Y1236358D01*
Y1235942D01*
X96292Y1235567D01*
X96542Y1235317D01*
X96833Y1235233D01*
X97125Y1235317D01*
X97333Y1235525D01*
X97458Y1235858D01*
X97500Y1236150D01*
G01X91208Y1227767D02*
X91083Y1227517D01*
X91000Y1227225D01*
Y1226892D01*
X91125Y1226517D01*
X91333Y1226225D01*
X91583Y1226017D01*
X92000Y1225850D01*
X92375Y1225808D01*
X92750Y1225892D01*
X93000Y1226017D01*
X93250Y1226267D01*
X93417Y1226558D01*
X93500Y1226850D01*
Y1227142D01*
X93417Y1227433D01*
X93292Y1227683D01*
X93125Y1227892D01*
G01X91417Y1229158D02*
X91167Y1229408D01*
X91042Y1229700D01*
X91000Y1230033D01*
X91083Y1230450D01*
X91292Y1230742D01*
X91542Y1230825D01*
X91792Y1230783D01*
X92000Y1230617D01*
X92417Y1229783D01*
X92708Y1229408D01*
X93125Y1229158D01*
X93500Y1229075D01*
Y1230825D01*
G01Y1233050D02*
X93458Y1233342D01*
X93333Y1233675D01*
X93125Y1233883D01*
X92833Y1233967D01*
X92542Y1233883D01*
X92292Y1233633D01*
X92167Y1233258D01*
Y1232842D01*
X92083Y1232592D01*
X91875Y1232383D01*
X91583Y1232300D01*
X91292Y1232425D01*
X91083Y1232717D01*
X91000Y1233050D01*
X91083Y1233383D01*
X91292Y1233675D01*
X91583Y1233800D01*
X91875Y1233717D01*
X92083Y1233508D01*
X92167Y1233258D01*
Y1232842D01*
X92292Y1232467D01*
X92542Y1232217D01*
X92833Y1232133D01*
X93125Y1232217D01*
X93333Y1232425D01*
X93458Y1232758D01*
X93500Y1233050D01*
G01X93208Y1235442D02*
X93417Y1235733D01*
X93500Y1236067D01*
X93417Y1236400D01*
X93167Y1236692D01*
X92792Y1236900D01*
X92417Y1236983D01*
X91958D01*
X91583Y1236900D01*
X91250Y1236692D01*
X91083Y1236442D01*
X91000Y1236150D01*
X91083Y1235817D01*
X91250Y1235567D01*
X91500Y1235400D01*
X91833Y1235317D01*
X92125Y1235400D01*
X92417Y1235608D01*
X92583Y1235858D01*
X92625Y1236150D01*
X92542Y1236483D01*
X92333Y1236733D01*
X91958Y1236983D01*
G01X87208Y1227767D02*
X87083Y1227517D01*
X87000Y1227225D01*
Y1226892D01*
X87125Y1226517D01*
X87333Y1226225D01*
X87583Y1226017D01*
X88000Y1225850D01*
X88375Y1225808D01*
X88750Y1225892D01*
X89000Y1226017D01*
X89250Y1226267D01*
X89417Y1226558D01*
X89500Y1226850D01*
Y1227142D01*
X89417Y1227433D01*
X89292Y1227683D01*
X89125Y1227892D01*
G01X87417Y1229158D02*
X87167Y1229408D01*
X87042Y1229700D01*
X87000Y1230033D01*
X87083Y1230450D01*
X87292Y1230742D01*
X87542Y1230825D01*
X87792Y1230783D01*
X88000Y1230617D01*
X88417Y1229783D01*
X88708Y1229408D01*
X89125Y1229158D01*
X89500Y1229075D01*
Y1230825D01*
G01X89208Y1232342D02*
X89417Y1232633D01*
X89500Y1232967D01*
X89417Y1233300D01*
X89167Y1233592D01*
X88792Y1233800D01*
X88417Y1233883D01*
X87958D01*
X87583Y1233800D01*
X87250Y1233592D01*
X87083Y1233342D01*
X87000Y1233050D01*
X87083Y1232717D01*
X87250Y1232467D01*
X87500Y1232300D01*
X87833Y1232217D01*
X88125Y1232300D01*
X88417Y1232508D01*
X88583Y1232758D01*
X88625Y1233050D01*
X88542Y1233383D01*
X88333Y1233633D01*
X87958Y1233883D01*
G01X87000Y1236150D02*
X87083Y1235817D01*
X87292Y1235567D01*
X87542Y1235400D01*
X87875Y1235275D01*
X88250Y1235233D01*
X88625Y1235275D01*
X88958Y1235400D01*
X89208Y1235567D01*
X89417Y1235817D01*
X89500Y1236150D01*
X89417Y1236483D01*
X89208Y1236733D01*
X88958Y1236900D01*
X88625Y1237025D01*
X88250Y1237067D01*
X87875Y1237025D01*
X87542Y1236900D01*
X87292Y1236733D01*
X87083Y1236483D01*
X87000Y1236150D01*
G01X93707Y1297380D02*
X93582Y1297130D01*
X93499Y1296838D01*
Y1296505D01*
X93624Y1296130D01*
X93832Y1295838D01*
X94082Y1295630D01*
X94499Y1295463D01*
X94874Y1295421D01*
X95249Y1295505D01*
X95499Y1295630D01*
X95749Y1295880D01*
X95916Y1296171D01*
X95999Y1296463D01*
Y1296755D01*
X95916Y1297046D01*
X95791Y1297296D01*
X95624Y1297505D01*
G01X93916Y1298771D02*
X93666Y1299021D01*
X93541Y1299313D01*
X93499Y1299646D01*
X93582Y1300063D01*
X93791Y1300355D01*
X94041Y1300438D01*
X94291Y1300396D01*
X94499Y1300230D01*
X94916Y1299396D01*
X95207Y1299021D01*
X95624Y1298771D01*
X95999Y1298688D01*
Y1300438D01*
G01Y1302663D02*
X95957Y1302955D01*
X95832Y1303288D01*
X95624Y1303496D01*
X95332Y1303580D01*
X95041Y1303496D01*
X94791Y1303246D01*
X94666Y1302871D01*
Y1302455D01*
X94582Y1302205D01*
X94374Y1301996D01*
X94082Y1301913D01*
X93791Y1302038D01*
X93582Y1302330D01*
X93499Y1302663D01*
X93582Y1302996D01*
X93791Y1303288D01*
X94082Y1303413D01*
X94374Y1303330D01*
X94582Y1303121D01*
X94666Y1302871D01*
Y1302455D01*
X94791Y1302080D01*
X95041Y1301830D01*
X95332Y1301746D01*
X95624Y1301830D01*
X95832Y1302038D01*
X95957Y1302371D01*
X95999Y1302663D01*
G01X94957Y1304971D02*
X94666Y1305263D01*
X94499Y1305513D01*
X94416Y1305846D01*
X94499Y1306138D01*
X94666Y1306346D01*
X94916Y1306513D01*
X95207Y1306555D01*
X95457Y1306513D01*
X95707Y1306346D01*
X95916Y1306096D01*
X95999Y1305805D01*
X95916Y1305471D01*
X95666Y1305180D01*
X95291Y1305013D01*
X94874Y1304971D01*
X94332Y1305055D01*
X94041Y1305180D01*
X93749Y1305388D01*
X93541Y1305680D01*
X93499Y1305971D01*
X93582Y1306263D01*
X93791Y1306471D01*
G01X94208Y1268767D02*
X94083Y1268517D01*
X94000Y1268225D01*
Y1267892D01*
X94125Y1267517D01*
X94333Y1267225D01*
X94583Y1267017D01*
X95000Y1266850D01*
X95375Y1266808D01*
X95750Y1266892D01*
X96000Y1267017D01*
X96250Y1267267D01*
X96417Y1267558D01*
X96500Y1267850D01*
Y1268142D01*
X96417Y1268433D01*
X96292Y1268683D01*
X96125Y1268892D01*
G01X94417Y1270158D02*
X94167Y1270408D01*
X94042Y1270700D01*
X94000Y1271033D01*
X94083Y1271450D01*
X94292Y1271742D01*
X94542Y1271825D01*
X94792Y1271783D01*
X95000Y1271617D01*
X95417Y1270783D01*
X95708Y1270408D01*
X96125Y1270158D01*
X96500Y1270075D01*
Y1271825D01*
G01Y1274050D02*
X96458Y1274342D01*
X96333Y1274675D01*
X96125Y1274883D01*
X95833Y1274967D01*
X95542Y1274883D01*
X95292Y1274633D01*
X95167Y1274258D01*
Y1273842D01*
X95083Y1273592D01*
X94875Y1273383D01*
X94583Y1273300D01*
X94292Y1273425D01*
X94083Y1273717D01*
X94000Y1274050D01*
X94083Y1274383D01*
X94292Y1274675D01*
X94583Y1274800D01*
X94875Y1274717D01*
X95083Y1274508D01*
X95167Y1274258D01*
Y1273842D01*
X95292Y1273467D01*
X95542Y1273217D01*
X95833Y1273133D01*
X96125Y1273217D01*
X96333Y1273425D01*
X96458Y1273758D01*
X96500Y1274050D01*
G01Y1277650D02*
X94000D01*
X95792Y1276108D01*
Y1278192D01*
G01X15899Y1309050D02*
Y1306550D01*
G01X14941Y1309050D02*
X16857D01*
G01X18166Y1306550D02*
Y1309050D01*
X19166D01*
X19499Y1308925D01*
X19749Y1308633D01*
X19832Y1308300D01*
X19749Y1307967D01*
X19541Y1307717D01*
X19166Y1307592D01*
X18166D01*
G01X21182Y1306925D02*
X21432Y1306717D01*
X21724Y1306592D01*
X22099Y1306550D01*
X22474Y1306633D01*
X22766Y1306800D01*
X22974Y1307092D01*
X23016Y1307425D01*
X22932Y1307758D01*
X22724Y1307967D01*
X22432Y1308133D01*
X22141Y1308175D01*
X21849Y1308133D01*
X21474Y1307967D01*
X21599Y1309050D01*
X22724D01*
G01X91598Y1400797D02*
Y1239597D01*
X77998D01*
Y1226647D01*
X59798D01*
Y1239597D01*
X30898D01*
Y1249947D01*
X37598D01*
Y1390447D01*
X30898D01*
Y1400797D01*
X59798D01*
Y1413747D01*
X77998D01*
Y1400797D01*
X91598D01*
G01X97266Y1371342D02*
X97016Y1371467D01*
X96724Y1371550D01*
X96391D01*
X96016Y1371425D01*
X95724Y1371217D01*
X95516Y1370967D01*
X95349Y1370550D01*
X95307Y1370175D01*
X95391Y1369800D01*
X95516Y1369550D01*
X95766Y1369300D01*
X96057Y1369133D01*
X96349Y1369050D01*
X96641D01*
X96932Y1369133D01*
X97182Y1369258D01*
X97391Y1369425D01*
G01X98657Y1371133D02*
X98907Y1371383D01*
X99199Y1371508D01*
X99532Y1371550D01*
X99949Y1371467D01*
X100241Y1371258D01*
X100324Y1371008D01*
X100282Y1370758D01*
X100116Y1370550D01*
X99282Y1370133D01*
X98907Y1369842D01*
X98657Y1369425D01*
X98574Y1369050D01*
X100324D01*
G01X102466D02*
X102549Y1369592D01*
X102674Y1370050D01*
X102841Y1370467D01*
X103049Y1370925D01*
X103382Y1371550D01*
X101716D01*
G01X105649Y1369050D02*
X105941Y1369092D01*
X106274Y1369217D01*
X106482Y1369425D01*
X106566Y1369717D01*
X106482Y1370008D01*
X106232Y1370258D01*
X105857Y1370383D01*
X105441D01*
X105191Y1370467D01*
X104982Y1370675D01*
X104899Y1370967D01*
X105024Y1371258D01*
X105316Y1371467D01*
X105649Y1371550D01*
X105982Y1371467D01*
X106274Y1371258D01*
X106399Y1370967D01*
X106316Y1370675D01*
X106107Y1370467D01*
X105857Y1370383D01*
X105441D01*
X105066Y1370258D01*
X104816Y1370008D01*
X104732Y1369717D01*
X104816Y1369425D01*
X105024Y1369217D01*
X105357Y1369092D01*
X105649Y1369050D01*
G01X94708Y1319267D02*
X94583Y1319017D01*
X94500Y1318725D01*
Y1318392D01*
X94625Y1318017D01*
X94833Y1317725D01*
X95083Y1317517D01*
X95500Y1317350D01*
X95875Y1317308D01*
X96250Y1317392D01*
X96500Y1317517D01*
X96750Y1317767D01*
X96917Y1318058D01*
X97000Y1318350D01*
Y1318642D01*
X96917Y1318933D01*
X96792Y1319183D01*
X96625Y1319392D01*
G01X94917Y1320658D02*
X94667Y1320908D01*
X94542Y1321200D01*
X94500Y1321533D01*
X94583Y1321950D01*
X94792Y1322242D01*
X95042Y1322325D01*
X95292Y1322283D01*
X95500Y1322117D01*
X95917Y1321283D01*
X96208Y1320908D01*
X96625Y1320658D01*
X97000Y1320575D01*
Y1322325D01*
G01Y1324550D02*
X96958Y1324842D01*
X96833Y1325175D01*
X96625Y1325383D01*
X96333Y1325467D01*
X96042Y1325383D01*
X95792Y1325133D01*
X95667Y1324758D01*
Y1324342D01*
X95583Y1324092D01*
X95375Y1323883D01*
X95083Y1323800D01*
X94792Y1323925D01*
X94583Y1324217D01*
X94500Y1324550D01*
X94583Y1324883D01*
X94792Y1325175D01*
X95083Y1325300D01*
X95375Y1325217D01*
X95583Y1325008D01*
X95667Y1324758D01*
Y1324342D01*
X95792Y1323967D01*
X96042Y1323717D01*
X96333Y1323633D01*
X96625Y1323717D01*
X96833Y1323925D01*
X96958Y1324258D01*
X97000Y1324550D01*
G01X94500Y1327650D02*
X94583Y1327317D01*
X94792Y1327067D01*
X95042Y1326900D01*
X95375Y1326775D01*
X95750Y1326733D01*
X96125Y1326775D01*
X96458Y1326900D01*
X96708Y1327067D01*
X96917Y1327317D01*
X97000Y1327650D01*
X96917Y1327983D01*
X96708Y1328233D01*
X96458Y1328400D01*
X96125Y1328525D01*
X95750Y1328567D01*
X95375Y1328525D01*
X95042Y1328400D01*
X94792Y1328233D01*
X94583Y1327983D01*
X94500Y1327650D01*
G01X95317Y1352292D02*
X95067Y1352417D01*
X94775Y1352500D01*
X94442D01*
X94067Y1352375D01*
X93775Y1352167D01*
X93567Y1351917D01*
X93400Y1351500D01*
X93358Y1351125D01*
X93442Y1350750D01*
X93567Y1350500D01*
X93817Y1350250D01*
X94108Y1350083D01*
X94400Y1350000D01*
X94692D01*
X94983Y1350083D01*
X95233Y1350208D01*
X95442Y1350375D01*
G01X96583Y1350500D02*
X96833Y1350208D01*
X97167Y1350042D01*
X97542Y1350000D01*
X97875Y1350042D01*
X98208Y1350250D01*
X98417Y1350500D01*
X98458Y1350750D01*
X98375Y1351042D01*
X98083Y1351250D01*
X97792Y1351333D01*
X97417D01*
G01X97792D02*
X98042Y1351458D01*
X98250Y1351667D01*
X98333Y1351917D01*
X98250Y1352167D01*
X98042Y1352375D01*
X97667Y1352500D01*
X97292Y1352458D01*
X96917Y1352292D01*
G01X99892Y1350292D02*
X100183Y1350083D01*
X100517Y1350000D01*
X100850Y1350083D01*
X101142Y1350333D01*
X101350Y1350708D01*
X101433Y1351083D01*
Y1351542D01*
X101350Y1351917D01*
X101142Y1352250D01*
X100892Y1352417D01*
X100600Y1352500D01*
X100267Y1352417D01*
X100017Y1352250D01*
X99850Y1352000D01*
X99767Y1351667D01*
X99850Y1351375D01*
X100058Y1351083D01*
X100308Y1350917D01*
X100600Y1350875D01*
X100933Y1350958D01*
X101183Y1351167D01*
X101433Y1351542D01*
G01X95317Y1348292D02*
X95067Y1348417D01*
X94775Y1348500D01*
X94442D01*
X94067Y1348375D01*
X93775Y1348167D01*
X93567Y1347917D01*
X93400Y1347500D01*
X93358Y1347125D01*
X93442Y1346750D01*
X93567Y1346500D01*
X93817Y1346250D01*
X94108Y1346083D01*
X94400Y1346000D01*
X94692D01*
X94983Y1346083D01*
X95233Y1346208D01*
X95442Y1346375D01*
G01X96583Y1346500D02*
X96833Y1346208D01*
X97167Y1346042D01*
X97542Y1346000D01*
X97875Y1346042D01*
X98208Y1346250D01*
X98417Y1346500D01*
X98458Y1346750D01*
X98375Y1347042D01*
X98083Y1347250D01*
X97792Y1347333D01*
X97417D01*
G01X97792D02*
X98042Y1347458D01*
X98250Y1347667D01*
X98333Y1347917D01*
X98250Y1348167D01*
X98042Y1348375D01*
X97667Y1348500D01*
X97292Y1348458D01*
X96917Y1348292D01*
G01X100600Y1346000D02*
X100892Y1346042D01*
X101225Y1346167D01*
X101433Y1346375D01*
X101517Y1346667D01*
X101433Y1346958D01*
X101183Y1347208D01*
X100808Y1347333D01*
X100392D01*
X100142Y1347417D01*
X99933Y1347625D01*
X99850Y1347917D01*
X99975Y1348208D01*
X100267Y1348417D01*
X100600Y1348500D01*
X100933Y1348417D01*
X101225Y1348208D01*
X101350Y1347917D01*
X101267Y1347625D01*
X101058Y1347417D01*
X100808Y1347333D01*
X100392D01*
X100017Y1347208D01*
X99767Y1346958D01*
X99683Y1346667D01*
X99767Y1346375D01*
X99975Y1346167D01*
X100308Y1346042D01*
X100600Y1346000D01*
G01X33567Y1324325D02*
X33775Y1324658D01*
X33900Y1325033D01*
Y1325367D01*
X33775Y1325700D01*
X33567Y1325950D01*
X33275Y1326075D01*
X32983Y1325992D01*
X32733Y1325783D01*
X32567Y1325408D01*
X32483Y1324908D01*
X32317Y1324617D01*
X32025Y1324492D01*
X31733Y1324575D01*
X31525Y1324783D01*
X31400Y1325075D01*
Y1325367D01*
X31483Y1325658D01*
X31692Y1325908D01*
G01X33900Y1327383D02*
X31400D01*
G01Y1328967D02*
X32942Y1327383D01*
G01X33900Y1329217D02*
X32233Y1328092D01*
G01X31400Y1331400D02*
X33900D01*
G01X31400Y1330442D02*
Y1332358D01*
G01X33900Y1334500D02*
X31400D01*
X31900Y1334000D01*
G01X33900D02*
Y1335000D01*
G01X31817Y1336808D02*
X31567Y1337058D01*
X31442Y1337350D01*
X31400Y1337683D01*
X31483Y1338100D01*
X31692Y1338392D01*
X31942Y1338475D01*
X32192Y1338433D01*
X32400Y1338267D01*
X32817Y1337433D01*
X33108Y1337058D01*
X33525Y1336808D01*
X33900Y1336725D01*
Y1338475D01*
G01X43265Y1499750D02*
X53265D01*
G01Y1492750D02*
X43265D01*
G01X48265D02*
Y1499750D01*
G01X43265Y1489317D02*
X53265D01*
Y1485983D01*
X52765Y1484650D01*
X52098Y1483650D01*
X51098Y1482817D01*
X49931Y1482150D01*
X48265Y1481983D01*
X46598Y1482150D01*
X45432Y1482817D01*
X44431Y1483650D01*
X43765Y1484650D01*
X43265Y1485983D01*
Y1489317D01*
G01Y1478717D02*
X53265D01*
Y1475383D01*
X52765Y1474050D01*
X52098Y1473050D01*
X51098Y1472217D01*
X49931Y1471550D01*
X48265Y1471383D01*
X46598Y1471550D01*
X45432Y1472217D01*
X44431Y1473050D01*
X43765Y1474050D01*
X43265Y1475383D01*
Y1478717D01*
G01Y1464450D02*
X53265D01*
X51265Y1466450D01*
G01X43265D02*
Y1462450D01*
G01Y1453850D02*
X53265D01*
X51265Y1455850D01*
G01X43265D02*
Y1451850D01*
G01X39932Y1448250D02*
Y1438250D01*
G01X53265Y1435983D02*
X43265D01*
Y1429317D01*
G01Y1418717D02*
Y1425383D01*
X53265D01*
Y1418717D01*
G01X48432Y1421383D02*
Y1425383D01*
G01X43265Y1415117D02*
X53265D01*
Y1411783D01*
X52765Y1410450D01*
X52098Y1409450D01*
X51098Y1408617D01*
X49931Y1407950D01*
X48265Y1407783D01*
X46598Y1407950D01*
X45432Y1408617D01*
X44431Y1409450D01*
X43765Y1410450D01*
X43265Y1411783D01*
Y1415117D01*
G01X74265Y1534550D02*
X67265D01*
G01X74265Y1537617D02*
Y1531483D01*
G01X67265Y1523283D02*
Y1528617D01*
X74265D01*
Y1523283D01*
G01X70882Y1525417D02*
Y1528617D01*
G01X67265Y1520817D02*
X74265D01*
X68432Y1517350D01*
X74265Y1513883D01*
X67265D01*
G01Y1511417D02*
X74265D01*
Y1508217D01*
X73915Y1507150D01*
X73098Y1506350D01*
X72165Y1506083D01*
X71232Y1506350D01*
X70532Y1507017D01*
X70181Y1508217D01*
Y1511417D01*
G01X64932Y1504150D02*
Y1496150D01*
G01X68198Y1494350D02*
X67615Y1493283D01*
X67265Y1492083D01*
Y1491017D01*
X67615Y1489950D01*
X68198Y1489150D01*
X69015Y1488750D01*
X69832Y1489017D01*
X70532Y1489683D01*
X70998Y1490883D01*
X71232Y1492483D01*
X71698Y1493417D01*
X72515Y1493817D01*
X73332Y1493550D01*
X73915Y1492883D01*
X74265Y1491950D01*
Y1491017D01*
X74032Y1490083D01*
X73448Y1489283D01*
G01X67265Y1480283D02*
Y1485617D01*
X74265D01*
Y1480283D01*
G01X70882Y1482417D02*
Y1485617D01*
G01X67265Y1477417D02*
X74265D01*
X67265Y1471283D01*
X74265D01*
G01X68198Y1468550D02*
X67615Y1467483D01*
X67265Y1466283D01*
Y1465217D01*
X67615Y1464150D01*
X68198Y1463350D01*
X69015Y1462950D01*
X69832Y1463217D01*
X70532Y1463883D01*
X70998Y1465083D01*
X71232Y1466683D01*
X71698Y1467617D01*
X72515Y1468017D01*
X73332Y1467750D01*
X73915Y1467083D01*
X74265Y1466150D01*
Y1465217D01*
X74032Y1464283D01*
X73448Y1463483D01*
G01X67265Y1457150D02*
X67382Y1458217D01*
X67848Y1459150D01*
X68548Y1459950D01*
X69365Y1460483D01*
X70298Y1460750D01*
X71232D01*
X72165Y1460483D01*
X72982Y1459950D01*
X73682Y1459150D01*
X74148Y1458217D01*
X74265Y1457150D01*
X74148Y1456083D01*
X73682Y1455150D01*
X72982Y1454350D01*
X72165Y1453817D01*
X71232Y1453550D01*
X70298D01*
X69365Y1453817D01*
X68548Y1454350D01*
X67848Y1455150D01*
X67382Y1456083D01*
X67265Y1457150D01*
G01Y1451217D02*
X74265D01*
Y1447883D01*
X73915Y1446817D01*
X73448Y1446150D01*
X72515Y1445883D01*
X71582Y1446150D01*
X70998Y1446950D01*
X70648Y1447883D01*
Y1451217D01*
G01Y1447883D02*
X67265Y1445883D01*
G01Y1439950D02*
X74265D01*
X72865Y1441550D01*
G01X67265D02*
Y1438350D01*
G01X24208Y1449380D02*
X24083Y1449130D01*
X24000Y1448838D01*
Y1448505D01*
X24125Y1448130D01*
X24333Y1447838D01*
X24583Y1447630D01*
X25000Y1447463D01*
X25375Y1447421D01*
X25750Y1447505D01*
X26000Y1447630D01*
X26250Y1447880D01*
X26417Y1448171D01*
X26500Y1448463D01*
Y1448755D01*
X26417Y1449046D01*
X26292Y1449296D01*
X26125Y1449505D01*
G01X26500Y1450605D02*
X24000D01*
X26500Y1452521D01*
X24000D01*
G01X26500Y1454663D02*
X24000D01*
X24500Y1454163D01*
G01X26500D02*
Y1455163D01*
G01X77167Y1426200D02*
Y1423700D01*
X78833D01*
G01X81933D02*
X80267D01*
Y1426200D01*
X81933D01*
G01X81267Y1424992D02*
X80267D01*
G01X83283Y1423700D02*
Y1426200D01*
X84117D01*
X84450Y1426075D01*
X84700Y1425908D01*
X84908Y1425658D01*
X85075Y1425367D01*
X85117Y1424950D01*
X85075Y1424533D01*
X84908Y1424242D01*
X84700Y1423992D01*
X84450Y1423825D01*
X84117Y1423700D01*
X83283D01*
G01X87300D02*
Y1426200D01*
X86800Y1425700D01*
G01Y1423700D02*
X87800D01*
G01X89608Y1425783D02*
X89858Y1426033D01*
X90150Y1426158D01*
X90483Y1426200D01*
X90900Y1426117D01*
X91192Y1425908D01*
X91275Y1425658D01*
X91233Y1425408D01*
X91067Y1425200D01*
X90233Y1424783D01*
X89858Y1424492D01*
X89608Y1424075D01*
X89525Y1423700D01*
X91275D01*
G01X63198Y1420767D02*
Y1428367D01*
X74598D01*
Y1420767D01*
X63198D01*
G01X93499Y1460067D02*
X90999D01*
Y1461108D01*
X91124Y1461442D01*
X91291Y1461650D01*
X91624Y1461733D01*
X91957Y1461650D01*
X92166Y1461400D01*
X92291Y1461108D01*
Y1460067D01*
G01Y1461108D02*
X93499Y1461733D01*
G01X92999Y1463083D02*
X93291Y1463333D01*
X93457Y1463667D01*
X93499Y1464042D01*
X93457Y1464375D01*
X93249Y1464708D01*
X92999Y1464917D01*
X92749Y1464958D01*
X92457Y1464875D01*
X92249Y1464583D01*
X92166Y1464292D01*
Y1463917D01*
G01Y1464292D02*
X92041Y1464542D01*
X91832Y1464750D01*
X91582Y1464833D01*
X91332Y1464750D01*
X91124Y1464542D01*
X90999Y1464167D01*
X91041Y1463792D01*
X91207Y1463417D01*
G01X91416Y1466308D02*
X91166Y1466558D01*
X91041Y1466850D01*
X90999Y1467183D01*
X91082Y1467600D01*
X91291Y1467892D01*
X91541Y1467975D01*
X91791Y1467933D01*
X91999Y1467767D01*
X92416Y1466933D01*
X92707Y1466558D01*
X93124Y1466308D01*
X93499Y1466225D01*
Y1467975D01*
G01X90999Y1470200D02*
X91082Y1469867D01*
X91291Y1469617D01*
X91541Y1469450D01*
X91874Y1469325D01*
X92249Y1469283D01*
X92624Y1469325D01*
X92957Y1469450D01*
X93207Y1469617D01*
X93416Y1469867D01*
X93499Y1470200D01*
X93416Y1470533D01*
X93207Y1470783D01*
X92957Y1470950D01*
X92624Y1471075D01*
X92249Y1471117D01*
X91874Y1471075D01*
X91541Y1470950D01*
X91291Y1470783D01*
X91082Y1470533D01*
X90999Y1470200D01*
G01X97499Y1460067D02*
X94999D01*
Y1461108D01*
X95124Y1461442D01*
X95291Y1461650D01*
X95624Y1461733D01*
X95957Y1461650D01*
X96166Y1461400D01*
X96291Y1461108D01*
Y1460067D01*
G01Y1461108D02*
X97499Y1461733D01*
G01X96999Y1463083D02*
X97291Y1463333D01*
X97457Y1463667D01*
X97499Y1464042D01*
X97457Y1464375D01*
X97249Y1464708D01*
X96999Y1464917D01*
X96749Y1464958D01*
X96457Y1464875D01*
X96249Y1464583D01*
X96166Y1464292D01*
Y1463917D01*
G01Y1464292D02*
X96041Y1464542D01*
X95832Y1464750D01*
X95582Y1464833D01*
X95332Y1464750D01*
X95124Y1464542D01*
X94999Y1464167D01*
X95041Y1463792D01*
X95207Y1463417D01*
G01X95416Y1466308D02*
X95166Y1466558D01*
X95041Y1466850D01*
X94999Y1467183D01*
X95082Y1467600D01*
X95291Y1467892D01*
X95541Y1467975D01*
X95791Y1467933D01*
X95999Y1467767D01*
X96416Y1466933D01*
X96707Y1466558D01*
X97124Y1466308D01*
X97499Y1466225D01*
Y1467975D01*
G01Y1470200D02*
X94999D01*
X95499Y1469700D01*
G01X97499D02*
Y1470700D01*
G01X44965Y1627950D02*
X54965Y1620950D01*
G01Y1627950D02*
X44965Y1620950D01*
G01Y1613850D02*
X54965D01*
X52965Y1615850D01*
G01X44965D02*
Y1611850D01*
G01X49131Y1606417D02*
X50298Y1605250D01*
X50965Y1604250D01*
X51298Y1602917D01*
X50965Y1601750D01*
X50298Y1600917D01*
X49298Y1600250D01*
X48132Y1600083D01*
X47132Y1600250D01*
X46131Y1600917D01*
X45298Y1601917D01*
X44965Y1603083D01*
X45298Y1604417D01*
X46298Y1605583D01*
X47798Y1606250D01*
X49465Y1606417D01*
X51631Y1606083D01*
X52798Y1605583D01*
X53965Y1604750D01*
X54798Y1603583D01*
X54965Y1602417D01*
X54632Y1601250D01*
X53798Y1600417D01*
G01X44965Y1595983D02*
X54965D01*
Y1591983D01*
X54465Y1590650D01*
X53298Y1589650D01*
X51965Y1589317D01*
X50632Y1589650D01*
X49632Y1590483D01*
X49131Y1591983D01*
Y1595983D01*
G01X54132Y1578383D02*
X54632Y1579383D01*
X54965Y1580550D01*
Y1581883D01*
X54465Y1583384D01*
X53632Y1584550D01*
X52632Y1585383D01*
X50965Y1586050D01*
X49465Y1586217D01*
X47965Y1585883D01*
X46965Y1585383D01*
X45965Y1584383D01*
X45298Y1583217D01*
X44965Y1582050D01*
Y1580883D01*
X45298Y1579717D01*
X45798Y1578717D01*
X46465Y1577883D01*
G01X54965Y1573450D02*
Y1569450D01*
G01Y1571450D02*
X44965D01*
G01Y1573450D02*
Y1569450D01*
G01Y1557517D02*
Y1564183D01*
X54965D01*
Y1557517D01*
G01X50132Y1560183D02*
Y1564183D01*
G01X41632Y1555250D02*
Y1545250D01*
G01X44965Y1543817D02*
X54965Y1539650D01*
X44965Y1535483D01*
G01X48465Y1536983D02*
Y1542317D01*
G01X87300Y1559500D02*
Y1555500D01*
X94700D01*
G01X87300D02*
Y1551500D01*
X94700D01*
G01X85000Y1533517D02*
X82500D01*
Y1534558D01*
X82625Y1534892D01*
X82792Y1535100D01*
X83125Y1535183D01*
X83458Y1535100D01*
X83667Y1534850D01*
X83792Y1534558D01*
Y1533517D01*
G01Y1534558D02*
X85000Y1535183D01*
G01X84625Y1536533D02*
X84833Y1536783D01*
X84958Y1537075D01*
X85000Y1537450D01*
X84917Y1537825D01*
X84750Y1538117D01*
X84458Y1538325D01*
X84125Y1538367D01*
X83792Y1538283D01*
X83583Y1538075D01*
X83417Y1537783D01*
X83375Y1537492D01*
X83417Y1537200D01*
X83583Y1536825D01*
X82500Y1536950D01*
Y1538075D01*
G01Y1540550D02*
X82583Y1540217D01*
X82792Y1539967D01*
X83042Y1539800D01*
X83375Y1539675D01*
X83750Y1539633D01*
X84125Y1539675D01*
X84458Y1539800D01*
X84708Y1539967D01*
X84917Y1540217D01*
X85000Y1540550D01*
X84917Y1540883D01*
X84708Y1541133D01*
X84458Y1541300D01*
X84125Y1541425D01*
X83750Y1541467D01*
X83375Y1541425D01*
X83042Y1541300D01*
X82792Y1541133D01*
X82583Y1540883D01*
X82500Y1540550D01*
G01X84708Y1542942D02*
X84917Y1543233D01*
X85000Y1543567D01*
X84917Y1543900D01*
X84667Y1544192D01*
X84292Y1544400D01*
X83917Y1544483D01*
X83458D01*
X83083Y1544400D01*
X82750Y1544192D01*
X82583Y1543942D01*
X82500Y1543650D01*
X82583Y1543317D01*
X82750Y1543067D01*
X83000Y1542900D01*
X83333Y1542817D01*
X83625Y1542900D01*
X83917Y1543108D01*
X84083Y1543358D01*
X84125Y1543650D01*
X84042Y1543983D01*
X83833Y1544233D01*
X83458Y1544483D01*
G01X85000Y1553700D02*
X81000D01*
Y1546300D01*
G01Y1533517D02*
X78500D01*
Y1534558D01*
X78625Y1534892D01*
X78792Y1535100D01*
X79125Y1535183D01*
X79458Y1535100D01*
X79667Y1534850D01*
X79792Y1534558D01*
Y1533517D01*
G01Y1534558D02*
X81000Y1535183D01*
G01X80625Y1536533D02*
X80833Y1536783D01*
X80958Y1537075D01*
X81000Y1537450D01*
X80917Y1537825D01*
X80750Y1538117D01*
X80458Y1538325D01*
X80125Y1538367D01*
X79792Y1538283D01*
X79583Y1538075D01*
X79417Y1537783D01*
X79375Y1537492D01*
X79417Y1537200D01*
X79583Y1536825D01*
X78500Y1536950D01*
Y1538075D01*
G01Y1540550D02*
X78583Y1540217D01*
X78792Y1539967D01*
X79042Y1539800D01*
X79375Y1539675D01*
X79750Y1539633D01*
X80125Y1539675D01*
X80458Y1539800D01*
X80708Y1539967D01*
X80917Y1540217D01*
X81000Y1540550D01*
X80917Y1540883D01*
X80708Y1541133D01*
X80458Y1541300D01*
X80125Y1541425D01*
X79750Y1541467D01*
X79375Y1541425D01*
X79042Y1541300D01*
X78792Y1541133D01*
X78583Y1540883D01*
X78500Y1540550D01*
G01X81000Y1543650D02*
X80958Y1543942D01*
X80833Y1544275D01*
X80625Y1544483D01*
X80333Y1544567D01*
X80042Y1544483D01*
X79792Y1544233D01*
X79667Y1543858D01*
Y1543442D01*
X79583Y1543192D01*
X79375Y1542983D01*
X79083Y1542900D01*
X78792Y1543025D01*
X78583Y1543317D01*
X78500Y1543650D01*
X78583Y1543983D01*
X78792Y1544275D01*
X79083Y1544400D01*
X79375Y1544317D01*
X79583Y1544108D01*
X79667Y1543858D01*
Y1543442D01*
X79792Y1543067D01*
X80042Y1542817D01*
X80333Y1542733D01*
X80625Y1542817D01*
X80833Y1543025D01*
X80958Y1543358D01*
X81000Y1543650D01*
G01Y1553700D02*
X77000D01*
Y1546300D01*
G01X28500Y1557350D02*
X31000D01*
G01X28500Y1556392D02*
Y1558308D01*
G01X31000Y1559617D02*
X28500D01*
Y1560617D01*
X28625Y1560950D01*
X28917Y1561200D01*
X29250Y1561283D01*
X29583Y1561200D01*
X29833Y1560992D01*
X29958Y1560617D01*
Y1559617D01*
G01X31000Y1563550D02*
X28500D01*
X29000Y1563050D01*
G01X31000D02*
Y1564050D01*
G01X30625Y1565733D02*
X30833Y1565983D01*
X30958Y1566275D01*
X31000Y1566650D01*
X30917Y1567025D01*
X30750Y1567317D01*
X30458Y1567525D01*
X30125Y1567567D01*
X29792Y1567483D01*
X29583Y1567275D01*
X29417Y1566983D01*
X29375Y1566692D01*
X29417Y1566400D01*
X29583Y1566025D01*
X28500Y1566150D01*
Y1567275D01*
G01X92883Y1507063D02*
Y1505271D01*
X93050Y1504896D01*
X93383Y1504646D01*
X93800Y1504563D01*
X94217Y1504646D01*
X94550Y1504896D01*
X94717Y1505271D01*
Y1507063D01*
G01X97400Y1504563D02*
Y1507063D01*
X95858Y1505271D01*
X97942D01*
G01X99208Y1505605D02*
X99500Y1505896D01*
X99750Y1506063D01*
X100083Y1506146D01*
X100375Y1506063D01*
X100583Y1505896D01*
X100750Y1505646D01*
X100792Y1505355D01*
X100750Y1505105D01*
X100583Y1504855D01*
X100333Y1504646D01*
X100042Y1504563D01*
X99708Y1504646D01*
X99417Y1504896D01*
X99250Y1505271D01*
X99208Y1505688D01*
X99292Y1506230D01*
X99417Y1506521D01*
X99625Y1506813D01*
X99917Y1507021D01*
X100208Y1507063D01*
X100500Y1506980D01*
X100708Y1506771D01*
G01X95308Y1638204D02*
X95183Y1637954D01*
X95100Y1637662D01*
Y1637329D01*
X95225Y1636954D01*
X95433Y1636662D01*
X95683Y1636454D01*
X96100Y1636287D01*
X96475Y1636245D01*
X96850Y1636329D01*
X97100Y1636454D01*
X97350Y1636704D01*
X97517Y1636995D01*
X97600Y1637287D01*
Y1637579D01*
X97517Y1637870D01*
X97392Y1638120D01*
X97225Y1638329D01*
G01X95517Y1639595D02*
X95267Y1639845D01*
X95142Y1640137D01*
X95100Y1640470D01*
X95183Y1640887D01*
X95392Y1641179D01*
X95642Y1641262D01*
X95892Y1641220D01*
X96100Y1641054D01*
X96517Y1640220D01*
X96808Y1639845D01*
X97225Y1639595D01*
X97600Y1639512D01*
Y1641262D01*
G01Y1643404D02*
X97058Y1643487D01*
X96600Y1643612D01*
X96183Y1643779D01*
X95725Y1643987D01*
X95100Y1644320D01*
Y1642654D01*
G01X95517Y1645795D02*
X95267Y1646045D01*
X95142Y1646337D01*
X95100Y1646670D01*
X95183Y1647087D01*
X95392Y1647379D01*
X95642Y1647462D01*
X95892Y1647420D01*
X96100Y1647254D01*
X96517Y1646420D01*
X96808Y1646045D01*
X97225Y1645795D01*
X97600Y1645712D01*
Y1647462D01*
G01X35500Y1596017D02*
X33000D01*
Y1597058D01*
X33125Y1597392D01*
X33292Y1597600D01*
X33625Y1597683D01*
X33958Y1597600D01*
X34167Y1597350D01*
X34292Y1597058D01*
Y1596017D01*
G01Y1597058D02*
X35500Y1597683D01*
G01X35000Y1599033D02*
X35292Y1599283D01*
X35458Y1599617D01*
X35500Y1599992D01*
X35458Y1600325D01*
X35250Y1600658D01*
X35000Y1600867D01*
X34750Y1600908D01*
X34458Y1600825D01*
X34250Y1600533D01*
X34167Y1600242D01*
Y1599867D01*
G01Y1600242D02*
X34042Y1600492D01*
X33833Y1600700D01*
X33583Y1600783D01*
X33333Y1600700D01*
X33125Y1600492D01*
X33000Y1600117D01*
X33042Y1599742D01*
X33208Y1599367D01*
G01X35125Y1602133D02*
X35333Y1602383D01*
X35458Y1602675D01*
X35500Y1603050D01*
X35417Y1603425D01*
X35250Y1603717D01*
X34958Y1603925D01*
X34625Y1603967D01*
X34292Y1603883D01*
X34083Y1603675D01*
X33917Y1603383D01*
X33875Y1603092D01*
X33917Y1602800D01*
X34083Y1602425D01*
X33000Y1602550D01*
Y1603675D01*
G01X35125Y1605233D02*
X35333Y1605483D01*
X35458Y1605775D01*
X35500Y1606150D01*
X35417Y1606525D01*
X35250Y1606817D01*
X34958Y1607025D01*
X34625Y1607067D01*
X34292Y1606983D01*
X34083Y1606775D01*
X33917Y1606483D01*
X33875Y1606192D01*
X33917Y1605900D01*
X34083Y1605525D01*
X33000Y1605650D01*
Y1606775D01*
G01X36599Y1594050D02*
X32599D01*
Y1586650D01*
G01X75500Y1573017D02*
X73000D01*
Y1574058D01*
X73125Y1574392D01*
X73292Y1574600D01*
X73625Y1574683D01*
X73958Y1574600D01*
X74167Y1574350D01*
X74292Y1574058D01*
Y1573017D01*
G01Y1574058D02*
X75500Y1574683D01*
G01Y1577450D02*
X73000D01*
X74792Y1575908D01*
Y1577992D01*
G01X75500Y1580050D02*
X75458Y1580342D01*
X75333Y1580675D01*
X75125Y1580883D01*
X74833Y1580967D01*
X74542Y1580883D01*
X74292Y1580633D01*
X74167Y1580258D01*
Y1579842D01*
X74083Y1579592D01*
X73875Y1579383D01*
X73583Y1579300D01*
X73292Y1579425D01*
X73083Y1579717D01*
X73000Y1580050D01*
X73083Y1580383D01*
X73292Y1580675D01*
X73583Y1580800D01*
X73875Y1580717D01*
X74083Y1580508D01*
X74167Y1580258D01*
Y1579842D01*
X74292Y1579467D01*
X74542Y1579217D01*
X74833Y1579133D01*
X75125Y1579217D01*
X75333Y1579425D01*
X75458Y1579758D01*
X75500Y1580050D01*
G01Y1583150D02*
X73000D01*
X73500Y1582650D01*
G01X75500D02*
Y1583650D01*
G01X77000Y1570600D02*
X73000D01*
Y1563200D01*
G01X79500Y1573017D02*
X77000D01*
Y1574058D01*
X77125Y1574392D01*
X77292Y1574600D01*
X77625Y1574683D01*
X77958Y1574600D01*
X78167Y1574350D01*
X78292Y1574058D01*
Y1573017D01*
G01Y1574058D02*
X79500Y1574683D01*
G01X79125Y1576033D02*
X79333Y1576283D01*
X79458Y1576575D01*
X79500Y1576950D01*
X79417Y1577325D01*
X79250Y1577617D01*
X78958Y1577825D01*
X78625Y1577867D01*
X78292Y1577783D01*
X78083Y1577575D01*
X77917Y1577283D01*
X77875Y1576992D01*
X77917Y1576700D01*
X78083Y1576325D01*
X77000Y1576450D01*
Y1577575D01*
G01Y1580050D02*
X77083Y1579717D01*
X77292Y1579467D01*
X77542Y1579300D01*
X77875Y1579175D01*
X78250Y1579133D01*
X78625Y1579175D01*
X78958Y1579300D01*
X79208Y1579467D01*
X79417Y1579717D01*
X79500Y1580050D01*
X79417Y1580383D01*
X79208Y1580633D01*
X78958Y1580800D01*
X78625Y1580925D01*
X78250Y1580967D01*
X77875Y1580925D01*
X77542Y1580800D01*
X77292Y1580633D01*
X77083Y1580383D01*
X77000Y1580050D01*
G01X79500Y1583067D02*
X78958Y1583150D01*
X78500Y1583275D01*
X78083Y1583442D01*
X77625Y1583650D01*
X77000Y1583983D01*
Y1582317D01*
G01X81000Y1570600D02*
X77000D01*
Y1563200D01*
G01X93700Y1573500D02*
X104900D01*
G01X93700Y1591500D02*
Y1573500D01*
G01X104900Y1591500D02*
X93700D01*
G01X31500Y1596017D02*
X29000D01*
Y1597058D01*
X29125Y1597392D01*
X29292Y1597600D01*
X29625Y1597683D01*
X29958Y1597600D01*
X30167Y1597350D01*
X30292Y1597058D01*
Y1596017D01*
G01Y1597058D02*
X31500Y1597683D01*
G01X31000Y1599033D02*
X31292Y1599283D01*
X31458Y1599617D01*
X31500Y1599992D01*
X31458Y1600325D01*
X31250Y1600658D01*
X31000Y1600867D01*
X30750Y1600908D01*
X30458Y1600825D01*
X30250Y1600533D01*
X30167Y1600242D01*
Y1599867D01*
G01Y1600242D02*
X30042Y1600492D01*
X29833Y1600700D01*
X29583Y1600783D01*
X29333Y1600700D01*
X29125Y1600492D01*
X29000Y1600117D01*
X29042Y1599742D01*
X29208Y1599367D01*
G01X31125Y1602133D02*
X31333Y1602383D01*
X31458Y1602675D01*
X31500Y1603050D01*
X31417Y1603425D01*
X31250Y1603717D01*
X30958Y1603925D01*
X30625Y1603967D01*
X30292Y1603883D01*
X30083Y1603675D01*
X29917Y1603383D01*
X29875Y1603092D01*
X29917Y1602800D01*
X30083Y1602425D01*
X29000Y1602550D01*
Y1603675D01*
G01X31500Y1606150D02*
X31458Y1606442D01*
X31333Y1606775D01*
X31125Y1606983D01*
X30833Y1607067D01*
X30542Y1606983D01*
X30292Y1606733D01*
X30167Y1606358D01*
Y1605942D01*
X30083Y1605692D01*
X29875Y1605483D01*
X29583Y1605400D01*
X29292Y1605525D01*
X29083Y1605817D01*
X29000Y1606150D01*
X29083Y1606483D01*
X29292Y1606775D01*
X29583Y1606900D01*
X29875Y1606817D01*
X30083Y1606608D01*
X30167Y1606358D01*
Y1605942D01*
X30292Y1605567D01*
X30542Y1605317D01*
X30833Y1605233D01*
X31125Y1605317D01*
X31333Y1605525D01*
X31458Y1605858D01*
X31500Y1606150D01*
G01X28499Y1586660D02*
X32499D01*
Y1594060D01*
G01X91598Y1806309D02*
Y1645109D01*
X77998D01*
Y1632159D01*
X59798D01*
Y1645109D01*
X30898D01*
Y1655459D01*
X37598D01*
Y1795959D01*
X30898D01*
Y1806309D01*
X59798D01*
Y1819259D01*
X77998D01*
Y1806309D01*
X91598D01*
G01X94938Y1697445D02*
X94813Y1697195D01*
X94730Y1696903D01*
Y1696570D01*
X94855Y1696195D01*
X95063Y1695903D01*
X95313Y1695695D01*
X95730Y1695528D01*
X96105Y1695486D01*
X96480Y1695570D01*
X96730Y1695695D01*
X96980Y1695945D01*
X97147Y1696236D01*
X97230Y1696528D01*
Y1696820D01*
X97147Y1697111D01*
X97022Y1697361D01*
X96855Y1697570D01*
G01X95147Y1698836D02*
X94897Y1699086D01*
X94772Y1699378D01*
X94730Y1699711D01*
X94813Y1700128D01*
X95022Y1700420D01*
X95272Y1700503D01*
X95522Y1700461D01*
X95730Y1700295D01*
X96147Y1699461D01*
X96438Y1699086D01*
X96855Y1698836D01*
X97230Y1698753D01*
Y1700503D01*
G01Y1702645D02*
X96688Y1702728D01*
X96230Y1702853D01*
X95813Y1703020D01*
X95355Y1703228D01*
X94730Y1703561D01*
Y1701895D01*
G01Y1705828D02*
X94813Y1705495D01*
X95022Y1705245D01*
X95272Y1705078D01*
X95605Y1704953D01*
X95980Y1704911D01*
X96355Y1704953D01*
X96688Y1705078D01*
X96938Y1705245D01*
X97147Y1705495D01*
X97230Y1705828D01*
X97147Y1706161D01*
X96938Y1706411D01*
X96688Y1706578D01*
X96355Y1706703D01*
X95980Y1706745D01*
X95605Y1706703D01*
X95272Y1706578D01*
X95022Y1706411D01*
X94813Y1706161D01*
X94730Y1705828D01*
G01X94207Y1670380D02*
X94082Y1670130D01*
X93999Y1669838D01*
Y1669505D01*
X94124Y1669130D01*
X94332Y1668838D01*
X94582Y1668630D01*
X94999Y1668463D01*
X95374Y1668421D01*
X95749Y1668505D01*
X95999Y1668630D01*
X96249Y1668880D01*
X96416Y1669171D01*
X96499Y1669463D01*
Y1669755D01*
X96416Y1670046D01*
X96291Y1670296D01*
X96124Y1670505D01*
G01X94416Y1671771D02*
X94166Y1672021D01*
X94041Y1672313D01*
X93999Y1672646D01*
X94082Y1673063D01*
X94291Y1673355D01*
X94541Y1673438D01*
X94791Y1673396D01*
X94999Y1673230D01*
X95416Y1672396D01*
X95707Y1672021D01*
X96124Y1671771D01*
X96499Y1671688D01*
Y1673438D01*
G01X95457Y1674871D02*
X95166Y1675163D01*
X94999Y1675413D01*
X94916Y1675746D01*
X94999Y1676038D01*
X95166Y1676246D01*
X95416Y1676413D01*
X95707Y1676455D01*
X95957Y1676413D01*
X96207Y1676246D01*
X96416Y1675996D01*
X96499Y1675705D01*
X96416Y1675371D01*
X96166Y1675080D01*
X95791Y1674913D01*
X95374Y1674871D01*
X94832Y1674955D01*
X94541Y1675080D01*
X94249Y1675288D01*
X94041Y1675580D01*
X93999Y1675871D01*
X94082Y1676163D01*
X94291Y1676371D01*
G01X95457Y1677971D02*
X95166Y1678263D01*
X94999Y1678513D01*
X94916Y1678846D01*
X94999Y1679138D01*
X95166Y1679346D01*
X95416Y1679513D01*
X95707Y1679555D01*
X95957Y1679513D01*
X96207Y1679346D01*
X96416Y1679096D01*
X96499Y1678805D01*
X96416Y1678471D01*
X96166Y1678180D01*
X95791Y1678013D01*
X95374Y1677971D01*
X94832Y1678055D01*
X94541Y1678180D01*
X94249Y1678388D01*
X94041Y1678680D01*
X93999Y1678971D01*
X94082Y1679263D01*
X94291Y1679471D01*
G01X94443Y1709154D02*
Y1711654D01*
X95484D01*
X95818Y1711529D01*
X96026Y1711362D01*
X96109Y1711029D01*
X96026Y1710696D01*
X95776Y1710487D01*
X95484Y1710362D01*
X94443D01*
G01X95484D02*
X96109Y1709154D01*
G01X97584Y1711237D02*
X97834Y1711487D01*
X98126Y1711612D01*
X98459Y1711654D01*
X98876Y1711571D01*
X99168Y1711362D01*
X99251Y1711112D01*
X99209Y1710862D01*
X99043Y1710654D01*
X98209Y1710237D01*
X97834Y1709946D01*
X97584Y1709529D01*
X97501Y1709154D01*
X99251D01*
G01X101976D02*
Y1711654D01*
X100434Y1709862D01*
X102518D01*
G01X103784Y1710196D02*
X104076Y1710487D01*
X104326Y1710654D01*
X104659Y1710737D01*
X104951Y1710654D01*
X105159Y1710487D01*
X105326Y1710237D01*
X105368Y1709946D01*
X105326Y1709696D01*
X105159Y1709446D01*
X104909Y1709237D01*
X104618Y1709154D01*
X104284Y1709237D01*
X103993Y1709487D01*
X103826Y1709862D01*
X103784Y1710279D01*
X103868Y1710821D01*
X103993Y1711112D01*
X104201Y1711404D01*
X104493Y1711612D01*
X104784Y1711654D01*
X105076Y1711571D01*
X105284Y1711362D01*
G01X34267Y1717325D02*
X34475Y1717658D01*
X34600Y1718033D01*
Y1718367D01*
X34475Y1718700D01*
X34267Y1718950D01*
X33975Y1719075D01*
X33683Y1718992D01*
X33433Y1718783D01*
X33267Y1718408D01*
X33183Y1717908D01*
X33017Y1717617D01*
X32725Y1717492D01*
X32433Y1717575D01*
X32225Y1717783D01*
X32100Y1718075D01*
Y1718367D01*
X32183Y1718658D01*
X32392Y1718908D01*
G01X34600Y1720383D02*
X32100D01*
G01Y1721967D02*
X33642Y1720383D01*
G01X34600Y1722217D02*
X32933Y1721092D01*
G01X32100Y1724400D02*
X34600D01*
G01X32100Y1723442D02*
Y1725358D01*
G01X34600Y1727500D02*
X32100D01*
X32600Y1727000D01*
G01X34600D02*
Y1728000D01*
G01Y1730600D02*
X32100D01*
X32600Y1730100D01*
G01X34600D02*
Y1731100D01*
G01X98299Y1822450D02*
X108299D01*
G01Y1815450D02*
X98299D01*
G01X103299D02*
Y1822450D01*
G01X98299Y1812017D02*
X108299D01*
Y1808683D01*
X107799Y1807350D01*
X107132Y1806350D01*
X106132Y1805517D01*
X104965Y1804850D01*
X103299Y1804683D01*
X101632Y1804850D01*
X100466Y1805517D01*
X99465Y1806350D01*
X98799Y1807350D01*
X98299Y1808683D01*
Y1812017D01*
G01Y1801417D02*
X108299D01*
Y1798083D01*
X107799Y1796750D01*
X107132Y1795750D01*
X106132Y1794917D01*
X104965Y1794250D01*
X103299Y1794083D01*
X101632Y1794250D01*
X100466Y1794917D01*
X99465Y1795750D01*
X98799Y1796750D01*
X98299Y1798083D01*
Y1801417D01*
G01Y1787150D02*
X108299D01*
X106299Y1789150D01*
G01X98299D02*
Y1785150D01*
G01X108299Y1776550D02*
X107966Y1777884D01*
X107132Y1778883D01*
X106132Y1779550D01*
X104799Y1780050D01*
X103299Y1780217D01*
X101799Y1780050D01*
X100466Y1779550D01*
X99465Y1778883D01*
X98632Y1777884D01*
X98299Y1776550D01*
X98632Y1775217D01*
X99465Y1774217D01*
X100466Y1773550D01*
X101799Y1773050D01*
X103299Y1772883D01*
X104799Y1773050D01*
X106132Y1773550D01*
X107132Y1774217D01*
X107966Y1775217D01*
X108299Y1776550D01*
G01X95379Y1725641D02*
Y1728141D01*
X96420D01*
X96754Y1728016D01*
X96962Y1727849D01*
X97045Y1727516D01*
X96962Y1727183D01*
X96712Y1726974D01*
X96420Y1726849D01*
X95379D01*
G01X96420D02*
X97045Y1725641D01*
G01X99812D02*
Y1728141D01*
X98270Y1726349D01*
X100354D01*
G01X101620Y1726683D02*
X101912Y1726974D01*
X102162Y1727141D01*
X102495Y1727224D01*
X102787Y1727141D01*
X102995Y1726974D01*
X103162Y1726724D01*
X103204Y1726433D01*
X103162Y1726183D01*
X102995Y1725933D01*
X102745Y1725724D01*
X102454Y1725641D01*
X102120Y1725724D01*
X101829Y1725974D01*
X101662Y1726349D01*
X101620Y1726766D01*
X101704Y1727308D01*
X101829Y1727599D01*
X102037Y1727891D01*
X102329Y1728099D01*
X102620Y1728141D01*
X102912Y1728058D01*
X103120Y1727849D01*
G01X105512Y1728141D02*
X105179Y1728058D01*
X104929Y1727849D01*
X104762Y1727599D01*
X104637Y1727266D01*
X104595Y1726891D01*
X104637Y1726516D01*
X104762Y1726183D01*
X104929Y1725933D01*
X105179Y1725724D01*
X105512Y1725641D01*
X105845Y1725724D01*
X106095Y1725933D01*
X106262Y1726183D01*
X106387Y1726516D01*
X106429Y1726891D01*
X106387Y1727266D01*
X106262Y1727599D01*
X106095Y1727849D01*
X105845Y1728058D01*
X105512Y1728141D01*
G01X95379Y1729641D02*
Y1732141D01*
X96420D01*
X96754Y1732016D01*
X96962Y1731849D01*
X97045Y1731516D01*
X96962Y1731183D01*
X96712Y1730974D01*
X96420Y1730849D01*
X95379D01*
G01X96420D02*
X97045Y1729641D01*
G01X99812D02*
Y1732141D01*
X98270Y1730349D01*
X100354D01*
G01X101620Y1730683D02*
X101912Y1730974D01*
X102162Y1731141D01*
X102495Y1731224D01*
X102787Y1731141D01*
X102995Y1730974D01*
X103162Y1730724D01*
X103204Y1730433D01*
X103162Y1730183D01*
X102995Y1729933D01*
X102745Y1729724D01*
X102454Y1729641D01*
X102120Y1729724D01*
X101829Y1729974D01*
X101662Y1730349D01*
X101620Y1730766D01*
X101704Y1731308D01*
X101829Y1731599D01*
X102037Y1731891D01*
X102329Y1732099D01*
X102620Y1732141D01*
X102912Y1732058D01*
X103120Y1731849D01*
G01X105512Y1729641D02*
Y1732141D01*
X105012Y1731641D01*
G01Y1729641D02*
X106012D01*
G01X50800Y1893150D02*
X55800Y1889650D01*
G01Y1893150D02*
X50800Y1889650D01*
G01Y1885800D02*
X55800D01*
X54800Y1886800D01*
G01X50800D02*
Y1884800D01*
G01Y1881867D02*
X55800D01*
Y1879867D01*
X55550Y1879200D01*
X54967Y1878700D01*
X54300Y1878533D01*
X53633Y1878700D01*
X53133Y1879117D01*
X52883Y1879867D01*
Y1881867D01*
G01X55383Y1872767D02*
X55633Y1873267D01*
X55800Y1873850D01*
Y1874517D01*
X55550Y1875267D01*
X55133Y1875850D01*
X54633Y1876267D01*
X53800Y1876600D01*
X53050Y1876683D01*
X52300Y1876517D01*
X51800Y1876267D01*
X51300Y1875767D01*
X50967Y1875183D01*
X50800Y1874600D01*
Y1874017D01*
X50967Y1873433D01*
X51217Y1872933D01*
X51550Y1872517D01*
G01X55800Y1870000D02*
Y1868000D01*
G01Y1869000D02*
X50800D01*
G01Y1870000D02*
Y1868000D01*
G01Y1861733D02*
Y1865067D01*
X55800D01*
Y1861733D01*
G01X53383Y1863067D02*
Y1865067D01*
G01X49133Y1860300D02*
Y1855300D01*
G01X50800Y1854283D02*
X55800Y1852200D01*
X50800Y1850117D01*
G01X52550Y1850867D02*
Y1853533D01*
G01X61467Y1823563D02*
Y1821063D01*
X63133D01*
G01X66233D02*
X64567D01*
Y1823563D01*
X66233D01*
G01X65567Y1822355D02*
X64567D01*
G01X67583Y1821063D02*
Y1823563D01*
X68417D01*
X68750Y1823438D01*
X69000Y1823271D01*
X69208Y1823021D01*
X69375Y1822730D01*
X69417Y1822313D01*
X69375Y1821896D01*
X69208Y1821605D01*
X69000Y1821355D01*
X68750Y1821188D01*
X68417Y1821063D01*
X67583D01*
G01X71600D02*
Y1823563D01*
X71100Y1823063D01*
G01Y1821063D02*
X72100D01*
G01X74700D02*
Y1823563D01*
X74200Y1823063D01*
G01Y1821063D02*
X75200D01*
G01X63198Y1826279D02*
Y1833879D01*
X74598D01*
Y1826279D01*
X63198D01*
G01X36100Y1863800D02*
X49100D01*
G01X36100Y1889800D02*
Y1863800D01*
G01X49100D02*
Y1889800D01*
G01X93173Y1839449D02*
Y1841949D01*
X94214D01*
X94548Y1841824D01*
X94756Y1841657D01*
X94839Y1841324D01*
X94756Y1840991D01*
X94506Y1840782D01*
X94214Y1840657D01*
X93173D01*
G01X94214D02*
X94839Y1839449D01*
G01X96314Y1841532D02*
X96564Y1841782D01*
X96856Y1841907D01*
X97189Y1841949D01*
X97606Y1841866D01*
X97898Y1841657D01*
X97981Y1841407D01*
X97939Y1841157D01*
X97773Y1840949D01*
X96939Y1840532D01*
X96564Y1840241D01*
X96314Y1839824D01*
X96231Y1839449D01*
X97981D01*
G01X100706D02*
Y1841949D01*
X99164Y1840157D01*
X101248D01*
G01X103306Y1841949D02*
X102973Y1841866D01*
X102723Y1841657D01*
X102556Y1841407D01*
X102431Y1841074D01*
X102389Y1840699D01*
X102431Y1840324D01*
X102556Y1839991D01*
X102723Y1839741D01*
X102973Y1839532D01*
X103306Y1839449D01*
X103639Y1839532D01*
X103889Y1839741D01*
X104056Y1839991D01*
X104181Y1840324D01*
X104223Y1840699D01*
X104181Y1841074D01*
X104056Y1841407D01*
X103889Y1841657D01*
X103639Y1841866D01*
X103306Y1841949D01*
G01X79199Y1835550D02*
Y1839550D01*
X71799D01*
G01X94266Y1827113D02*
Y1829613D01*
X95307D01*
X95641Y1829488D01*
X95849Y1829321D01*
X95932Y1828988D01*
X95849Y1828655D01*
X95599Y1828446D01*
X95307Y1828321D01*
X94266D01*
G01X95307D02*
X95932Y1827113D01*
G01X97407Y1829196D02*
X97657Y1829446D01*
X97949Y1829571D01*
X98282Y1829613D01*
X98699Y1829530D01*
X98991Y1829321D01*
X99074Y1829071D01*
X99032Y1828821D01*
X98866Y1828613D01*
X98032Y1828196D01*
X97657Y1827905D01*
X97407Y1827488D01*
X97324Y1827113D01*
X99074D01*
G01X101799D02*
Y1829613D01*
X100257Y1827821D01*
X102341D01*
G01X104399Y1827113D02*
Y1829613D01*
X103899Y1829113D01*
G01Y1827113D02*
X104899D01*
G01X87949Y1826613D02*
Y1830613D01*
X80549D01*
G01X88376Y1846973D02*
Y1849473D01*
X89417D01*
X89751Y1849348D01*
X89959Y1849181D01*
X90042Y1848848D01*
X89959Y1848515D01*
X89709Y1848306D01*
X89417Y1848181D01*
X88376D01*
G01X89417D02*
X90042Y1846973D01*
G01X91517Y1849056D02*
X91767Y1849306D01*
X92059Y1849431D01*
X92392Y1849473D01*
X92809Y1849390D01*
X93101Y1849181D01*
X93184Y1848931D01*
X93142Y1848681D01*
X92976Y1848473D01*
X92142Y1848056D01*
X91767Y1847765D01*
X91517Y1847348D01*
X91434Y1846973D01*
X93184D01*
G01X95909D02*
Y1849473D01*
X94367Y1847681D01*
X96451D01*
G01X97717Y1849056D02*
X97967Y1849306D01*
X98259Y1849431D01*
X98592Y1849473D01*
X99009Y1849390D01*
X99301Y1849181D01*
X99384Y1848931D01*
X99342Y1848681D01*
X99176Y1848473D01*
X98342Y1848056D01*
X97967Y1847765D01*
X97717Y1847348D01*
X97634Y1846973D01*
X99384D01*
G01X79449Y1841113D02*
Y1845113D01*
X72049D01*
G01X94266Y1831113D02*
Y1833613D01*
X95307D01*
X95641Y1833488D01*
X95849Y1833321D01*
X95932Y1832988D01*
X95849Y1832655D01*
X95599Y1832446D01*
X95307Y1832321D01*
X94266D01*
G01X95307D02*
X95932Y1831113D01*
G01X97407Y1833196D02*
X97657Y1833446D01*
X97949Y1833571D01*
X98282Y1833613D01*
X98699Y1833530D01*
X98991Y1833321D01*
X99074Y1833071D01*
X99032Y1832821D01*
X98866Y1832613D01*
X98032Y1832196D01*
X97657Y1831905D01*
X97407Y1831488D01*
X97324Y1831113D01*
X99074D01*
G01X101799D02*
Y1833613D01*
X100257Y1831821D01*
X102341D01*
G01X103482Y1831613D02*
X103732Y1831321D01*
X104066Y1831155D01*
X104441Y1831113D01*
X104774Y1831155D01*
X105107Y1831363D01*
X105316Y1831613D01*
X105357Y1831863D01*
X105274Y1832155D01*
X104982Y1832363D01*
X104691Y1832446D01*
X104316D01*
G01X104691D02*
X104941Y1832571D01*
X105149Y1832780D01*
X105232Y1833030D01*
X105149Y1833280D01*
X104941Y1833488D01*
X104566Y1833613D01*
X104191Y1833571D01*
X103816Y1833405D01*
G01X87949Y1830613D02*
Y1834613D01*
X80549D01*
G01X88126Y1850910D02*
Y1853410D01*
X89167D01*
X89501Y1853285D01*
X89709Y1853118D01*
X89792Y1852785D01*
X89709Y1852452D01*
X89459Y1852243D01*
X89167Y1852118D01*
X88126D01*
G01X89167D02*
X89792Y1850910D01*
G01X91267Y1852993D02*
X91517Y1853243D01*
X91809Y1853368D01*
X92142Y1853410D01*
X92559Y1853327D01*
X92851Y1853118D01*
X92934Y1852868D01*
X92892Y1852618D01*
X92726Y1852410D01*
X91892Y1851993D01*
X91517Y1851702D01*
X91267Y1851285D01*
X91184Y1850910D01*
X92934D01*
G01X95659D02*
Y1853410D01*
X94117Y1851618D01*
X96201D01*
G01X98759Y1850910D02*
Y1853410D01*
X97217Y1851618D01*
X99301D01*
G01X79199Y1847050D02*
Y1851050D01*
X71799D01*
G01X28517Y1848000D02*
Y1850500D01*
X29558D01*
X29892Y1850375D01*
X30100Y1850208D01*
X30183Y1849875D01*
X30100Y1849542D01*
X29850Y1849333D01*
X29558Y1849208D01*
X28517D01*
G01X29558D02*
X30183Y1848000D01*
G01X31533Y1848500D02*
X31783Y1848208D01*
X32117Y1848042D01*
X32492Y1848000D01*
X32825Y1848042D01*
X33158Y1848250D01*
X33367Y1848500D01*
X33408Y1848750D01*
X33325Y1849042D01*
X33033Y1849250D01*
X32742Y1849333D01*
X32367D01*
G01X32742D02*
X32992Y1849458D01*
X33200Y1849667D01*
X33283Y1849917D01*
X33200Y1850167D01*
X32992Y1850375D01*
X32617Y1850500D01*
X32242Y1850458D01*
X31867Y1850292D01*
G01X34842Y1848292D02*
X35133Y1848083D01*
X35467Y1848000D01*
X35800Y1848083D01*
X36092Y1848333D01*
X36300Y1848708D01*
X36383Y1849083D01*
Y1849542D01*
X36300Y1849917D01*
X36092Y1850250D01*
X35842Y1850417D01*
X35550Y1850500D01*
X35217Y1850417D01*
X34967Y1850250D01*
X34800Y1850000D01*
X34717Y1849667D01*
X34800Y1849375D01*
X35008Y1849083D01*
X35258Y1848917D01*
X35550Y1848875D01*
X35883Y1848958D01*
X36133Y1849167D01*
X36383Y1849542D01*
G01X38650Y1848000D02*
Y1850500D01*
X38150Y1850000D01*
G01Y1848000D02*
X39150D01*
G01X36299Y1840050D02*
Y1836050D01*
X43699D01*
G01X28516Y1852617D02*
Y1855117D01*
X29557D01*
X29891Y1854992D01*
X30099Y1854825D01*
X30182Y1854492D01*
X30099Y1854159D01*
X29849Y1853950D01*
X29557Y1853825D01*
X28516D01*
G01X29557D02*
X30182Y1852617D01*
G01X31532Y1853117D02*
X31782Y1852825D01*
X32116Y1852659D01*
X32491Y1852617D01*
X32824Y1852659D01*
X33157Y1852867D01*
X33366Y1853117D01*
X33407Y1853367D01*
X33324Y1853659D01*
X33032Y1853867D01*
X32741Y1853950D01*
X32366D01*
G01X32741D02*
X32991Y1854075D01*
X33199Y1854284D01*
X33282Y1854534D01*
X33199Y1854784D01*
X32991Y1854992D01*
X32616Y1855117D01*
X32241Y1855075D01*
X31866Y1854909D01*
G01X34841Y1852909D02*
X35132Y1852700D01*
X35466Y1852617D01*
X35799Y1852700D01*
X36091Y1852950D01*
X36299Y1853325D01*
X36382Y1853700D01*
Y1854159D01*
X36299Y1854534D01*
X36091Y1854867D01*
X35841Y1855034D01*
X35549Y1855117D01*
X35216Y1855034D01*
X34966Y1854867D01*
X34799Y1854617D01*
X34716Y1854284D01*
X34799Y1853992D01*
X35007Y1853700D01*
X35257Y1853534D01*
X35549Y1853492D01*
X35882Y1853575D01*
X36132Y1853784D01*
X36382Y1854159D01*
G01X37857Y1854700D02*
X38107Y1854950D01*
X38399Y1855075D01*
X38732Y1855117D01*
X39149Y1855034D01*
X39441Y1854825D01*
X39524Y1854575D01*
X39482Y1854325D01*
X39316Y1854117D01*
X38482Y1853700D01*
X38107Y1853409D01*
X37857Y1852992D01*
X37774Y1852617D01*
X39524D01*
G01X36299Y1844050D02*
Y1840050D01*
X43699D01*
G01X68816Y1856350D02*
Y1858850D01*
X69857D01*
X70191Y1858725D01*
X70399Y1858558D01*
X70482Y1858225D01*
X70399Y1857892D01*
X70149Y1857683D01*
X69857Y1857558D01*
X68816D01*
G01X69857D02*
X70482Y1856350D01*
G01X71832Y1856725D02*
X72082Y1856517D01*
X72374Y1856392D01*
X72749Y1856350D01*
X73124Y1856433D01*
X73416Y1856600D01*
X73624Y1856892D01*
X73666Y1857225D01*
X73582Y1857558D01*
X73374Y1857767D01*
X73082Y1857933D01*
X72791Y1857975D01*
X72499Y1857933D01*
X72124Y1857767D01*
X72249Y1858850D01*
X73374D01*
G01X75849D02*
X75516Y1858767D01*
X75266Y1858558D01*
X75099Y1858308D01*
X74974Y1857975D01*
X74932Y1857600D01*
X74974Y1857225D01*
X75099Y1856892D01*
X75266Y1856642D01*
X75516Y1856433D01*
X75849Y1856350D01*
X76182Y1856433D01*
X76432Y1856642D01*
X76599Y1856892D01*
X76724Y1857225D01*
X76766Y1857600D01*
X76724Y1857975D01*
X76599Y1858308D01*
X76432Y1858558D01*
X76182Y1858767D01*
X75849Y1858850D01*
G01X78949D02*
X78616Y1858767D01*
X78366Y1858558D01*
X78199Y1858308D01*
X78074Y1857975D01*
X78032Y1857600D01*
X78074Y1857225D01*
X78199Y1856892D01*
X78366Y1856642D01*
X78616Y1856433D01*
X78949Y1856350D01*
X79282Y1856433D01*
X79532Y1856642D01*
X79699Y1856892D01*
X79824Y1857225D01*
X79866Y1857600D01*
X79824Y1857975D01*
X79699Y1858308D01*
X79532Y1858558D01*
X79282Y1858767D01*
X78949Y1858850D01*
G01X61899Y1853900D02*
Y1849900D01*
X69299D01*
G01X28750Y1828700D02*
Y1826200D01*
G01X27792Y1828700D02*
X29708D01*
G01X31017Y1826200D02*
Y1828700D01*
X32017D01*
X32350Y1828575D01*
X32600Y1828283D01*
X32683Y1827950D01*
X32600Y1827617D01*
X32392Y1827367D01*
X32017Y1827242D01*
X31017D01*
G01X34950Y1826200D02*
Y1828700D01*
X34450Y1828200D01*
G01Y1826200D02*
X35450D01*
G01X38050D02*
X38342Y1826242D01*
X38675Y1826367D01*
X38883Y1826575D01*
X38967Y1826867D01*
X38883Y1827158D01*
X38633Y1827408D01*
X38258Y1827533D01*
X37842D01*
X37592Y1827617D01*
X37383Y1827825D01*
X37300Y1828117D01*
X37425Y1828408D01*
X37717Y1828617D01*
X38050Y1828700D01*
X38383Y1828617D01*
X38675Y1828408D01*
X38800Y1828117D01*
X38717Y1827825D01*
X38508Y1827617D01*
X38258Y1827533D01*
X37842D01*
X37467Y1827408D01*
X37217Y1827158D01*
X37133Y1826867D01*
X37217Y1826575D01*
X37425Y1826367D01*
X37758Y1826242D01*
X38050Y1826200D01*
G01X29708Y1814317D02*
X29583Y1814067D01*
X29500Y1813775D01*
Y1813442D01*
X29625Y1813067D01*
X29833Y1812775D01*
X30083Y1812567D01*
X30500Y1812400D01*
X30875Y1812358D01*
X31250Y1812442D01*
X31500Y1812567D01*
X31750Y1812817D01*
X31917Y1813108D01*
X32000Y1813400D01*
Y1813692D01*
X31917Y1813983D01*
X31792Y1814233D01*
X31625Y1814442D01*
G01X32000Y1815542D02*
X29500D01*
X32000Y1817458D01*
X29500D01*
G01X31625Y1818683D02*
X31833Y1818933D01*
X31958Y1819225D01*
X32000Y1819600D01*
X31917Y1819975D01*
X31750Y1820267D01*
X31458Y1820475D01*
X31125Y1820517D01*
X30792Y1820433D01*
X30583Y1820225D01*
X30417Y1819933D01*
X30375Y1819642D01*
X30417Y1819350D01*
X30583Y1818975D01*
X29500Y1819100D01*
Y1820225D01*
G01X72017Y1888700D02*
Y1891200D01*
X73017D01*
X73350Y1891075D01*
X73600Y1890783D01*
X73683Y1890450D01*
X73600Y1890117D01*
X73392Y1889867D01*
X73017Y1889742D01*
X72017D01*
G01X76867Y1890992D02*
X76617Y1891117D01*
X76325Y1891200D01*
X75992D01*
X75617Y1891075D01*
X75325Y1890867D01*
X75117Y1890617D01*
X74950Y1890200D01*
X74908Y1889825D01*
X74992Y1889450D01*
X75117Y1889200D01*
X75367Y1888950D01*
X75658Y1888783D01*
X75950Y1888700D01*
X76242D01*
X76533Y1888783D01*
X76783Y1888908D01*
X76992Y1889075D01*
G01X78133Y1889200D02*
X78383Y1888908D01*
X78717Y1888742D01*
X79092Y1888700D01*
X79425Y1888742D01*
X79758Y1888950D01*
X79967Y1889200D01*
X80008Y1889450D01*
X79925Y1889742D01*
X79633Y1889950D01*
X79342Y1890033D01*
X78967D01*
G01X79342D02*
X79592Y1890158D01*
X79800Y1890367D01*
X79883Y1890617D01*
X79800Y1890867D01*
X79592Y1891075D01*
X79217Y1891200D01*
X78842Y1891158D01*
X78467Y1890992D01*
G01X82150Y1888700D02*
X82442Y1888742D01*
X82775Y1888867D01*
X82983Y1889075D01*
X83067Y1889367D01*
X82983Y1889658D01*
X82733Y1889908D01*
X82358Y1890033D01*
X81942D01*
X81692Y1890117D01*
X81483Y1890325D01*
X81400Y1890617D01*
X81525Y1890908D01*
X81817Y1891117D01*
X82150Y1891200D01*
X82483Y1891117D01*
X82775Y1890908D01*
X82900Y1890617D01*
X82817Y1890325D01*
X82608Y1890117D01*
X82358Y1890033D01*
X81942D01*
X81567Y1889908D01*
X81317Y1889658D01*
X81233Y1889367D01*
X81317Y1889075D01*
X81525Y1888867D01*
X81858Y1888742D01*
X82150Y1888700D01*
G01X76999Y1885850D02*
Y1880350D01*
G01X68999Y1885850D02*
X76999D01*
G01X68999Y1880350D02*
Y1885850D01*
G01Y1868250D02*
Y1873750D01*
G01X76999Y1868250D02*
X68999D01*
G01X76999Y1873750D02*
Y1868250D01*
G01X58717Y1888700D02*
Y1891200D01*
X59717D01*
X60050Y1891075D01*
X60300Y1890783D01*
X60383Y1890450D01*
X60300Y1890117D01*
X60092Y1889867D01*
X59717Y1889742D01*
X58717D01*
G01X63567Y1890992D02*
X63317Y1891117D01*
X63025Y1891200D01*
X62692D01*
X62317Y1891075D01*
X62025Y1890867D01*
X61817Y1890617D01*
X61650Y1890200D01*
X61608Y1889825D01*
X61692Y1889450D01*
X61817Y1889200D01*
X62067Y1888950D01*
X62358Y1888783D01*
X62650Y1888700D01*
X62942D01*
X63233Y1888783D01*
X63483Y1888908D01*
X63692Y1889075D01*
G01X64833Y1889200D02*
X65083Y1888908D01*
X65417Y1888742D01*
X65792Y1888700D01*
X66125Y1888742D01*
X66458Y1888950D01*
X66667Y1889200D01*
X66708Y1889450D01*
X66625Y1889742D01*
X66333Y1889950D01*
X66042Y1890033D01*
X65667D01*
G01X66042D02*
X66292Y1890158D01*
X66500Y1890367D01*
X66583Y1890617D01*
X66500Y1890867D01*
X66292Y1891075D01*
X65917Y1891200D01*
X65542Y1891158D01*
X65167Y1890992D01*
G01X68142Y1888992D02*
X68433Y1888783D01*
X68767Y1888700D01*
X69100Y1888783D01*
X69392Y1889033D01*
X69600Y1889408D01*
X69683Y1889783D01*
Y1890242D01*
X69600Y1890617D01*
X69392Y1890950D01*
X69142Y1891117D01*
X68850Y1891200D01*
X68517Y1891117D01*
X68267Y1890950D01*
X68100Y1890700D01*
X68017Y1890367D01*
X68100Y1890075D01*
X68308Y1889783D01*
X68558Y1889617D01*
X68850Y1889575D01*
X69183Y1889658D01*
X69433Y1889867D01*
X69683Y1890242D01*
G01X67999Y1885350D02*
Y1879850D01*
G01X59999Y1885350D02*
X67999D01*
G01X59999Y1879850D02*
Y1885350D01*
G01Y1867750D02*
Y1873250D01*
G01X67999Y1867750D02*
X59999D01*
G01X67999Y1873250D02*
Y1867750D01*
G01X53000Y1837900D02*
X52958Y1837567D01*
X52792Y1837275D01*
X52542Y1837025D01*
X52250Y1836858D01*
X51917Y1836775D01*
X51583D01*
X51250Y1836858D01*
X50958Y1837025D01*
X50708Y1837275D01*
X50542Y1837567D01*
X50500Y1837900D01*
X50542Y1838233D01*
X50708Y1838525D01*
X50958Y1838775D01*
X51250Y1838942D01*
X51583Y1839025D01*
X51917D01*
X52250Y1838942D01*
X52542Y1838775D01*
X52792Y1838525D01*
X52958Y1838233D01*
X53000Y1837900D01*
G01X52333Y1838233D02*
X53000Y1838733D01*
G01Y1841500D02*
X50500D01*
X52292Y1839958D01*
Y1842042D01*
G01X53000Y1844600D02*
X50500D01*
X52292Y1843058D01*
Y1845142D01*
G01X71199Y1849100D02*
X57199D01*
G01X71199Y1836100D02*
Y1849100D01*
G01X57199Y1836100D02*
X71199D01*
G01X57199Y1849100D02*
Y1836100D01*
G01X84299Y1881550D02*
X95499D01*
G01X84299Y1899550D02*
Y1881550D01*
G01Y1861050D02*
X95499D01*
G01X84299Y1879050D02*
Y1861050D01*
G01X95499Y1879050D02*
X84299D01*
G01X61217Y1901200D02*
Y1903700D01*
X62217D01*
X62550Y1903575D01*
X62800Y1903283D01*
X62883Y1902950D01*
X62800Y1902617D01*
X62592Y1902367D01*
X62217Y1902242D01*
X61217D01*
G01X66067Y1903492D02*
X65817Y1903617D01*
X65525Y1903700D01*
X65192D01*
X64817Y1903575D01*
X64525Y1903367D01*
X64317Y1903117D01*
X64150Y1902700D01*
X64108Y1902325D01*
X64192Y1901950D01*
X64317Y1901700D01*
X64567Y1901450D01*
X64858Y1901283D01*
X65150Y1901200D01*
X65442D01*
X65733Y1901283D01*
X65983Y1901408D01*
X66192Y1901575D01*
G01X67333Y1901700D02*
X67583Y1901408D01*
X67917Y1901242D01*
X68292Y1901200D01*
X68625Y1901242D01*
X68958Y1901450D01*
X69167Y1901700D01*
X69208Y1901950D01*
X69125Y1902242D01*
X68833Y1902450D01*
X68542Y1902533D01*
X68167D01*
G01X68542D02*
X68792Y1902658D01*
X69000Y1902867D01*
X69083Y1903117D01*
X69000Y1903367D01*
X68792Y1903575D01*
X68417Y1903700D01*
X68042Y1903658D01*
X67667Y1903492D01*
G01X71850Y1901200D02*
Y1903700D01*
X70308Y1901908D01*
X72392D01*
G01X51617Y1917600D02*
Y1920100D01*
X52617D01*
X52950Y1919975D01*
X53200Y1919683D01*
X53283Y1919350D01*
X53200Y1919017D01*
X52992Y1918767D01*
X52617Y1918642D01*
X51617D01*
G01X56467Y1919892D02*
X56217Y1920017D01*
X55925Y1920100D01*
X55592D01*
X55217Y1919975D01*
X54925Y1919767D01*
X54717Y1919517D01*
X54550Y1919100D01*
X54508Y1918725D01*
X54592Y1918350D01*
X54717Y1918100D01*
X54967Y1917850D01*
X55258Y1917683D01*
X55550Y1917600D01*
X55842D01*
X56133Y1917683D01*
X56383Y1917808D01*
X56592Y1917975D01*
G01X57733Y1918100D02*
X57983Y1917808D01*
X58317Y1917642D01*
X58692Y1917600D01*
X59025Y1917642D01*
X59358Y1917850D01*
X59567Y1918100D01*
X59608Y1918350D01*
X59525Y1918642D01*
X59233Y1918850D01*
X58942Y1918933D01*
X58567D01*
G01X58942D02*
X59192Y1919058D01*
X59400Y1919267D01*
X59483Y1919517D01*
X59400Y1919767D01*
X59192Y1919975D01*
X58817Y1920100D01*
X58442Y1920058D01*
X58067Y1919892D01*
G01X60833Y1918100D02*
X61083Y1917808D01*
X61417Y1917642D01*
X61792Y1917600D01*
X62125Y1917642D01*
X62458Y1917850D01*
X62667Y1918100D01*
X62708Y1918350D01*
X62625Y1918642D01*
X62333Y1918850D01*
X62042Y1918933D01*
X61667D01*
G01X62042D02*
X62292Y1919058D01*
X62500Y1919267D01*
X62583Y1919517D01*
X62500Y1919767D01*
X62292Y1919975D01*
X61917Y1920100D01*
X61542Y1920058D01*
X61167Y1919892D01*
G01X51617Y1913000D02*
Y1915500D01*
X52617D01*
X52950Y1915375D01*
X53200Y1915083D01*
X53283Y1914750D01*
X53200Y1914417D01*
X52992Y1914167D01*
X52617Y1914042D01*
X51617D01*
G01X56467Y1915292D02*
X56217Y1915417D01*
X55925Y1915500D01*
X55592D01*
X55217Y1915375D01*
X54925Y1915167D01*
X54717Y1914917D01*
X54550Y1914500D01*
X54508Y1914125D01*
X54592Y1913750D01*
X54717Y1913500D01*
X54967Y1913250D01*
X55258Y1913083D01*
X55550Y1913000D01*
X55842D01*
X56133Y1913083D01*
X56383Y1913208D01*
X56592Y1913375D01*
G01X57858Y1915083D02*
X58108Y1915333D01*
X58400Y1915458D01*
X58733Y1915500D01*
X59150Y1915417D01*
X59442Y1915208D01*
X59525Y1914958D01*
X59483Y1914708D01*
X59317Y1914500D01*
X58483Y1914083D01*
X58108Y1913792D01*
X57858Y1913375D01*
X57775Y1913000D01*
X59525D01*
G01X61750D02*
X62042Y1913042D01*
X62375Y1913167D01*
X62583Y1913375D01*
X62667Y1913667D01*
X62583Y1913958D01*
X62333Y1914208D01*
X61958Y1914333D01*
X61542D01*
X61292Y1914417D01*
X61083Y1914625D01*
X61000Y1914917D01*
X61125Y1915208D01*
X61417Y1915417D01*
X61750Y1915500D01*
X62083Y1915417D01*
X62375Y1915208D01*
X62500Y1914917D01*
X62417Y1914625D01*
X62208Y1914417D01*
X61958Y1914333D01*
X61542D01*
X61167Y1914208D01*
X60917Y1913958D01*
X60833Y1913667D01*
X60917Y1913375D01*
X61125Y1913167D01*
X61458Y1913042D01*
X61750Y1913000D01*
G01X37017Y1891900D02*
Y1894400D01*
X38058D01*
X38392Y1894275D01*
X38600Y1894108D01*
X38683Y1893775D01*
X38600Y1893442D01*
X38350Y1893233D01*
X38058Y1893108D01*
X37017D01*
G01X38058D02*
X38683Y1891900D01*
G01X40158Y1892942D02*
X40450Y1893233D01*
X40700Y1893400D01*
X41033Y1893483D01*
X41325Y1893400D01*
X41533Y1893233D01*
X41700Y1892983D01*
X41742Y1892692D01*
X41700Y1892442D01*
X41533Y1892192D01*
X41283Y1891983D01*
X40992Y1891900D01*
X40658Y1891983D01*
X40367Y1892233D01*
X40200Y1892608D01*
X40158Y1893025D01*
X40242Y1893567D01*
X40367Y1893858D01*
X40575Y1894150D01*
X40867Y1894358D01*
X41158Y1894400D01*
X41450Y1894317D01*
X41658Y1894108D01*
G01X44050Y1894400D02*
X43717Y1894317D01*
X43467Y1894108D01*
X43300Y1893858D01*
X43175Y1893525D01*
X43133Y1893150D01*
X43175Y1892775D01*
X43300Y1892442D01*
X43467Y1892192D01*
X43717Y1891983D01*
X44050Y1891900D01*
X44383Y1891983D01*
X44633Y1892192D01*
X44800Y1892442D01*
X44925Y1892775D01*
X44967Y1893150D01*
X44925Y1893525D01*
X44800Y1893858D01*
X44633Y1894108D01*
X44383Y1894317D01*
X44050Y1894400D01*
G01X47150Y1891900D02*
X47442Y1891942D01*
X47775Y1892067D01*
X47983Y1892275D01*
X48067Y1892567D01*
X47983Y1892858D01*
X47733Y1893108D01*
X47358Y1893233D01*
X46942D01*
X46692Y1893317D01*
X46483Y1893525D01*
X46400Y1893817D01*
X46525Y1894108D01*
X46817Y1894317D01*
X47150Y1894400D01*
X47483Y1894317D01*
X47775Y1894108D01*
X47900Y1893817D01*
X47817Y1893525D01*
X47608Y1893317D01*
X47358Y1893233D01*
X46942D01*
X46567Y1893108D01*
X46317Y1892858D01*
X46233Y1892567D01*
X46317Y1892275D01*
X46525Y1892067D01*
X46858Y1891942D01*
X47150Y1891900D01*
G01X49100Y1889800D02*
X36100D01*
G01X21999Y1962850D02*
X25999D01*
Y1970250D01*
G01X49900Y1912917D02*
X47400D01*
Y1913917D01*
X47525Y1914250D01*
X47817Y1914500D01*
X48150Y1914583D01*
X48483Y1914500D01*
X48733Y1914292D01*
X48858Y1913917D01*
Y1912917D01*
G01X49900Y1916017D02*
X47400D01*
Y1917058D01*
X47525Y1917392D01*
X47692Y1917600D01*
X48025Y1917683D01*
X48358Y1917600D01*
X48567Y1917350D01*
X48692Y1917058D01*
Y1916017D01*
G01Y1917058D02*
X49900Y1917683D01*
G01X49400Y1919033D02*
X49692Y1919283D01*
X49858Y1919617D01*
X49900Y1919992D01*
X49858Y1920325D01*
X49650Y1920658D01*
X49400Y1920867D01*
X49150Y1920908D01*
X48858Y1920825D01*
X48650Y1920533D01*
X48567Y1920242D01*
Y1919867D01*
G01Y1920242D02*
X48442Y1920492D01*
X48233Y1920700D01*
X47983Y1920783D01*
X47733Y1920700D01*
X47525Y1920492D01*
X47400Y1920117D01*
X47442Y1919742D01*
X47608Y1919367D01*
G01X48858Y1922258D02*
X48567Y1922550D01*
X48400Y1922800D01*
X48317Y1923133D01*
X48400Y1923425D01*
X48567Y1923633D01*
X48817Y1923800D01*
X49108Y1923842D01*
X49358Y1923800D01*
X49608Y1923633D01*
X49817Y1923383D01*
X49900Y1923092D01*
X49817Y1922758D01*
X49567Y1922467D01*
X49192Y1922300D01*
X48775Y1922258D01*
X48233Y1922342D01*
X47942Y1922467D01*
X47650Y1922675D01*
X47442Y1922967D01*
X47400Y1923258D01*
X47483Y1923550D01*
X47692Y1923758D01*
G01X29999Y1916850D02*
X33999D01*
Y1924250D01*
G01X16299Y1946050D02*
Y1942050D01*
X23699D01*
G01X33999Y1977750D02*
X29999D01*
Y1970350D01*
G01X23699Y1946050D02*
Y1950050D01*
X16299D01*
G01X16454Y1959816D02*
X13954D01*
Y1960816D01*
X14079Y1961149D01*
X14371Y1961399D01*
X14704Y1961482D01*
X15037Y1961399D01*
X15287Y1961191D01*
X15412Y1960816D01*
Y1959816D01*
G01X16454Y1962916D02*
X13954D01*
Y1963957D01*
X14079Y1964291D01*
X14246Y1964499D01*
X14579Y1964582D01*
X14912Y1964499D01*
X15121Y1964249D01*
X15246Y1963957D01*
Y1962916D01*
G01Y1963957D02*
X16454Y1964582D01*
G01Y1967349D02*
X13954D01*
X15746Y1965807D01*
Y1967891D01*
G01X16454Y1970449D02*
X13954D01*
X15746Y1968907D01*
Y1970991D01*
G01X33999Y1970250D02*
X29999D01*
Y1962850D01*
G01X23699Y1950050D02*
Y1954050D01*
X16299D01*
G01X25999Y1962850D02*
X29999D01*
Y1970250D01*
G01X21999D02*
X17999D01*
Y1962850D01*
G01X16299Y1938050D02*
Y1934050D01*
X23699D01*
G01X29030Y1930638D02*
X25030D01*
Y1923238D01*
G01X23699Y1938050D02*
Y1942050D01*
X16299D01*
G01X45400Y1899117D02*
X42900D01*
Y1900117D01*
X43025Y1900450D01*
X43317Y1900700D01*
X43650Y1900783D01*
X43983Y1900700D01*
X44233Y1900492D01*
X44358Y1900117D01*
Y1899117D01*
G01X45400Y1902217D02*
X42900D01*
Y1903258D01*
X43025Y1903592D01*
X43192Y1903800D01*
X43525Y1903883D01*
X43858Y1903800D01*
X44067Y1903550D01*
X44192Y1903258D01*
Y1902217D01*
G01Y1903258D02*
X45400Y1903883D01*
G01X45025Y1905233D02*
X45233Y1905483D01*
X45358Y1905775D01*
X45400Y1906150D01*
X45317Y1906525D01*
X45150Y1906817D01*
X44858Y1907025D01*
X44525Y1907067D01*
X44192Y1906983D01*
X43983Y1906775D01*
X43817Y1906483D01*
X43775Y1906192D01*
X43817Y1905900D01*
X43983Y1905525D01*
X42900Y1905650D01*
Y1906775D01*
G01X45400Y1909250D02*
X42900D01*
X43400Y1908750D01*
G01X45400D02*
Y1909750D01*
G01X51499Y1907250D02*
X47499D01*
Y1899850D01*
G01X25030Y1930638D02*
X21030D01*
Y1923238D01*
G01X54150Y1924800D02*
Y1922300D01*
G01X53192Y1924800D02*
X55108D01*
G01X56417Y1922300D02*
Y1924800D01*
X57417D01*
X57750Y1924675D01*
X58000Y1924383D01*
X58083Y1924050D01*
X58000Y1923717D01*
X57792Y1923467D01*
X57417Y1923342D01*
X56417D01*
G01X59558Y1924383D02*
X59808Y1924633D01*
X60100Y1924758D01*
X60433Y1924800D01*
X60850Y1924717D01*
X61142Y1924508D01*
X61225Y1924258D01*
X61183Y1924008D01*
X61017Y1923800D01*
X60183Y1923383D01*
X59808Y1923092D01*
X59558Y1922675D01*
X59475Y1922300D01*
X61225D01*
G01X63950D02*
Y1924800D01*
X62408Y1923008D01*
X64492D01*
G01X54050Y1928700D02*
Y1926200D01*
G01X53092Y1928700D02*
X55008D01*
G01X56317Y1926200D02*
Y1928700D01*
X57317D01*
X57650Y1928575D01*
X57900Y1928283D01*
X57983Y1927950D01*
X57900Y1927617D01*
X57692Y1927367D01*
X57317Y1927242D01*
X56317D01*
G01X59458Y1928283D02*
X59708Y1928533D01*
X60000Y1928658D01*
X60333Y1928700D01*
X60750Y1928617D01*
X61042Y1928408D01*
X61125Y1928158D01*
X61083Y1927908D01*
X60917Y1927700D01*
X60083Y1927283D01*
X59708Y1926992D01*
X59458Y1926575D01*
X59375Y1926200D01*
X61125D01*
G01X63350D02*
Y1928700D01*
X62850Y1928200D01*
G01Y1926200D02*
X63850D01*
G01X61517Y1896800D02*
Y1899300D01*
X62517D01*
X62850Y1899175D01*
X63100Y1898883D01*
X63183Y1898550D01*
X63100Y1898217D01*
X62892Y1897967D01*
X62517Y1897842D01*
X61517D01*
G01X64617Y1896800D02*
Y1899300D01*
X65658D01*
X65992Y1899175D01*
X66200Y1899008D01*
X66283Y1898675D01*
X66200Y1898342D01*
X65950Y1898133D01*
X65658Y1898008D01*
X64617D01*
G01X65658D02*
X66283Y1896800D01*
G01X67633Y1897300D02*
X67883Y1897008D01*
X68217Y1896842D01*
X68592Y1896800D01*
X68925Y1896842D01*
X69258Y1897050D01*
X69467Y1897300D01*
X69508Y1897550D01*
X69425Y1897842D01*
X69133Y1898050D01*
X68842Y1898133D01*
X68467D01*
G01X68842D02*
X69092Y1898258D01*
X69300Y1898467D01*
X69383Y1898717D01*
X69300Y1898967D01*
X69092Y1899175D01*
X68717Y1899300D01*
X68342Y1899258D01*
X67967Y1899092D01*
G01X71567Y1896800D02*
X71650Y1897342D01*
X71775Y1897800D01*
X71942Y1898217D01*
X72150Y1898675D01*
X72483Y1899300D01*
X70817D01*
G01X57699Y1895050D02*
Y1899050D01*
X50299D01*
G01X62500Y1941667D02*
X60000D01*
Y1942667D01*
X60125Y1943000D01*
X60417Y1943250D01*
X60750Y1943333D01*
X61083Y1943250D01*
X61333Y1943042D01*
X61458Y1942667D01*
Y1941667D01*
G01X60000Y1944683D02*
X61792D01*
X62167Y1944850D01*
X62417Y1945183D01*
X62500Y1945600D01*
X62417Y1946017D01*
X62167Y1946350D01*
X61792Y1946517D01*
X60000D01*
G01X62000Y1947783D02*
X62292Y1948033D01*
X62458Y1948367D01*
X62500Y1948742D01*
X62458Y1949075D01*
X62250Y1949408D01*
X62000Y1949617D01*
X61750Y1949658D01*
X61458Y1949575D01*
X61250Y1949283D01*
X61167Y1948992D01*
Y1948617D01*
G01Y1948992D02*
X61042Y1949242D01*
X60833Y1949450D01*
X60583Y1949533D01*
X60333Y1949450D01*
X60125Y1949242D01*
X60000Y1948867D01*
X60042Y1948492D01*
X60208Y1948117D01*
G01X35368Y1960562D02*
X30368D01*
Y1955562D01*
G01X58368D02*
Y1960562D01*
X53368D01*
G01Y1932862D02*
X58368D01*
Y1937862D01*
G01X38462Y1959555D02*
Y1962555D01*
G01X48305Y1959555D02*
Y1961555D01*
G01X52242Y1933869D02*
Y1930869D01*
G01X42399Y1933869D02*
Y1931869D01*
G01X118599Y1908850D02*
Y1950250D01*
X68399D01*
Y1908850D01*
X118599D01*
G01X95499Y1899550D02*
X84299D01*
G01X34790Y1908749D02*
Y1911249D01*
G01X36540D02*
Y1908749D01*
G01Y1909999D02*
X34790D01*
G01X37973Y1910832D02*
X38223Y1911082D01*
X38515Y1911207D01*
X38848Y1911249D01*
X39265Y1911166D01*
X39557Y1910957D01*
X39640Y1910707D01*
X39598Y1910457D01*
X39432Y1910249D01*
X38598Y1909832D01*
X38223Y1909541D01*
X37973Y1909124D01*
X37890Y1908749D01*
X39640D01*
G01X45700Y1978817D02*
X43200D01*
Y1979817D01*
X43325Y1980150D01*
X43617Y1980400D01*
X43950Y1980483D01*
X44283Y1980400D01*
X44533Y1980192D01*
X44658Y1979817D01*
Y1978817D01*
G01X43408Y1983667D02*
X43283Y1983417D01*
X43200Y1983125D01*
Y1982792D01*
X43325Y1982417D01*
X43533Y1982125D01*
X43783Y1981917D01*
X44200Y1981750D01*
X44575Y1981708D01*
X44950Y1981792D01*
X45200Y1981917D01*
X45450Y1982167D01*
X45617Y1982458D01*
X45700Y1982750D01*
Y1983042D01*
X45617Y1983333D01*
X45492Y1983583D01*
X45325Y1983792D01*
G01X45200Y1984933D02*
X45492Y1985183D01*
X45658Y1985517D01*
X45700Y1985892D01*
X45658Y1986225D01*
X45450Y1986558D01*
X45200Y1986767D01*
X44950Y1986808D01*
X44658Y1986725D01*
X44450Y1986433D01*
X44367Y1986142D01*
Y1985767D01*
G01Y1986142D02*
X44242Y1986392D01*
X44033Y1986600D01*
X43783Y1986683D01*
X43533Y1986600D01*
X43325Y1986392D01*
X43200Y1986017D01*
X43242Y1985642D01*
X43408Y1985267D01*
G01X43200Y1988950D02*
X43283Y1988617D01*
X43492Y1988367D01*
X43742Y1988200D01*
X44075Y1988075D01*
X44450Y1988033D01*
X44825Y1988075D01*
X45158Y1988200D01*
X45408Y1988367D01*
X45617Y1988617D01*
X45700Y1988950D01*
X45617Y1989283D01*
X45408Y1989533D01*
X45158Y1989700D01*
X44825Y1989825D01*
X44450Y1989867D01*
X44075Y1989825D01*
X43742Y1989700D01*
X43492Y1989533D01*
X43283Y1989283D01*
X43200Y1988950D01*
G01X28500Y1979017D02*
X26000D01*
Y1980017D01*
X26125Y1980350D01*
X26417Y1980600D01*
X26750Y1980683D01*
X27083Y1980600D01*
X27333Y1980392D01*
X27458Y1980017D01*
Y1979017D01*
G01X28500Y1982117D02*
X26000D01*
Y1983158D01*
X26125Y1983492D01*
X26292Y1983700D01*
X26625Y1983783D01*
X26958Y1983700D01*
X27167Y1983450D01*
X27292Y1983158D01*
Y1982117D01*
G01Y1983158D02*
X28500Y1983783D01*
G01Y1986550D02*
X26000D01*
X27792Y1985008D01*
Y1987092D01*
G01X26417Y1988358D02*
X26167Y1988608D01*
X26042Y1988900D01*
X26000Y1989233D01*
X26083Y1989650D01*
X26292Y1989942D01*
X26542Y1990025D01*
X26792Y1989983D01*
X27000Y1989817D01*
X27417Y1988983D01*
X27708Y1988608D01*
X28125Y1988358D01*
X28500Y1988275D01*
Y1990025D01*
G01X51400Y1979017D02*
X48900D01*
Y1980017D01*
X49025Y1980350D01*
X49317Y1980600D01*
X49650Y1980683D01*
X49983Y1980600D01*
X50233Y1980392D01*
X50358Y1980017D01*
Y1979017D01*
G01X51400Y1982117D02*
X48900D01*
Y1983158D01*
X49025Y1983492D01*
X49192Y1983700D01*
X49525Y1983783D01*
X49858Y1983700D01*
X50067Y1983450D01*
X50192Y1983158D01*
Y1982117D01*
G01Y1983158D02*
X51400Y1983783D01*
G01X50900Y1985133D02*
X51192Y1985383D01*
X51358Y1985717D01*
X51400Y1986092D01*
X51358Y1986425D01*
X51150Y1986758D01*
X50900Y1986967D01*
X50650Y1987008D01*
X50358Y1986925D01*
X50150Y1986633D01*
X50067Y1986342D01*
Y1985967D01*
G01Y1986342D02*
X49942Y1986592D01*
X49733Y1986800D01*
X49483Y1986883D01*
X49233Y1986800D01*
X49025Y1986592D01*
X48900Y1986217D01*
X48942Y1985842D01*
X49108Y1985467D01*
G01X51025Y1988233D02*
X51233Y1988483D01*
X51358Y1988775D01*
X51400Y1989150D01*
X51317Y1989525D01*
X51150Y1989817D01*
X50858Y1990025D01*
X50525Y1990067D01*
X50192Y1989983D01*
X49983Y1989775D01*
X49817Y1989483D01*
X49775Y1989192D01*
X49817Y1988900D01*
X49983Y1988525D01*
X48900Y1988650D01*
Y1989775D01*
G01X33400Y1979617D02*
X30900D01*
Y1980617D01*
X31025Y1980950D01*
X31317Y1981200D01*
X31650Y1981283D01*
X31983Y1981200D01*
X32233Y1980992D01*
X32358Y1980617D01*
Y1979617D01*
G01X31108Y1984467D02*
X30983Y1984217D01*
X30900Y1983925D01*
Y1983592D01*
X31025Y1983217D01*
X31233Y1982925D01*
X31483Y1982717D01*
X31900Y1982550D01*
X32275Y1982508D01*
X32650Y1982592D01*
X32900Y1982717D01*
X33150Y1982967D01*
X33317Y1983258D01*
X33400Y1983550D01*
Y1983842D01*
X33317Y1984133D01*
X33192Y1984383D01*
X33025Y1984592D01*
G01X32900Y1985733D02*
X33192Y1985983D01*
X33358Y1986317D01*
X33400Y1986692D01*
X33358Y1987025D01*
X33150Y1987358D01*
X32900Y1987567D01*
X32650Y1987608D01*
X32358Y1987525D01*
X32150Y1987233D01*
X32067Y1986942D01*
Y1986567D01*
G01Y1986942D02*
X31942Y1987192D01*
X31733Y1987400D01*
X31483Y1987483D01*
X31233Y1987400D01*
X31025Y1987192D01*
X30900Y1986817D01*
X30942Y1986442D01*
X31108Y1986067D01*
G01X32358Y1988958D02*
X32067Y1989250D01*
X31900Y1989500D01*
X31817Y1989833D01*
X31900Y1990125D01*
X32067Y1990333D01*
X32317Y1990500D01*
X32608Y1990542D01*
X32858Y1990500D01*
X33108Y1990333D01*
X33317Y1990083D01*
X33400Y1989792D01*
X33317Y1989458D01*
X33067Y1989167D01*
X32692Y1989000D01*
X32275Y1988958D01*
X31733Y1989042D01*
X31442Y1989167D01*
X31150Y1989375D01*
X30942Y1989667D01*
X30900Y1989958D01*
X30983Y1990250D01*
X31192Y1990458D01*
G01X19288Y1980567D02*
X16788D01*
Y1981567D01*
X16913Y1981900D01*
X17205Y1982150D01*
X17538Y1982233D01*
X17871Y1982150D01*
X18121Y1981942D01*
X18246Y1981567D01*
Y1980567D01*
G01X18038Y1984750D02*
Y1985583D01*
X18788D01*
X19038Y1985333D01*
X19205Y1985042D01*
X19288Y1984625D01*
X19205Y1984208D01*
X19038Y1983917D01*
X18788Y1983667D01*
X18496Y1983500D01*
X18163Y1983417D01*
X17871D01*
X17621Y1983500D01*
X17330Y1983667D01*
X17080Y1983917D01*
X16913Y1984167D01*
X16788Y1984500D01*
Y1984792D01*
X16871Y1985125D01*
X17038Y1985375D01*
G01X18788Y1986683D02*
X19080Y1986933D01*
X19246Y1987267D01*
X19288Y1987642D01*
X19246Y1987975D01*
X19038Y1988308D01*
X18788Y1988517D01*
X18538Y1988558D01*
X18246Y1988475D01*
X18038Y1988183D01*
X17955Y1987892D01*
Y1987517D01*
G01Y1987892D02*
X17830Y1988142D01*
X17621Y1988350D01*
X17371Y1988433D01*
X17121Y1988350D01*
X16913Y1988142D01*
X16788Y1987767D01*
X16830Y1987392D01*
X16996Y1987017D01*
G01X66700Y1978717D02*
X64200D01*
Y1979717D01*
X64325Y1980050D01*
X64617Y1980300D01*
X64950Y1980383D01*
X65283Y1980300D01*
X65533Y1980092D01*
X65658Y1979717D01*
Y1978717D01*
G01X64408Y1983567D02*
X64283Y1983317D01*
X64200Y1983025D01*
Y1982692D01*
X64325Y1982317D01*
X64533Y1982025D01*
X64783Y1981817D01*
X65200Y1981650D01*
X65575Y1981608D01*
X65950Y1981692D01*
X66200Y1981817D01*
X66450Y1982067D01*
X66617Y1982358D01*
X66700Y1982650D01*
Y1982942D01*
X66617Y1983233D01*
X66492Y1983483D01*
X66325Y1983692D01*
G01X64617Y1984958D02*
X64367Y1985208D01*
X64242Y1985500D01*
X64200Y1985833D01*
X64283Y1986250D01*
X64492Y1986542D01*
X64742Y1986625D01*
X64992Y1986583D01*
X65200Y1986417D01*
X65617Y1985583D01*
X65908Y1985208D01*
X66325Y1984958D01*
X66700Y1984875D01*
Y1986625D01*
G01X66408Y1988142D02*
X66617Y1988433D01*
X66700Y1988767D01*
X66617Y1989100D01*
X66367Y1989392D01*
X65992Y1989600D01*
X65617Y1989683D01*
X65158D01*
X64783Y1989600D01*
X64450Y1989392D01*
X64283Y1989142D01*
X64200Y1988850D01*
X64283Y1988517D01*
X64450Y1988267D01*
X64700Y1988100D01*
X65033Y1988017D01*
X65325Y1988100D01*
X65617Y1988308D01*
X65783Y1988558D01*
X65825Y1988850D01*
X65742Y1989183D01*
X65533Y1989433D01*
X65158Y1989683D01*
G01X75200Y1978717D02*
X72700D01*
Y1979717D01*
X72825Y1980050D01*
X73117Y1980300D01*
X73450Y1980383D01*
X73783Y1980300D01*
X74033Y1980092D01*
X74158Y1979717D01*
Y1978717D01*
G01X72908Y1983567D02*
X72783Y1983317D01*
X72700Y1983025D01*
Y1982692D01*
X72825Y1982317D01*
X73033Y1982025D01*
X73283Y1981817D01*
X73700Y1981650D01*
X74075Y1981608D01*
X74450Y1981692D01*
X74700Y1981817D01*
X74950Y1982067D01*
X75117Y1982358D01*
X75200Y1982650D01*
Y1982942D01*
X75117Y1983233D01*
X74992Y1983483D01*
X74825Y1983692D01*
G01X74700Y1984833D02*
X74992Y1985083D01*
X75158Y1985417D01*
X75200Y1985792D01*
X75158Y1986125D01*
X74950Y1986458D01*
X74700Y1986667D01*
X74450Y1986708D01*
X74158Y1986625D01*
X73950Y1986333D01*
X73867Y1986042D01*
Y1985667D01*
G01Y1986042D02*
X73742Y1986292D01*
X73533Y1986500D01*
X73283Y1986583D01*
X73033Y1986500D01*
X72825Y1986292D01*
X72700Y1985917D01*
X72742Y1985542D01*
X72908Y1985167D01*
G01X75200Y1988850D02*
X72700D01*
X73200Y1988350D01*
G01X75200D02*
Y1989350D01*
G01X84900Y1978317D02*
X82400D01*
Y1979317D01*
X82525Y1979650D01*
X82817Y1979900D01*
X83150Y1979983D01*
X83483Y1979900D01*
X83733Y1979692D01*
X83858Y1979317D01*
Y1978317D01*
G01X82608Y1983167D02*
X82483Y1982917D01*
X82400Y1982625D01*
Y1982292D01*
X82525Y1981917D01*
X82733Y1981625D01*
X82983Y1981417D01*
X83400Y1981250D01*
X83775Y1981208D01*
X84150Y1981292D01*
X84400Y1981417D01*
X84650Y1981667D01*
X84817Y1981958D01*
X84900Y1982250D01*
Y1982542D01*
X84817Y1982833D01*
X84692Y1983083D01*
X84525Y1983292D01*
G01X84400Y1984433D02*
X84692Y1984683D01*
X84858Y1985017D01*
X84900Y1985392D01*
X84858Y1985725D01*
X84650Y1986058D01*
X84400Y1986267D01*
X84150Y1986308D01*
X83858Y1986225D01*
X83650Y1985933D01*
X83567Y1985642D01*
Y1985267D01*
G01Y1985642D02*
X83442Y1985892D01*
X83233Y1986100D01*
X82983Y1986183D01*
X82733Y1986100D01*
X82525Y1985892D01*
X82400Y1985517D01*
X82442Y1985142D01*
X82608Y1984767D01*
G01X84525Y1987533D02*
X84733Y1987783D01*
X84858Y1988075D01*
X84900Y1988450D01*
X84817Y1988825D01*
X84650Y1989117D01*
X84358Y1989325D01*
X84025Y1989367D01*
X83692Y1989283D01*
X83483Y1989075D01*
X83317Y1988783D01*
X83275Y1988492D01*
X83317Y1988200D01*
X83483Y1987825D01*
X82400Y1987950D01*
Y1989075D01*
G01X57600Y1978817D02*
X55100D01*
Y1979817D01*
X55225Y1980150D01*
X55517Y1980400D01*
X55850Y1980483D01*
X56183Y1980400D01*
X56433Y1980192D01*
X56558Y1979817D01*
Y1978817D01*
G01X55308Y1983667D02*
X55183Y1983417D01*
X55100Y1983125D01*
Y1982792D01*
X55225Y1982417D01*
X55433Y1982125D01*
X55683Y1981917D01*
X56100Y1981750D01*
X56475Y1981708D01*
X56850Y1981792D01*
X57100Y1981917D01*
X57350Y1982167D01*
X57517Y1982458D01*
X57600Y1982750D01*
Y1983042D01*
X57517Y1983333D01*
X57392Y1983583D01*
X57225Y1983792D01*
G01X57100Y1984933D02*
X57392Y1985183D01*
X57558Y1985517D01*
X57600Y1985892D01*
X57558Y1986225D01*
X57350Y1986558D01*
X57100Y1986767D01*
X56850Y1986808D01*
X56558Y1986725D01*
X56350Y1986433D01*
X56267Y1986142D01*
Y1985767D01*
G01Y1986142D02*
X56142Y1986392D01*
X55933Y1986600D01*
X55683Y1986683D01*
X55433Y1986600D01*
X55225Y1986392D01*
X55100Y1986017D01*
X55142Y1985642D01*
X55308Y1985267D01*
G01X57600Y1988867D02*
X57058Y1988950D01*
X56600Y1989075D01*
X56183Y1989242D01*
X55725Y1989450D01*
X55100Y1989783D01*
Y1988117D01*
G01X93400Y1978317D02*
X90900D01*
Y1979317D01*
X91025Y1979650D01*
X91317Y1979900D01*
X91650Y1979983D01*
X91983Y1979900D01*
X92233Y1979692D01*
X92358Y1979317D01*
Y1978317D01*
G01X91108Y1983167D02*
X90983Y1982917D01*
X90900Y1982625D01*
Y1982292D01*
X91025Y1981917D01*
X91233Y1981625D01*
X91483Y1981417D01*
X91900Y1981250D01*
X92275Y1981208D01*
X92650Y1981292D01*
X92900Y1981417D01*
X93150Y1981667D01*
X93317Y1981958D01*
X93400Y1982250D01*
Y1982542D01*
X93317Y1982833D01*
X93192Y1983083D01*
X93025Y1983292D01*
G01X91317Y1984558D02*
X91067Y1984808D01*
X90942Y1985100D01*
X90900Y1985433D01*
X90983Y1985850D01*
X91192Y1986142D01*
X91442Y1986225D01*
X91692Y1986183D01*
X91900Y1986017D01*
X92317Y1985183D01*
X92608Y1984808D01*
X93025Y1984558D01*
X93400Y1984475D01*
Y1986225D01*
G01Y1988367D02*
X92858Y1988450D01*
X92400Y1988575D01*
X91983Y1988742D01*
X91525Y1988950D01*
X90900Y1989283D01*
Y1987617D01*
G01X180100Y41817D02*
X177600D01*
Y42817D01*
X177725Y43150D01*
X178017Y43400D01*
X178350Y43483D01*
X178683Y43400D01*
X178933Y43192D01*
X179058Y42817D01*
Y41817D01*
G01X177808Y46667D02*
X177683Y46417D01*
X177600Y46125D01*
Y45792D01*
X177725Y45417D01*
X177933Y45125D01*
X178183Y44917D01*
X178600Y44750D01*
X178975Y44708D01*
X179350Y44792D01*
X179600Y44917D01*
X179850Y45167D01*
X180017Y45458D01*
X180100Y45750D01*
Y46042D01*
X180017Y46333D01*
X179892Y46583D01*
X179725Y46792D01*
G01X180100Y48850D02*
X177600D01*
X178100Y48350D01*
G01X180100D02*
Y49350D01*
G01X179725Y51033D02*
X179933Y51283D01*
X180058Y51575D01*
X180100Y51950D01*
X180017Y52325D01*
X179850Y52617D01*
X179558Y52825D01*
X179225Y52867D01*
X178892Y52783D01*
X178683Y52575D01*
X178517Y52283D01*
X178475Y51992D01*
X178517Y51700D01*
X178683Y51325D01*
X177600Y51450D01*
Y52575D01*
G01X174043Y55128D02*
Y57628D01*
X175043D01*
X175376Y57503D01*
X175626Y57211D01*
X175709Y56878D01*
X175626Y56545D01*
X175418Y56295D01*
X175043Y56170D01*
X174043D01*
G01X177143Y55128D02*
Y57628D01*
X178184D01*
X178518Y57503D01*
X178726Y57336D01*
X178809Y57003D01*
X178726Y56670D01*
X178476Y56461D01*
X178184Y56336D01*
X177143D01*
G01X178184D02*
X178809Y55128D01*
G01X180284Y57211D02*
X180534Y57461D01*
X180826Y57586D01*
X181159Y57628D01*
X181576Y57545D01*
X181868Y57336D01*
X181951Y57086D01*
X181909Y56836D01*
X181743Y56628D01*
X180909Y56211D01*
X180534Y55920D01*
X180284Y55503D01*
X180201Y55128D01*
X181951D01*
G01X184176Y57628D02*
X183843Y57545D01*
X183593Y57336D01*
X183426Y57086D01*
X183301Y56753D01*
X183259Y56378D01*
X183301Y56003D01*
X183426Y55670D01*
X183593Y55420D01*
X183843Y55211D01*
X184176Y55128D01*
X184509Y55211D01*
X184759Y55420D01*
X184926Y55670D01*
X185051Y56003D01*
X185093Y56378D01*
X185051Y56753D01*
X184926Y57086D01*
X184759Y57336D01*
X184509Y57545D01*
X184176Y57628D01*
G01X174089Y63272D02*
Y65772D01*
X175089D01*
X175422Y65647D01*
X175672Y65355D01*
X175755Y65022D01*
X175672Y64689D01*
X175464Y64439D01*
X175089Y64314D01*
X174089D01*
G01X177189Y63272D02*
Y65772D01*
X178230D01*
X178564Y65647D01*
X178772Y65480D01*
X178855Y65147D01*
X178772Y64814D01*
X178522Y64605D01*
X178230Y64480D01*
X177189D01*
G01X178230D02*
X178855Y63272D01*
G01X180205Y63772D02*
X180455Y63480D01*
X180789Y63314D01*
X181164Y63272D01*
X181497Y63314D01*
X181830Y63522D01*
X182039Y63772D01*
X182080Y64022D01*
X181997Y64314D01*
X181705Y64522D01*
X181414Y64605D01*
X181039D01*
G01X181414D02*
X181664Y64730D01*
X181872Y64939D01*
X181955Y65189D01*
X181872Y65439D01*
X181664Y65647D01*
X181289Y65772D01*
X180914Y65730D01*
X180539Y65564D01*
G01X184222Y63272D02*
Y65772D01*
X183722Y65272D01*
G01Y63272D02*
X184722D01*
G01X173917Y58900D02*
Y61400D01*
X174917D01*
X175250Y61275D01*
X175500Y60983D01*
X175583Y60650D01*
X175500Y60317D01*
X175292Y60067D01*
X174917Y59942D01*
X173917D01*
G01X177017Y58900D02*
Y61400D01*
X178058D01*
X178392Y61275D01*
X178600Y61108D01*
X178683Y60775D01*
X178600Y60442D01*
X178350Y60233D01*
X178058Y60108D01*
X177017D01*
G01X178058D02*
X178683Y58900D01*
G01X180033Y59400D02*
X180283Y59108D01*
X180617Y58942D01*
X180992Y58900D01*
X181325Y58942D01*
X181658Y59150D01*
X181867Y59400D01*
X181908Y59650D01*
X181825Y59942D01*
X181533Y60150D01*
X181242Y60233D01*
X180867D01*
G01X181242D02*
X181492Y60358D01*
X181700Y60567D01*
X181783Y60817D01*
X181700Y61067D01*
X181492Y61275D01*
X181117Y61400D01*
X180742Y61358D01*
X180367Y61192D01*
G01X183258Y60983D02*
X183508Y61233D01*
X183800Y61358D01*
X184133Y61400D01*
X184550Y61317D01*
X184842Y61108D01*
X184925Y60858D01*
X184883Y60608D01*
X184717Y60400D01*
X183883Y59983D01*
X183508Y59692D01*
X183258Y59275D01*
X183175Y58900D01*
X184925D01*
G01X175600Y41817D02*
X173100D01*
Y42817D01*
X173225Y43150D01*
X173517Y43400D01*
X173850Y43483D01*
X174183Y43400D01*
X174433Y43192D01*
X174558Y42817D01*
Y41817D01*
G01X175600Y44917D02*
X173100D01*
Y45958D01*
X173225Y46292D01*
X173392Y46500D01*
X173725Y46583D01*
X174058Y46500D01*
X174267Y46250D01*
X174392Y45958D01*
Y44917D01*
G01Y45958D02*
X175600Y46583D01*
G01X175225Y47933D02*
X175433Y48183D01*
X175558Y48475D01*
X175600Y48850D01*
X175517Y49225D01*
X175350Y49517D01*
X175058Y49725D01*
X174725Y49767D01*
X174392Y49683D01*
X174183Y49475D01*
X174017Y49183D01*
X173975Y48892D01*
X174017Y48600D01*
X174183Y48225D01*
X173100Y48350D01*
Y49475D01*
G01Y51950D02*
X173183Y51617D01*
X173392Y51367D01*
X173642Y51200D01*
X173975Y51075D01*
X174350Y51033D01*
X174725Y51075D01*
X175058Y51200D01*
X175308Y51367D01*
X175517Y51617D01*
X175600Y51950D01*
X175517Y52283D01*
X175308Y52533D01*
X175058Y52700D01*
X174725Y52825D01*
X174350Y52867D01*
X173975Y52825D01*
X173642Y52700D01*
X173392Y52533D01*
X173183Y52283D01*
X173100Y51950D01*
G01X100499Y35400D02*
X102999D01*
G01X100499Y34442D02*
Y36358D01*
G01X102999Y37667D02*
X100499D01*
Y38667D01*
X100624Y39000D01*
X100916Y39250D01*
X101249Y39333D01*
X101582Y39250D01*
X101832Y39042D01*
X101957Y38667D01*
Y37667D01*
G01X102499Y40683D02*
X102791Y40933D01*
X102957Y41267D01*
X102999Y41642D01*
X102957Y41975D01*
X102749Y42308D01*
X102499Y42517D01*
X102249Y42558D01*
X101957Y42475D01*
X101749Y42183D01*
X101666Y41892D01*
Y41517D01*
G01Y41892D02*
X101541Y42142D01*
X101332Y42350D01*
X101082Y42433D01*
X100832Y42350D01*
X100624Y42142D01*
X100499Y41767D01*
X100541Y41392D01*
X100707Y41017D01*
G01X102707Y43992D02*
X102916Y44283D01*
X102999Y44617D01*
X102916Y44950D01*
X102666Y45242D01*
X102291Y45450D01*
X101916Y45533D01*
X101457D01*
X101082Y45450D01*
X100749Y45242D01*
X100582Y44992D01*
X100499Y44700D01*
X100582Y44367D01*
X100749Y44117D01*
X100999Y43950D01*
X101332Y43867D01*
X101624Y43950D01*
X101916Y44158D01*
X102082Y44408D01*
X102124Y44700D01*
X102041Y45033D01*
X101832Y45283D01*
X101457Y45533D01*
G01X147767Y40500D02*
Y43000D01*
X148767D01*
X149100Y42875D01*
X149350Y42583D01*
X149433Y42250D01*
X149350Y41917D01*
X149142Y41667D01*
X148767Y41542D01*
X147767D01*
G01X150867Y43000D02*
Y40500D01*
X152533D01*
G01X155300D02*
Y43000D01*
X153758Y41208D01*
X155842D01*
G01X164699Y96650D02*
X123299D01*
Y46450D01*
X164699D01*
Y96650D01*
G01X115437Y40641D02*
Y43141D01*
G01X117187D02*
Y40641D01*
G01Y41891D02*
X115437D01*
G01X118495Y41016D02*
X118745Y40808D01*
X119037Y40683D01*
X119412Y40641D01*
X119787Y40724D01*
X120079Y40891D01*
X120287Y41183D01*
X120329Y41516D01*
X120245Y41849D01*
X120037Y42058D01*
X119745Y42224D01*
X119454Y42266D01*
X119162Y42224D01*
X118787Y42058D01*
X118912Y43141D01*
X120037D01*
G01X102266Y137842D02*
X102016Y137967D01*
X101724Y138050D01*
X101391D01*
X101016Y137925D01*
X100724Y137717D01*
X100516Y137467D01*
X100349Y137050D01*
X100307Y136675D01*
X100391Y136300D01*
X100516Y136050D01*
X100766Y135800D01*
X101057Y135633D01*
X101349Y135550D01*
X101641D01*
X101932Y135633D01*
X102182Y135758D01*
X102391Y135925D01*
G01X103532Y136050D02*
X103782Y135758D01*
X104116Y135592D01*
X104491Y135550D01*
X104824Y135592D01*
X105157Y135800D01*
X105366Y136050D01*
X105407Y136300D01*
X105324Y136592D01*
X105032Y136800D01*
X104741Y136883D01*
X104366D01*
G01X104741D02*
X104991Y137008D01*
X105199Y137217D01*
X105282Y137467D01*
X105199Y137717D01*
X104991Y137925D01*
X104616Y138050D01*
X104241Y138008D01*
X103866Y137842D01*
G01X106757Y137633D02*
X107007Y137883D01*
X107299Y138008D01*
X107632Y138050D01*
X108049Y137967D01*
X108341Y137758D01*
X108424Y137508D01*
X108382Y137258D01*
X108216Y137050D01*
X107382Y136633D01*
X107007Y136342D01*
X106757Y135925D01*
X106674Y135550D01*
X108424D01*
G01X110649D02*
X110941Y135592D01*
X111274Y135717D01*
X111482Y135925D01*
X111566Y136217D01*
X111482Y136508D01*
X111232Y136758D01*
X110857Y136883D01*
X110441D01*
X110191Y136967D01*
X109982Y137175D01*
X109899Y137467D01*
X110024Y137758D01*
X110316Y137967D01*
X110649Y138050D01*
X110982Y137967D01*
X111274Y137758D01*
X111399Y137467D01*
X111316Y137175D01*
X111107Y136967D01*
X110857Y136883D01*
X110441D01*
X110066Y136758D01*
X109816Y136508D01*
X109732Y136217D01*
X109816Y135925D01*
X110024Y135717D01*
X110357Y135592D01*
X110649Y135550D01*
G01X102266Y134342D02*
X102016Y134467D01*
X101724Y134550D01*
X101391D01*
X101016Y134425D01*
X100724Y134217D01*
X100516Y133967D01*
X100349Y133550D01*
X100307Y133175D01*
X100391Y132800D01*
X100516Y132550D01*
X100766Y132300D01*
X101057Y132133D01*
X101349Y132050D01*
X101641D01*
X101932Y132133D01*
X102182Y132258D01*
X102391Y132425D01*
G01X103532Y132550D02*
X103782Y132258D01*
X104116Y132092D01*
X104491Y132050D01*
X104824Y132092D01*
X105157Y132300D01*
X105366Y132550D01*
X105407Y132800D01*
X105324Y133092D01*
X105032Y133300D01*
X104741Y133383D01*
X104366D01*
G01X104741D02*
X104991Y133508D01*
X105199Y133717D01*
X105282Y133967D01*
X105199Y134217D01*
X104991Y134425D01*
X104616Y134550D01*
X104241Y134508D01*
X103866Y134342D01*
G01X106757Y134133D02*
X107007Y134383D01*
X107299Y134508D01*
X107632Y134550D01*
X108049Y134467D01*
X108341Y134258D01*
X108424Y134008D01*
X108382Y133758D01*
X108216Y133550D01*
X107382Y133133D01*
X107007Y132842D01*
X106757Y132425D01*
X106674Y132050D01*
X108424D01*
G01X109941Y132342D02*
X110232Y132133D01*
X110566Y132050D01*
X110899Y132133D01*
X111191Y132383D01*
X111399Y132758D01*
X111482Y133133D01*
Y133592D01*
X111399Y133967D01*
X111191Y134300D01*
X110941Y134467D01*
X110649Y134550D01*
X110316Y134467D01*
X110066Y134300D01*
X109899Y134050D01*
X109816Y133717D01*
X109899Y133425D01*
X110107Y133133D01*
X110357Y132967D01*
X110649Y132925D01*
X110982Y133008D01*
X111232Y133217D01*
X111482Y133592D01*
G01X178017Y105400D02*
Y107900D01*
X179017D01*
X179350Y107775D01*
X179600Y107483D01*
X179683Y107150D01*
X179600Y106817D01*
X179392Y106567D01*
X179017Y106442D01*
X178017D01*
G01X182867Y107692D02*
X182617Y107817D01*
X182325Y107900D01*
X181992D01*
X181617Y107775D01*
X181325Y107567D01*
X181117Y107317D01*
X180950Y106900D01*
X180908Y106525D01*
X180992Y106150D01*
X181117Y105900D01*
X181367Y105650D01*
X181658Y105483D01*
X181950Y105400D01*
X182242D01*
X182533Y105483D01*
X182783Y105608D01*
X182992Y105775D01*
G01X184258Y107483D02*
X184508Y107733D01*
X184800Y107858D01*
X185133Y107900D01*
X185550Y107817D01*
X185842Y107608D01*
X185925Y107358D01*
X185883Y107108D01*
X185717Y106900D01*
X184883Y106483D01*
X184508Y106192D01*
X184258Y105775D01*
X184175Y105400D01*
X185925D01*
G01X188150D02*
Y107900D01*
X187650Y107400D01*
G01Y105400D02*
X188650D01*
G01X177426Y84428D02*
Y80428D01*
X184826D01*
G01X184872Y88572D02*
Y92572D01*
X177472D01*
G01X184872Y84572D02*
Y88572D01*
X177472D01*
G01X172999Y69350D02*
X176999D01*
Y76750D01*
G01X177917Y101500D02*
Y104000D01*
X178917D01*
X179250Y103875D01*
X179500Y103583D01*
X179583Y103250D01*
X179500Y102917D01*
X179292Y102667D01*
X178917Y102542D01*
X177917D01*
G01X181017Y101500D02*
Y104000D01*
X182058D01*
X182392Y103875D01*
X182600Y103708D01*
X182683Y103375D01*
X182600Y103042D01*
X182350Y102833D01*
X182058Y102708D01*
X181017D01*
G01X182058D02*
X182683Y101500D01*
G01X184158Y103583D02*
X184408Y103833D01*
X184700Y103958D01*
X185033Y104000D01*
X185450Y103917D01*
X185742Y103708D01*
X185825Y103458D01*
X185783Y103208D01*
X185617Y103000D01*
X184783Y102583D01*
X184408Y102292D01*
X184158Y101875D01*
X184075Y101500D01*
X185825D01*
G01X188550D02*
Y104000D01*
X187008Y102208D01*
X189092D01*
G01X168000Y86050D02*
X170500D01*
G01X168000Y85092D02*
Y87008D01*
G01X170500Y88317D02*
X168000D01*
Y89317D01*
X168125Y89650D01*
X168417Y89900D01*
X168750Y89983D01*
X169083Y89900D01*
X169333Y89692D01*
X169458Y89317D01*
Y88317D01*
G01X168417Y91458D02*
X168167Y91708D01*
X168042Y92000D01*
X168000Y92333D01*
X168083Y92750D01*
X168292Y93042D01*
X168542Y93125D01*
X168792Y93083D01*
X169000Y92917D01*
X169417Y92083D01*
X169708Y91708D01*
X170125Y91458D01*
X170500Y91375D01*
Y93125D01*
G01X170000Y94433D02*
X170292Y94683D01*
X170458Y95017D01*
X170500Y95392D01*
X170458Y95725D01*
X170250Y96058D01*
X170000Y96267D01*
X169750Y96308D01*
X169458Y96225D01*
X169250Y95933D01*
X169167Y95642D01*
Y95267D01*
G01Y95642D02*
X169042Y95892D01*
X168833Y96100D01*
X168583Y96183D01*
X168333Y96100D01*
X168125Y95892D01*
X168000Y95517D01*
X168042Y95142D01*
X168208Y94767D01*
G01X172533Y86200D02*
X175033D01*
G01X172533Y85242D02*
Y87158D01*
G01X175033Y88467D02*
X172533D01*
Y89467D01*
X172658Y89800D01*
X172950Y90050D01*
X173283Y90133D01*
X173616Y90050D01*
X173866Y89842D01*
X173991Y89467D01*
Y88467D01*
G01X172950Y91608D02*
X172700Y91858D01*
X172575Y92150D01*
X172533Y92483D01*
X172616Y92900D01*
X172825Y93192D01*
X173075Y93275D01*
X173325Y93233D01*
X173533Y93067D01*
X173950Y92233D01*
X174241Y91858D01*
X174658Y91608D01*
X175033Y91525D01*
Y93275D01*
G01X172533Y95500D02*
X172616Y95167D01*
X172825Y94917D01*
X173075Y94750D01*
X173408Y94625D01*
X173783Y94583D01*
X174158Y94625D01*
X174491Y94750D01*
X174741Y94917D01*
X174950Y95167D01*
X175033Y95500D01*
X174950Y95833D01*
X174741Y96083D01*
X174491Y96250D01*
X174158Y96375D01*
X173783Y96417D01*
X173408Y96375D01*
X173075Y96250D01*
X172825Y96083D01*
X172616Y95833D01*
X172533Y95500D01*
G01X173600Y128617D02*
X171100D01*
Y129617D01*
X171225Y129950D01*
X171517Y130200D01*
X171850Y130283D01*
X172183Y130200D01*
X172433Y129992D01*
X172558Y129617D01*
Y128617D01*
G01X171308Y133467D02*
X171183Y133217D01*
X171100Y132925D01*
Y132592D01*
X171225Y132217D01*
X171433Y131925D01*
X171683Y131717D01*
X172100Y131550D01*
X172475Y131508D01*
X172850Y131592D01*
X173100Y131717D01*
X173350Y131967D01*
X173517Y132258D01*
X173600Y132550D01*
Y132842D01*
X173517Y133133D01*
X173392Y133383D01*
X173225Y133592D01*
G01X171517Y134858D02*
X171267Y135108D01*
X171142Y135400D01*
X171100Y135733D01*
X171183Y136150D01*
X171392Y136442D01*
X171642Y136525D01*
X171892Y136483D01*
X172100Y136317D01*
X172517Y135483D01*
X172808Y135108D01*
X173225Y134858D01*
X173600Y134775D01*
Y136525D01*
G01X172558Y137958D02*
X172267Y138250D01*
X172100Y138500D01*
X172017Y138833D01*
X172100Y139125D01*
X172267Y139333D01*
X172517Y139500D01*
X172808Y139542D01*
X173058Y139500D01*
X173308Y139333D01*
X173517Y139083D01*
X173600Y138792D01*
X173517Y138458D01*
X173267Y138167D01*
X172892Y138000D01*
X172475Y137958D01*
X171933Y138042D01*
X171642Y138167D01*
X171350Y138375D01*
X171142Y138667D01*
X171100Y138958D01*
X171183Y139250D01*
X171392Y139458D01*
G01X165999Y109250D02*
Y114750D01*
G01X173999Y109250D02*
X165999D01*
G01X173999Y114750D02*
Y109250D01*
G01Y126850D02*
Y121350D01*
G01X165999Y126850D02*
X173999D01*
G01X165999Y121350D02*
Y126850D01*
G01X180300Y129317D02*
X177800D01*
Y130317D01*
X177925Y130650D01*
X178217Y130900D01*
X178550Y130983D01*
X178883Y130900D01*
X179133Y130692D01*
X179258Y130317D01*
Y129317D01*
G01X178008Y134167D02*
X177883Y133917D01*
X177800Y133625D01*
Y133292D01*
X177925Y132917D01*
X178133Y132625D01*
X178383Y132417D01*
X178800Y132250D01*
X179175Y132208D01*
X179550Y132292D01*
X179800Y132417D01*
X180050Y132667D01*
X180217Y132958D01*
X180300Y133250D01*
Y133542D01*
X180217Y133833D01*
X180092Y134083D01*
X179925Y134292D01*
G01X178217Y135558D02*
X177967Y135808D01*
X177842Y136100D01*
X177800Y136433D01*
X177883Y136850D01*
X178092Y137142D01*
X178342Y137225D01*
X178592Y137183D01*
X178800Y137017D01*
X179217Y136183D01*
X179508Y135808D01*
X179925Y135558D01*
X180300Y135475D01*
Y137225D01*
G01X179925Y138533D02*
X180133Y138783D01*
X180258Y139075D01*
X180300Y139450D01*
X180217Y139825D01*
X180050Y140117D01*
X179758Y140325D01*
X179425Y140367D01*
X179092Y140283D01*
X178883Y140075D01*
X178717Y139783D01*
X178675Y139492D01*
X178717Y139200D01*
X178883Y138825D01*
X177800Y138950D01*
Y140075D01*
G01X174999Y109250D02*
Y114750D01*
G01X182999Y109250D02*
X174999D01*
G01Y126850D02*
X182999D01*
G01X174999Y121350D02*
Y126850D01*
G01X153400Y142617D02*
X150900D01*
Y143617D01*
X151025Y143950D01*
X151317Y144200D01*
X151650Y144283D01*
X151983Y144200D01*
X152233Y143992D01*
X152358Y143617D01*
Y142617D01*
G01X150900Y146550D02*
X153400D01*
G01X150900Y145592D02*
Y147508D01*
G01X151108Y150567D02*
X150983Y150317D01*
X150900Y150025D01*
Y149692D01*
X151025Y149317D01*
X151233Y149025D01*
X151483Y148817D01*
X151900Y148650D01*
X152275Y148608D01*
X152650Y148692D01*
X152900Y148817D01*
X153150Y149067D01*
X153317Y149358D01*
X153400Y149650D01*
Y149942D01*
X153317Y150233D01*
X153192Y150483D01*
X153025Y150692D01*
G01X152900Y151833D02*
X153192Y152083D01*
X153358Y152417D01*
X153400Y152792D01*
X153358Y153125D01*
X153150Y153458D01*
X152900Y153667D01*
X152650Y153708D01*
X152358Y153625D01*
X152150Y153333D01*
X152067Y153042D01*
Y152667D01*
G01Y153042D02*
X151942Y153292D01*
X151733Y153500D01*
X151483Y153583D01*
X151233Y153500D01*
X151025Y153292D01*
X150900Y152917D01*
X150942Y152542D01*
X151108Y152167D01*
G01X163521Y100877D02*
Y112077D01*
G01X145521Y100877D02*
X163521D01*
G01X145521Y112077D02*
Y100877D01*
G01X163521Y139277D02*
Y128077D01*
G01X145521Y139277D02*
X163521D01*
G01X145521Y128077D02*
Y139277D01*
G01X135200Y143017D02*
X132700D01*
Y144017D01*
X132825Y144350D01*
X133117Y144600D01*
X133450Y144683D01*
X133783Y144600D01*
X134033Y144392D01*
X134158Y144017D01*
Y143017D01*
G01X132700Y146950D02*
X135200D01*
G01X132700Y145992D02*
Y147908D01*
G01X132908Y150967D02*
X132783Y150717D01*
X132700Y150425D01*
Y150092D01*
X132825Y149717D01*
X133033Y149425D01*
X133283Y149217D01*
X133700Y149050D01*
X134075Y149008D01*
X134450Y149092D01*
X134700Y149217D01*
X134950Y149467D01*
X135117Y149758D01*
X135200Y150050D01*
Y150342D01*
X135117Y150633D01*
X134992Y150883D01*
X134825Y151092D01*
G01X135200Y153650D02*
X132700D01*
X134492Y152108D01*
Y154192D01*
G01X142521Y100877D02*
Y112077D01*
G01X124521Y100877D02*
X142521D01*
G01X124521Y112077D02*
Y100877D01*
G01X142521Y139277D02*
Y128077D01*
G01X124521Y139277D02*
X142521D01*
G01X124521Y128077D02*
Y139277D01*
G01X98967Y114225D02*
X99175Y114558D01*
X99300Y114933D01*
Y115267D01*
X99175Y115600D01*
X98967Y115850D01*
X98675Y115975D01*
X98383Y115892D01*
X98133Y115683D01*
X97967Y115308D01*
X97883Y114808D01*
X97717Y114517D01*
X97425Y114392D01*
X97133Y114475D01*
X96925Y114683D01*
X96800Y114975D01*
Y115267D01*
X96883Y115558D01*
X97092Y115808D01*
G01X99300Y117283D02*
X96800D01*
G01Y118867D02*
X98342Y117283D01*
G01X99300Y119117D02*
X97633Y117992D01*
G01X96800Y121300D02*
X99300D01*
G01X96800Y120342D02*
Y122258D01*
G01X99300Y124400D02*
X96800D01*
X97300Y123900D01*
G01X99300D02*
Y124900D01*
G01X98925Y126583D02*
X99133Y126833D01*
X99258Y127125D01*
X99300Y127500D01*
X99217Y127875D01*
X99050Y128167D01*
X98758Y128375D01*
X98425Y128417D01*
X98092Y128333D01*
X97883Y128125D01*
X97717Y127833D01*
X97675Y127542D01*
X97717Y127250D01*
X97883Y126875D01*
X96800Y127000D01*
Y128125D01*
G01X115266Y225342D02*
X115016Y225467D01*
X114724Y225550D01*
X114391D01*
X114016Y225425D01*
X113724Y225217D01*
X113516Y224967D01*
X113349Y224550D01*
X113307Y224175D01*
X113391Y223800D01*
X113516Y223550D01*
X113766Y223300D01*
X114057Y223133D01*
X114349Y223050D01*
X114641D01*
X114932Y223133D01*
X115182Y223258D01*
X115391Y223425D01*
G01X116657Y225133D02*
X116907Y225383D01*
X117199Y225508D01*
X117532Y225550D01*
X117949Y225467D01*
X118241Y225258D01*
X118324Y225008D01*
X118282Y224758D01*
X118116Y224550D01*
X117282Y224133D01*
X116907Y223842D01*
X116657Y223425D01*
X116574Y223050D01*
X118324D01*
G01X121049D02*
Y225550D01*
X119507Y223758D01*
X121591D01*
G01X122857Y224092D02*
X123149Y224383D01*
X123399Y224550D01*
X123732Y224633D01*
X124024Y224550D01*
X124232Y224383D01*
X124399Y224133D01*
X124441Y223842D01*
X124399Y223592D01*
X124232Y223342D01*
X123982Y223133D01*
X123691Y223050D01*
X123357Y223133D01*
X123066Y223383D01*
X122899Y223758D01*
X122857Y224175D01*
X122941Y224717D01*
X123066Y225008D01*
X123274Y225300D01*
X123566Y225508D01*
X123857Y225550D01*
X124149Y225467D01*
X124357Y225258D01*
G01X114967Y229492D02*
X114717Y229617D01*
X114425Y229700D01*
X114092D01*
X113717Y229575D01*
X113425Y229367D01*
X113217Y229117D01*
X113050Y228700D01*
X113008Y228325D01*
X113092Y227950D01*
X113217Y227700D01*
X113467Y227450D01*
X113758Y227283D01*
X114050Y227200D01*
X114342D01*
X114633Y227283D01*
X114883Y227408D01*
X115092Y227575D01*
G01X116358Y229283D02*
X116608Y229533D01*
X116900Y229658D01*
X117233Y229700D01*
X117650Y229617D01*
X117942Y229408D01*
X118025Y229158D01*
X117983Y228908D01*
X117817Y228700D01*
X116983Y228283D01*
X116608Y227992D01*
X116358Y227575D01*
X116275Y227200D01*
X118025D01*
G01X120750D02*
Y229700D01*
X119208Y227908D01*
X121292D01*
G01X123267Y227200D02*
X123350Y227742D01*
X123475Y228200D01*
X123642Y228617D01*
X123850Y229075D01*
X124183Y229700D01*
X122517D01*
G01X97467Y154492D02*
X97217Y154617D01*
X96925Y154700D01*
X96592D01*
X96217Y154575D01*
X95925Y154367D01*
X95717Y154117D01*
X95550Y153700D01*
X95508Y153325D01*
X95592Y152950D01*
X95717Y152700D01*
X95967Y152450D01*
X96258Y152283D01*
X96550Y152200D01*
X96842D01*
X97133Y152283D01*
X97383Y152408D01*
X97592Y152575D01*
G01X98733Y152700D02*
X98983Y152408D01*
X99317Y152242D01*
X99692Y152200D01*
X100025Y152242D01*
X100358Y152450D01*
X100567Y152700D01*
X100608Y152950D01*
X100525Y153242D01*
X100233Y153450D01*
X99942Y153533D01*
X99567D01*
G01X99942D02*
X100192Y153658D01*
X100400Y153867D01*
X100483Y154117D01*
X100400Y154367D01*
X100192Y154575D01*
X99817Y154700D01*
X99442Y154658D01*
X99067Y154492D01*
G01X101958Y154283D02*
X102208Y154533D01*
X102500Y154658D01*
X102833Y154700D01*
X103250Y154617D01*
X103542Y154408D01*
X103625Y154158D01*
X103583Y153908D01*
X103417Y153700D01*
X102583Y153283D01*
X102208Y152992D01*
X101958Y152575D01*
X101875Y152200D01*
X103625D01*
G01X105058Y153242D02*
X105350Y153533D01*
X105600Y153700D01*
X105933Y153783D01*
X106225Y153700D01*
X106433Y153533D01*
X106600Y153283D01*
X106642Y152992D01*
X106600Y152742D01*
X106433Y152492D01*
X106183Y152283D01*
X105892Y152200D01*
X105558Y152283D01*
X105267Y152533D01*
X105100Y152908D01*
X105058Y153325D01*
X105142Y153867D01*
X105267Y154158D01*
X105475Y154450D01*
X105767Y154658D01*
X106058Y154700D01*
X106350Y154617D01*
X106558Y154408D01*
G01X159967Y170563D02*
Y168063D01*
X161633D01*
G01X164733D02*
X163067D01*
Y170563D01*
X164733D01*
G01X164067Y169355D02*
X163067D01*
G01X166083Y168063D02*
Y170563D01*
X166917D01*
X167250Y170438D01*
X167500Y170271D01*
X167708Y170021D01*
X167875Y169730D01*
X167917Y169313D01*
X167875Y168896D01*
X167708Y168605D01*
X167500Y168355D01*
X167250Y168188D01*
X166917Y168063D01*
X166083D01*
G01X170100D02*
Y170563D01*
X169600Y170063D01*
G01Y168063D02*
X170600D01*
G01X173200Y170563D02*
X172867Y170480D01*
X172617Y170271D01*
X172450Y170021D01*
X172325Y169688D01*
X172283Y169313D01*
X172325Y168938D01*
X172450Y168605D01*
X172617Y168355D01*
X172867Y168146D01*
X173200Y168063D01*
X173533Y168146D01*
X173783Y168355D01*
X173950Y168605D01*
X174075Y168938D01*
X174117Y169313D01*
X174075Y169688D01*
X173950Y170021D01*
X173783Y170271D01*
X173533Y170480D01*
X173200Y170563D01*
G01X173023Y165847D02*
Y158247D01*
X161623D01*
Y165847D01*
X173023D01*
G01X174799Y167050D02*
Y163050D01*
X182199D01*
G01X138116Y177150D02*
Y179650D01*
X139157D01*
X139491Y179525D01*
X139699Y179358D01*
X139782Y179025D01*
X139699Y178692D01*
X139449Y178483D01*
X139157Y178358D01*
X138116D01*
G01X139157D02*
X139782Y177150D01*
G01X141257Y179233D02*
X141507Y179483D01*
X141799Y179608D01*
X142132Y179650D01*
X142549Y179567D01*
X142841Y179358D01*
X142924Y179108D01*
X142882Y178858D01*
X142716Y178650D01*
X141882Y178233D01*
X141507Y177942D01*
X141257Y177525D01*
X141174Y177150D01*
X142924D01*
G01X144357Y179233D02*
X144607Y179483D01*
X144899Y179608D01*
X145232Y179650D01*
X145649Y179567D01*
X145941Y179358D01*
X146024Y179108D01*
X145982Y178858D01*
X145816Y178650D01*
X144982Y178233D01*
X144607Y177942D01*
X144357Y177525D01*
X144274Y177150D01*
X146024D01*
G01X148166D02*
X148249Y177692D01*
X148374Y178150D01*
X148541Y178567D01*
X148749Y179025D01*
X149082Y179650D01*
X147416D01*
G01X152799Y167050D02*
Y163050D01*
X160199D01*
G01X174799D02*
Y159050D01*
X182199D01*
G01X138116Y173150D02*
Y175650D01*
X139157D01*
X139491Y175525D01*
X139699Y175358D01*
X139782Y175025D01*
X139699Y174692D01*
X139449Y174483D01*
X139157Y174358D01*
X138116D01*
G01X139157D02*
X139782Y173150D01*
G01X141257Y175233D02*
X141507Y175483D01*
X141799Y175608D01*
X142132Y175650D01*
X142549Y175567D01*
X142841Y175358D01*
X142924Y175108D01*
X142882Y174858D01*
X142716Y174650D01*
X141882Y174233D01*
X141507Y173942D01*
X141257Y173525D01*
X141174Y173150D01*
X142924D01*
G01X144357Y175233D02*
X144607Y175483D01*
X144899Y175608D01*
X145232Y175650D01*
X145649Y175567D01*
X145941Y175358D01*
X146024Y175108D01*
X145982Y174858D01*
X145816Y174650D01*
X144982Y174233D01*
X144607Y173942D01*
X144357Y173525D01*
X144274Y173150D01*
X146024D01*
G01X147541Y173442D02*
X147832Y173233D01*
X148166Y173150D01*
X148499Y173233D01*
X148791Y173483D01*
X148999Y173858D01*
X149082Y174233D01*
Y174692D01*
X148999Y175067D01*
X148791Y175400D01*
X148541Y175567D01*
X148249Y175650D01*
X147916Y175567D01*
X147666Y175400D01*
X147499Y175150D01*
X147416Y174817D01*
X147499Y174525D01*
X147707Y174233D01*
X147957Y174067D01*
X148249Y174025D01*
X148582Y174108D01*
X148832Y174317D01*
X149082Y174692D01*
G01X152799Y163050D02*
Y159050D01*
X160199D01*
G01X174799Y158550D02*
Y154550D01*
X182199D01*
G01X144623Y185817D02*
Y347017D01*
X158223D01*
Y359967D01*
X176423D01*
Y347017D01*
X205323D01*
Y336667D01*
X198623D01*
Y196167D01*
X205323D01*
Y185817D01*
X176423D01*
Y172867D01*
X158223D01*
Y185817D01*
X144623D01*
G01X114967Y250192D02*
X114717Y250317D01*
X114425Y250400D01*
X114092D01*
X113717Y250275D01*
X113425Y250067D01*
X113217Y249817D01*
X113050Y249400D01*
X113008Y249025D01*
X113092Y248650D01*
X113217Y248400D01*
X113467Y248150D01*
X113758Y247983D01*
X114050Y247900D01*
X114342D01*
X114633Y247983D01*
X114883Y248108D01*
X115092Y248275D01*
G01X116358Y249983D02*
X116608Y250233D01*
X116900Y250358D01*
X117233Y250400D01*
X117650Y250317D01*
X117942Y250108D01*
X118025Y249858D01*
X117983Y249608D01*
X117817Y249400D01*
X116983Y248983D01*
X116608Y248692D01*
X116358Y248275D01*
X116275Y247900D01*
X118025D01*
G01X120750D02*
Y250400D01*
X119208Y248608D01*
X121292D01*
G01X123350Y247900D02*
X123642Y247942D01*
X123975Y248067D01*
X124183Y248275D01*
X124267Y248567D01*
X124183Y248858D01*
X123933Y249108D01*
X123558Y249233D01*
X123142D01*
X122892Y249317D01*
X122683Y249525D01*
X122600Y249817D01*
X122725Y250108D01*
X123017Y250317D01*
X123350Y250400D01*
X123683Y250317D01*
X123975Y250108D01*
X124100Y249817D01*
X124017Y249525D01*
X123808Y249317D01*
X123558Y249233D01*
X123142D01*
X122767Y249108D01*
X122517Y248858D01*
X122433Y248567D01*
X122517Y248275D01*
X122725Y248067D01*
X123058Y247942D01*
X123350Y247900D01*
G01X115266Y254342D02*
X115016Y254467D01*
X114724Y254550D01*
X114391D01*
X114016Y254425D01*
X113724Y254217D01*
X113516Y253967D01*
X113349Y253550D01*
X113307Y253175D01*
X113391Y252800D01*
X113516Y252550D01*
X113766Y252300D01*
X114057Y252133D01*
X114349Y252050D01*
X114641D01*
X114932Y252133D01*
X115182Y252258D01*
X115391Y252425D01*
G01X116657Y254133D02*
X116907Y254383D01*
X117199Y254508D01*
X117532Y254550D01*
X117949Y254467D01*
X118241Y254258D01*
X118324Y254008D01*
X118282Y253758D01*
X118116Y253550D01*
X117282Y253133D01*
X116907Y252842D01*
X116657Y252425D01*
X116574Y252050D01*
X118324D01*
G01X121049D02*
Y254550D01*
X119507Y252758D01*
X121591D01*
G01X122941Y252342D02*
X123232Y252133D01*
X123566Y252050D01*
X123899Y252133D01*
X124191Y252383D01*
X124399Y252758D01*
X124482Y253133D01*
Y253592D01*
X124399Y253967D01*
X124191Y254300D01*
X123941Y254467D01*
X123649Y254550D01*
X123316Y254467D01*
X123066Y254300D01*
X122899Y254050D01*
X122816Y253717D01*
X122899Y253425D01*
X123107Y253133D01*
X123357Y252967D01*
X123649Y252925D01*
X123982Y253008D01*
X124232Y253217D01*
X124482Y253592D01*
G01X137767Y258125D02*
X137975Y258458D01*
X138100Y258833D01*
Y259167D01*
X137975Y259500D01*
X137767Y259750D01*
X137475Y259875D01*
X137183Y259792D01*
X136933Y259583D01*
X136767Y259208D01*
X136683Y258708D01*
X136517Y258417D01*
X136225Y258292D01*
X135933Y258375D01*
X135725Y258583D01*
X135600Y258875D01*
Y259167D01*
X135683Y259458D01*
X135892Y259708D01*
G01X138100Y261183D02*
X135600D01*
G01Y262767D02*
X137142Y261183D01*
G01X138100Y263017D02*
X136433Y261892D01*
G01X135600Y265200D02*
X138100D01*
G01X135600Y264242D02*
Y266158D01*
G01X138100Y268300D02*
X135600D01*
X136100Y267800D01*
G01X138100D02*
Y268800D01*
G01X135600Y271400D02*
X135683Y271067D01*
X135892Y270817D01*
X136142Y270650D01*
X136475Y270525D01*
X136850Y270483D01*
X137225Y270525D01*
X137558Y270650D01*
X137808Y270817D01*
X138017Y271067D01*
X138100Y271400D01*
X138017Y271733D01*
X137808Y271983D01*
X137558Y272150D01*
X137225Y272275D01*
X136850Y272317D01*
X136475Y272275D01*
X136142Y272150D01*
X135892Y271983D01*
X135683Y271733D01*
X135600Y271400D01*
G01X189500Y411000D02*
X173400D01*
G01Y418000D02*
X189500D01*
G01X173400Y411000D02*
Y418000D01*
G01X124708Y414367D02*
X124583Y414117D01*
X124500Y413825D01*
Y413492D01*
X124625Y413117D01*
X124833Y412825D01*
X125083Y412617D01*
X125500Y412450D01*
X125875Y412408D01*
X126250Y412492D01*
X126500Y412617D01*
X126750Y412867D01*
X126917Y413158D01*
X127000Y413450D01*
Y413742D01*
X126917Y414033D01*
X126792Y414283D01*
X126625Y414492D01*
G01X126500Y415633D02*
X126792Y415883D01*
X126958Y416217D01*
X127000Y416592D01*
X126958Y416925D01*
X126750Y417258D01*
X126500Y417467D01*
X126250Y417508D01*
X125958Y417425D01*
X125750Y417133D01*
X125667Y416842D01*
Y416467D01*
G01Y416842D02*
X125542Y417092D01*
X125333Y417300D01*
X125083Y417383D01*
X124833Y417300D01*
X124625Y417092D01*
X124500Y416717D01*
X124542Y416342D01*
X124708Y415967D01*
G01X127000Y419650D02*
X124500D01*
X125000Y419150D01*
G01X127000D02*
Y420150D01*
G01X126625Y421833D02*
X126833Y422083D01*
X126958Y422375D01*
X127000Y422750D01*
X126917Y423125D01*
X126750Y423417D01*
X126458Y423625D01*
X126125Y423667D01*
X125792Y423583D01*
X125583Y423375D01*
X125417Y423083D01*
X125375Y422792D01*
X125417Y422500D01*
X125583Y422125D01*
X124500Y422250D01*
Y423375D01*
G01X110708Y453767D02*
X110583Y453517D01*
X110500Y453225D01*
Y452892D01*
X110625Y452517D01*
X110833Y452225D01*
X111083Y452017D01*
X111500Y451850D01*
X111875Y451808D01*
X112250Y451892D01*
X112500Y452017D01*
X112750Y452267D01*
X112917Y452558D01*
X113000Y452850D01*
Y453142D01*
X112917Y453433D01*
X112792Y453683D01*
X112625Y453892D01*
G01X112500Y455033D02*
X112792Y455283D01*
X112958Y455617D01*
X113000Y455992D01*
X112958Y456325D01*
X112750Y456658D01*
X112500Y456867D01*
X112250Y456908D01*
X111958Y456825D01*
X111750Y456533D01*
X111667Y456242D01*
Y455867D01*
G01Y456242D02*
X111542Y456492D01*
X111333Y456700D01*
X111083Y456783D01*
X110833Y456700D01*
X110625Y456492D01*
X110500Y456117D01*
X110542Y455742D01*
X110708Y455367D01*
G01X110917Y458258D02*
X110667Y458508D01*
X110542Y458800D01*
X110500Y459133D01*
X110583Y459550D01*
X110792Y459842D01*
X111042Y459925D01*
X111292Y459883D01*
X111500Y459717D01*
X111917Y458883D01*
X112208Y458508D01*
X112625Y458258D01*
X113000Y458175D01*
Y459925D01*
G01X110917Y461358D02*
X110667Y461608D01*
X110542Y461900D01*
X110500Y462233D01*
X110583Y462650D01*
X110792Y462942D01*
X111042Y463025D01*
X111292Y462983D01*
X111500Y462817D01*
X111917Y461983D01*
X112208Y461608D01*
X112625Y461358D01*
X113000Y461275D01*
Y463025D01*
G01X156618Y400572D02*
X156285Y400614D01*
X155993Y400780D01*
X155743Y401030D01*
X155576Y401322D01*
X155493Y401655D01*
Y401989D01*
X155576Y402322D01*
X155743Y402614D01*
X155993Y402864D01*
X156285Y403030D01*
X156618Y403072D01*
X156951Y403030D01*
X157243Y402864D01*
X157493Y402614D01*
X157660Y402322D01*
X157743Y401989D01*
Y401655D01*
X157660Y401322D01*
X157493Y401030D01*
X157243Y400780D01*
X156951Y400614D01*
X156618Y400572D01*
G01X156951Y401239D02*
X157451Y400572D01*
G01X158926Y402655D02*
X159176Y402905D01*
X159468Y403030D01*
X159801Y403072D01*
X160218Y402989D01*
X160510Y402780D01*
X160593Y402530D01*
X160551Y402280D01*
X160385Y402072D01*
X159551Y401655D01*
X159176Y401364D01*
X158926Y400947D01*
X158843Y400572D01*
X160593D01*
G01X162818D02*
X163110Y400614D01*
X163443Y400739D01*
X163651Y400947D01*
X163735Y401239D01*
X163651Y401530D01*
X163401Y401780D01*
X163026Y401905D01*
X162610D01*
X162360Y401989D01*
X162151Y402197D01*
X162068Y402489D01*
X162193Y402780D01*
X162485Y402989D01*
X162818Y403072D01*
X163151Y402989D01*
X163443Y402780D01*
X163568Y402489D01*
X163485Y402197D01*
X163276Y401989D01*
X163026Y401905D01*
X162610D01*
X162235Y401780D01*
X161985Y401530D01*
X161901Y401239D01*
X161985Y400947D01*
X162193Y400739D01*
X162526Y400614D01*
X162818Y400572D01*
G01X155299Y441313D02*
Y429913D01*
G01X168699Y441313D02*
X155299D01*
G01X168699Y429913D02*
Y441313D01*
G01X155299Y429913D02*
X168699D01*
G01X124017Y469500D02*
Y472000D01*
X125058D01*
X125392Y471875D01*
X125600Y471708D01*
X125683Y471375D01*
X125600Y471042D01*
X125350Y470833D01*
X125058Y470708D01*
X124017D01*
G01X125058D02*
X125683Y469500D01*
G01X127158Y471583D02*
X127408Y471833D01*
X127700Y471958D01*
X128033Y472000D01*
X128450Y471917D01*
X128742Y471708D01*
X128825Y471458D01*
X128783Y471208D01*
X128617Y471000D01*
X127783Y470583D01*
X127408Y470292D01*
X127158Y469875D01*
X127075Y469500D01*
X128825D01*
G01X130342Y469792D02*
X130633Y469583D01*
X130967Y469500D01*
X131300Y469583D01*
X131592Y469833D01*
X131800Y470208D01*
X131883Y470583D01*
Y471042D01*
X131800Y471417D01*
X131592Y471750D01*
X131342Y471917D01*
X131050Y472000D01*
X130717Y471917D01*
X130467Y471750D01*
X130300Y471500D01*
X130217Y471167D01*
X130300Y470875D01*
X130508Y470583D01*
X130758Y470417D01*
X131050Y470375D01*
X131383Y470458D01*
X131633Y470667D01*
X131883Y471042D01*
G01X133358Y471583D02*
X133608Y471833D01*
X133900Y471958D01*
X134233Y472000D01*
X134650Y471917D01*
X134942Y471708D01*
X135025Y471458D01*
X134983Y471208D01*
X134817Y471000D01*
X133983Y470583D01*
X133608Y470292D01*
X133358Y469875D01*
X133275Y469500D01*
X135025D01*
G01X162999Y468050D02*
Y481050D01*
G01X136999Y468050D02*
X162999D01*
G01X136999Y481050D02*
Y468050D01*
G01X174300Y422500D02*
Y418500D01*
X181700D01*
G01X144128Y406167D02*
X141628D01*
Y407208D01*
X141753Y407542D01*
X141920Y407750D01*
X142253Y407833D01*
X142586Y407750D01*
X142795Y407500D01*
X142920Y407208D01*
Y406167D01*
G01Y407208D02*
X144128Y407833D01*
G01X142045Y409308D02*
X141795Y409558D01*
X141670Y409850D01*
X141628Y410183D01*
X141711Y410600D01*
X141920Y410892D01*
X142170Y410975D01*
X142420Y410933D01*
X142628Y410767D01*
X143045Y409933D01*
X143336Y409558D01*
X143753Y409308D01*
X144128Y409225D01*
Y410975D01*
G01Y413200D02*
X144086Y413492D01*
X143961Y413825D01*
X143753Y414033D01*
X143461Y414117D01*
X143170Y414033D01*
X142920Y413783D01*
X142795Y413408D01*
Y412992D01*
X142711Y412742D01*
X142503Y412533D01*
X142211Y412450D01*
X141920Y412575D01*
X141711Y412867D01*
X141628Y413200D01*
X141711Y413533D01*
X141920Y413825D01*
X142211Y413950D01*
X142503Y413867D01*
X142711Y413658D01*
X142795Y413408D01*
Y412992D01*
X142920Y412617D01*
X143170Y412367D01*
X143461Y412283D01*
X143753Y412367D01*
X143961Y412575D01*
X144086Y412908D01*
X144128Y413200D01*
G01Y416217D02*
X143586Y416300D01*
X143128Y416425D01*
X142711Y416592D01*
X142253Y416800D01*
X141628Y417133D01*
Y415467D01*
G01X139499Y438413D02*
X143499D01*
Y445813D01*
G01X159218Y404652D02*
X156718D01*
Y405693D01*
X156843Y406027D01*
X157010Y406235D01*
X157343Y406318D01*
X157676Y406235D01*
X157885Y405985D01*
X158010Y405693D01*
Y404652D01*
G01Y405693D02*
X159218Y406318D01*
G01X157135Y407793D02*
X156885Y408043D01*
X156760Y408335D01*
X156718Y408668D01*
X156801Y409085D01*
X157010Y409377D01*
X157260Y409460D01*
X157510Y409418D01*
X157718Y409252D01*
X158135Y408418D01*
X158426Y408043D01*
X158843Y407793D01*
X159218Y407710D01*
Y409460D01*
G01Y411685D02*
X159176Y411977D01*
X159051Y412310D01*
X158843Y412518D01*
X158551Y412602D01*
X158260Y412518D01*
X158010Y412268D01*
X157885Y411893D01*
Y411477D01*
X157801Y411227D01*
X157593Y411018D01*
X157301Y410935D01*
X157010Y411060D01*
X156801Y411352D01*
X156718Y411685D01*
X156801Y412018D01*
X157010Y412310D01*
X157301Y412435D01*
X157593Y412352D01*
X157801Y412143D01*
X157885Y411893D01*
Y411477D01*
X158010Y411102D01*
X158260Y410852D01*
X158551Y410768D01*
X158843Y410852D01*
X159051Y411060D01*
X159176Y411393D01*
X159218Y411685D01*
G01Y414785D02*
X159176Y415077D01*
X159051Y415410D01*
X158843Y415618D01*
X158551Y415702D01*
X158260Y415618D01*
X158010Y415368D01*
X157885Y414993D01*
Y414577D01*
X157801Y414327D01*
X157593Y414118D01*
X157301Y414035D01*
X157010Y414160D01*
X156801Y414452D01*
X156718Y414785D01*
X156801Y415118D01*
X157010Y415410D01*
X157301Y415535D01*
X157593Y415452D01*
X157801Y415243D01*
X157885Y414993D01*
Y414577D01*
X158010Y414202D01*
X158260Y413952D01*
X158551Y413868D01*
X158843Y413952D01*
X159051Y414160D01*
X159176Y414493D01*
X159218Y414785D01*
G01X164999Y449313D02*
X160999D01*
Y441913D01*
G01X161217Y405700D02*
Y408200D01*
X162258D01*
X162592Y408075D01*
X162800Y407908D01*
X162883Y407575D01*
X162800Y407242D01*
X162550Y407033D01*
X162258Y406908D01*
X161217D01*
G01X162258D02*
X162883Y405700D01*
G01X164358Y407783D02*
X164608Y408033D01*
X164900Y408158D01*
X165233Y408200D01*
X165650Y408117D01*
X165942Y407908D01*
X166025Y407658D01*
X165983Y407408D01*
X165817Y407200D01*
X164983Y406783D01*
X164608Y406492D01*
X164358Y406075D01*
X164275Y405700D01*
X166025D01*
G01X167542Y405992D02*
X167833Y405783D01*
X168167Y405700D01*
X168500Y405783D01*
X168792Y406033D01*
X169000Y406408D01*
X169083Y406783D01*
Y407242D01*
X169000Y407617D01*
X168792Y407950D01*
X168542Y408117D01*
X168250Y408200D01*
X167917Y408117D01*
X167667Y407950D01*
X167500Y407700D01*
X167417Y407367D01*
X167500Y407075D01*
X167708Y406783D01*
X167958Y406617D01*
X168250Y406575D01*
X168583Y406658D01*
X168833Y406867D01*
X169083Y407242D01*
G01X171350Y408200D02*
X171017Y408117D01*
X170767Y407908D01*
X170600Y407658D01*
X170475Y407325D01*
X170433Y406950D01*
X170475Y406575D01*
X170600Y406242D01*
X170767Y405992D01*
X171017Y405783D01*
X171350Y405700D01*
X171683Y405783D01*
X171933Y405992D01*
X172100Y406242D01*
X172225Y406575D01*
X172267Y406950D01*
X172225Y407325D01*
X172100Y407658D01*
X171933Y407908D01*
X171683Y408117D01*
X171350Y408200D01*
G01X164900Y422300D02*
Y418300D01*
X172300D01*
G01X153628Y406167D02*
X151128D01*
Y407208D01*
X151253Y407542D01*
X151420Y407750D01*
X151753Y407833D01*
X152086Y407750D01*
X152295Y407500D01*
X152420Y407208D01*
Y406167D01*
G01Y407208D02*
X153628Y407833D01*
G01X151545Y409308D02*
X151295Y409558D01*
X151170Y409850D01*
X151128Y410183D01*
X151211Y410600D01*
X151420Y410892D01*
X151670Y410975D01*
X151920Y410933D01*
X152128Y410767D01*
X152545Y409933D01*
X152836Y409558D01*
X153253Y409308D01*
X153628Y409225D01*
Y410975D01*
G01X153336Y412492D02*
X153545Y412783D01*
X153628Y413117D01*
X153545Y413450D01*
X153295Y413742D01*
X152920Y413950D01*
X152545Y414033D01*
X152086D01*
X151711Y413950D01*
X151378Y413742D01*
X151211Y413492D01*
X151128Y413200D01*
X151211Y412867D01*
X151378Y412617D01*
X151628Y412450D01*
X151961Y412367D01*
X152253Y412450D01*
X152545Y412658D01*
X152711Y412908D01*
X152753Y413200D01*
X152670Y413533D01*
X152461Y413783D01*
X152086Y414033D01*
G01X153628Y416800D02*
X151128D01*
X152920Y415258D01*
Y417342D01*
G01X152999Y445813D02*
X148999D01*
Y438413D01*
G01X149128Y406167D02*
X146628D01*
Y407208D01*
X146753Y407542D01*
X146920Y407750D01*
X147253Y407833D01*
X147586Y407750D01*
X147795Y407500D01*
X147920Y407208D01*
Y406167D01*
G01Y407208D02*
X149128Y407833D01*
G01X147045Y409308D02*
X146795Y409558D01*
X146670Y409850D01*
X146628Y410183D01*
X146711Y410600D01*
X146920Y410892D01*
X147170Y410975D01*
X147420Y410933D01*
X147628Y410767D01*
X148045Y409933D01*
X148336Y409558D01*
X148753Y409308D01*
X149128Y409225D01*
Y410975D01*
G01X148836Y412492D02*
X149045Y412783D01*
X149128Y413117D01*
X149045Y413450D01*
X148795Y413742D01*
X148420Y413950D01*
X148045Y414033D01*
X147586D01*
X147211Y413950D01*
X146878Y413742D01*
X146711Y413492D01*
X146628Y413200D01*
X146711Y412867D01*
X146878Y412617D01*
X147128Y412450D01*
X147461Y412367D01*
X147753Y412450D01*
X148045Y412658D01*
X148211Y412908D01*
X148253Y413200D01*
X148170Y413533D01*
X147961Y413783D01*
X147586Y414033D01*
G01X148753Y415383D02*
X148961Y415633D01*
X149086Y415925D01*
X149128Y416300D01*
X149045Y416675D01*
X148878Y416967D01*
X148586Y417175D01*
X148253Y417217D01*
X147920Y417133D01*
X147711Y416925D01*
X147545Y416633D01*
X147503Y416342D01*
X147545Y416050D01*
X147711Y415675D01*
X146628Y415800D01*
Y416925D01*
G01X144499Y438413D02*
X148499D01*
Y445813D01*
G01X118716Y426213D02*
Y428713D01*
X119757D01*
X120091Y428588D01*
X120299Y428421D01*
X120382Y428088D01*
X120299Y427755D01*
X120049Y427546D01*
X119757Y427421D01*
X118716D01*
G01X119757D02*
X120382Y426213D01*
G01X123149D02*
Y428713D01*
X121607Y426921D01*
X123691D01*
G01X125666Y426213D02*
X125749Y426755D01*
X125874Y427213D01*
X126041Y427630D01*
X126249Y428088D01*
X126582Y428713D01*
X124916D01*
G01X128057Y428296D02*
X128307Y428546D01*
X128599Y428671D01*
X128932Y428713D01*
X129349Y428630D01*
X129641Y428421D01*
X129724Y428171D01*
X129682Y427921D01*
X129516Y427713D01*
X128682Y427296D01*
X128307Y427005D01*
X128057Y426588D01*
X127974Y426213D01*
X129724D01*
G01X132299Y425113D02*
Y421113D01*
X139699D01*
G01X118716Y430213D02*
Y432713D01*
X119757D01*
X120091Y432588D01*
X120299Y432421D01*
X120382Y432088D01*
X120299Y431755D01*
X120049Y431546D01*
X119757Y431421D01*
X118716D01*
G01X119757D02*
X120382Y430213D01*
G01X123149D02*
Y432713D01*
X121607Y430921D01*
X123691D01*
G01X125666Y430213D02*
X125749Y430755D01*
X125874Y431213D01*
X126041Y431630D01*
X126249Y432088D01*
X126582Y432713D01*
X124916D01*
G01X127932Y430713D02*
X128182Y430421D01*
X128516Y430255D01*
X128891Y430213D01*
X129224Y430255D01*
X129557Y430463D01*
X129766Y430713D01*
X129807Y430963D01*
X129724Y431255D01*
X129432Y431463D01*
X129141Y431546D01*
X128766D01*
G01X129141D02*
X129391Y431671D01*
X129599Y431880D01*
X129682Y432130D01*
X129599Y432380D01*
X129391Y432588D01*
X129016Y432713D01*
X128641Y432671D01*
X128266Y432505D01*
G01X132299Y429113D02*
Y425113D01*
X139699D01*
G01X161117Y409600D02*
Y412100D01*
X162158D01*
X162492Y411975D01*
X162700Y411808D01*
X162783Y411475D01*
X162700Y411142D01*
X162450Y410933D01*
X162158Y410808D01*
X161117D01*
G01X162158D02*
X162783Y409600D01*
G01X165550D02*
Y412100D01*
X164008Y410308D01*
X166092D01*
G01X167358Y411683D02*
X167608Y411933D01*
X167900Y412058D01*
X168233Y412100D01*
X168650Y412017D01*
X168942Y411808D01*
X169025Y411558D01*
X168983Y411308D01*
X168817Y411100D01*
X167983Y410683D01*
X167608Y410392D01*
X167358Y409975D01*
X167275Y409600D01*
X169025D01*
G01X171250D02*
Y412100D01*
X170750Y411600D01*
G01Y409600D02*
X171750D01*
G01X164900Y426300D02*
Y422300D01*
X172300D01*
G01X144111Y404587D02*
Y402795D01*
X144278Y402420D01*
X144611Y402170D01*
X145028Y402087D01*
X145445Y402170D01*
X145778Y402420D01*
X145945Y402795D01*
Y404587D01*
G01X148628Y402087D02*
Y404587D01*
X147086Y402795D01*
X149170D01*
G01X150436Y404170D02*
X150686Y404420D01*
X150978Y404545D01*
X151311Y404587D01*
X151728Y404504D01*
X152020Y404295D01*
X152103Y404045D01*
X152061Y403795D01*
X151895Y403587D01*
X151061Y403170D01*
X150686Y402879D01*
X150436Y402462D01*
X150353Y402087D01*
X152103D01*
G01X152999Y436813D02*
Y423413D01*
G01X142999Y436813D02*
X152999D01*
G01X142999Y423413D02*
Y436813D01*
G01X152999Y423413D02*
X142999D01*
G01X99499Y473400D02*
X101999D01*
G01X99499Y472442D02*
Y474358D01*
G01X101999Y475667D02*
X99499D01*
Y476667D01*
X99624Y477000D01*
X99916Y477250D01*
X100249Y477333D01*
X100582Y477250D01*
X100832Y477042D01*
X100957Y476667D01*
Y475667D01*
G01X101499Y478683D02*
X101791Y478933D01*
X101957Y479267D01*
X101999Y479642D01*
X101957Y479975D01*
X101749Y480308D01*
X101499Y480517D01*
X101249Y480558D01*
X100957Y480475D01*
X100749Y480183D01*
X100666Y479892D01*
Y479517D01*
G01Y479892D02*
X100541Y480142D01*
X100332Y480350D01*
X100082Y480433D01*
X99832Y480350D01*
X99624Y480142D01*
X99499Y479767D01*
X99541Y479392D01*
X99707Y479017D01*
G01X101999Y482700D02*
X101957Y482992D01*
X101832Y483325D01*
X101624Y483533D01*
X101332Y483617D01*
X101041Y483533D01*
X100791Y483283D01*
X100666Y482908D01*
Y482492D01*
X100582Y482242D01*
X100374Y482033D01*
X100082Y481950D01*
X99791Y482075D01*
X99582Y482367D01*
X99499Y482700D01*
X99582Y483033D01*
X99791Y483325D01*
X100082Y483450D01*
X100374Y483367D01*
X100582Y483158D01*
X100666Y482908D01*
Y482492D01*
X100791Y482117D01*
X101041Y481867D01*
X101332Y481783D01*
X101624Y481867D01*
X101832Y482075D01*
X101957Y482408D01*
X101999Y482700D01*
G01X124208Y453767D02*
X124083Y453517D01*
X124000Y453225D01*
Y452892D01*
X124125Y452517D01*
X124333Y452225D01*
X124583Y452017D01*
X125000Y451850D01*
X125375Y451808D01*
X125750Y451892D01*
X126000Y452017D01*
X126250Y452267D01*
X126417Y452558D01*
X126500Y452850D01*
Y453142D01*
X126417Y453433D01*
X126292Y453683D01*
X126125Y453892D01*
G01X126000Y455033D02*
X126292Y455283D01*
X126458Y455617D01*
X126500Y455992D01*
X126458Y456325D01*
X126250Y456658D01*
X126000Y456867D01*
X125750Y456908D01*
X125458Y456825D01*
X125250Y456533D01*
X125167Y456242D01*
Y455867D01*
G01Y456242D02*
X125042Y456492D01*
X124833Y456700D01*
X124583Y456783D01*
X124333Y456700D01*
X124125Y456492D01*
X124000Y456117D01*
X124042Y455742D01*
X124208Y455367D01*
G01X126500Y459050D02*
X124000D01*
X124500Y458550D01*
G01X126500D02*
Y459550D01*
G01Y462150D02*
X126458Y462442D01*
X126333Y462775D01*
X126125Y462983D01*
X125833Y463067D01*
X125542Y462983D01*
X125292Y462733D01*
X125167Y462358D01*
Y461942D01*
X125083Y461692D01*
X124875Y461483D01*
X124583Y461400D01*
X124292Y461525D01*
X124083Y461817D01*
X124000Y462150D01*
X124083Y462483D01*
X124292Y462775D01*
X124583Y462900D01*
X124875Y462817D01*
X125083Y462608D01*
X125167Y462358D01*
Y461942D01*
X125292Y461567D01*
X125542Y461317D01*
X125833Y461233D01*
X126125Y461317D01*
X126333Y461525D01*
X126458Y461858D01*
X126500Y462150D01*
G01X162999Y467413D02*
Y461913D01*
G01X154999Y467413D02*
X162999D01*
G01X154999Y461913D02*
Y467413D01*
G01Y449813D02*
Y455313D01*
G01X162999Y449813D02*
X154999D01*
G01X162999Y455313D02*
Y449813D01*
G01X119708Y453767D02*
X119583Y453517D01*
X119500Y453225D01*
Y452892D01*
X119625Y452517D01*
X119833Y452225D01*
X120083Y452017D01*
X120500Y451850D01*
X120875Y451808D01*
X121250Y451892D01*
X121500Y452017D01*
X121750Y452267D01*
X121917Y452558D01*
X122000Y452850D01*
Y453142D01*
X121917Y453433D01*
X121792Y453683D01*
X121625Y453892D01*
G01X121500Y455033D02*
X121792Y455283D01*
X121958Y455617D01*
X122000Y455992D01*
X121958Y456325D01*
X121750Y456658D01*
X121500Y456867D01*
X121250Y456908D01*
X120958Y456825D01*
X120750Y456533D01*
X120667Y456242D01*
Y455867D01*
G01Y456242D02*
X120542Y456492D01*
X120333Y456700D01*
X120083Y456783D01*
X119833Y456700D01*
X119625Y456492D01*
X119500Y456117D01*
X119542Y455742D01*
X119708Y455367D01*
G01X122000Y459050D02*
X119500D01*
X120000Y458550D01*
G01X122000D02*
Y459550D01*
G01X121708Y461442D02*
X121917Y461733D01*
X122000Y462067D01*
X121917Y462400D01*
X121667Y462692D01*
X121292Y462900D01*
X120917Y462983D01*
X120458D01*
X120083Y462900D01*
X119750Y462692D01*
X119583Y462442D01*
X119500Y462150D01*
X119583Y461817D01*
X119750Y461567D01*
X120000Y461400D01*
X120333Y461317D01*
X120625Y461400D01*
X120917Y461608D01*
X121083Y461858D01*
X121125Y462150D01*
X121042Y462483D01*
X120833Y462733D01*
X120458Y462983D01*
G01X153999Y467413D02*
Y461913D01*
G01X145999Y467413D02*
X153999D01*
G01X145999Y461913D02*
Y467413D01*
G01Y449813D02*
Y455313D01*
G01X153999Y449813D02*
X145999D01*
G01X153999Y455313D02*
Y449813D01*
G01X115208Y453767D02*
X115083Y453517D01*
X115000Y453225D01*
Y452892D01*
X115125Y452517D01*
X115333Y452225D01*
X115583Y452017D01*
X116000Y451850D01*
X116375Y451808D01*
X116750Y451892D01*
X117000Y452017D01*
X117250Y452267D01*
X117417Y452558D01*
X117500Y452850D01*
Y453142D01*
X117417Y453433D01*
X117292Y453683D01*
X117125Y453892D01*
G01X117000Y455033D02*
X117292Y455283D01*
X117458Y455617D01*
X117500Y455992D01*
X117458Y456325D01*
X117250Y456658D01*
X117000Y456867D01*
X116750Y456908D01*
X116458Y456825D01*
X116250Y456533D01*
X116167Y456242D01*
Y455867D01*
G01Y456242D02*
X116042Y456492D01*
X115833Y456700D01*
X115583Y456783D01*
X115333Y456700D01*
X115125Y456492D01*
X115000Y456117D01*
X115042Y455742D01*
X115208Y455367D01*
G01X115417Y458258D02*
X115167Y458508D01*
X115042Y458800D01*
X115000Y459133D01*
X115083Y459550D01*
X115292Y459842D01*
X115542Y459925D01*
X115792Y459883D01*
X116000Y459717D01*
X116417Y458883D01*
X116708Y458508D01*
X117125Y458258D01*
X117500Y458175D01*
Y459925D01*
G01X115000Y462150D02*
X115083Y461817D01*
X115292Y461567D01*
X115542Y461400D01*
X115875Y461275D01*
X116250Y461233D01*
X116625Y461275D01*
X116958Y461400D01*
X117208Y461567D01*
X117417Y461817D01*
X117500Y462150D01*
X117417Y462483D01*
X117208Y462733D01*
X116958Y462900D01*
X116625Y463025D01*
X116250Y463067D01*
X115875Y463025D01*
X115542Y462900D01*
X115292Y462733D01*
X115083Y462483D01*
X115000Y462150D01*
G01X144999Y467413D02*
Y461913D01*
G01X136999Y467413D02*
X144999D01*
G01X136999Y461913D02*
Y467413D01*
G01Y449813D02*
Y455313D01*
G01X144999Y449813D02*
X136999D01*
G01X144999Y455313D02*
Y449813D01*
G01X128708Y453767D02*
X128583Y453517D01*
X128500Y453225D01*
Y452892D01*
X128625Y452517D01*
X128833Y452225D01*
X129083Y452017D01*
X129500Y451850D01*
X129875Y451808D01*
X130250Y451892D01*
X130500Y452017D01*
X130750Y452267D01*
X130917Y452558D01*
X131000Y452850D01*
Y453142D01*
X130917Y453433D01*
X130792Y453683D01*
X130625Y453892D01*
G01X130500Y455033D02*
X130792Y455283D01*
X130958Y455617D01*
X131000Y455992D01*
X130958Y456325D01*
X130750Y456658D01*
X130500Y456867D01*
X130250Y456908D01*
X129958Y456825D01*
X129750Y456533D01*
X129667Y456242D01*
Y455867D01*
G01Y456242D02*
X129542Y456492D01*
X129333Y456700D01*
X129083Y456783D01*
X128833Y456700D01*
X128625Y456492D01*
X128500Y456117D01*
X128542Y455742D01*
X128708Y455367D01*
G01X128917Y458258D02*
X128667Y458508D01*
X128542Y458800D01*
X128500Y459133D01*
X128583Y459550D01*
X128792Y459842D01*
X129042Y459925D01*
X129292Y459883D01*
X129500Y459717D01*
X129917Y458883D01*
X130208Y458508D01*
X130625Y458258D01*
X131000Y458175D01*
Y459925D01*
G01Y462150D02*
X128500D01*
X129000Y461650D01*
G01X131000D02*
Y462650D01*
G01X171900Y467400D02*
Y461900D01*
G01X163900Y467400D02*
X171900D01*
G01X163900Y461900D02*
Y467400D01*
G01Y449800D02*
Y455300D01*
G01X171900Y449800D02*
X163900D01*
G01X171900Y455300D02*
Y449800D01*
G01X98665Y649850D02*
X108665D01*
G01Y642850D02*
X98665D01*
G01X103665D02*
Y649850D01*
G01X98665Y639417D02*
X108665D01*
Y636083D01*
X108165Y634750D01*
X107498Y633750D01*
X106498Y632917D01*
X105331Y632250D01*
X103665Y632083D01*
X101998Y632250D01*
X100832Y632917D01*
X99831Y633750D01*
X99165Y634750D01*
X98665Y636083D01*
Y639417D01*
G01Y628817D02*
X108665D01*
Y625483D01*
X108165Y624150D01*
X107498Y623150D01*
X106498Y622317D01*
X105331Y621650D01*
X103665Y621483D01*
X101998Y621650D01*
X100832Y622317D01*
X99831Y623150D01*
X99165Y624150D01*
X98665Y625483D01*
Y628817D01*
G01Y614550D02*
X108665D01*
X106665Y616550D01*
G01X98665D02*
Y612550D01*
G01X100665Y607617D02*
X99498Y606617D01*
X98832Y605284D01*
X98665Y603783D01*
X98832Y602450D01*
X99665Y601117D01*
X100665Y600283D01*
X101665Y600117D01*
X102831Y600450D01*
X103665Y601617D01*
X103998Y602783D01*
Y604283D01*
G01Y602783D02*
X104498Y601783D01*
X105331Y600950D01*
X106332Y600617D01*
X107332Y600950D01*
X108165Y601783D01*
X108665Y603283D01*
X108498Y604783D01*
X107832Y606283D01*
G01X95332Y598350D02*
Y588350D01*
G01X108665Y586083D02*
X98665D01*
Y579417D01*
G01Y568817D02*
Y575483D01*
X108665D01*
Y568817D01*
G01X103832Y571483D02*
Y575483D01*
G01X98665Y565217D02*
X108665D01*
Y561883D01*
X108165Y560550D01*
X107498Y559550D01*
X106498Y558717D01*
X105331Y558050D01*
X103665Y557883D01*
X101998Y558050D01*
X100832Y558717D01*
X99831Y559550D01*
X99165Y560550D01*
X98665Y561883D01*
Y565217D01*
G01X98612Y535280D02*
X98362Y535405D01*
X98070Y535488D01*
X97737D01*
X97362Y535363D01*
X97070Y535155D01*
X96862Y534905D01*
X96695Y534488D01*
X96653Y534113D01*
X96737Y533738D01*
X96862Y533488D01*
X97112Y533238D01*
X97403Y533071D01*
X97695Y532988D01*
X97987D01*
X98278Y533071D01*
X98528Y533196D01*
X98737Y533363D01*
G01X99878Y533488D02*
X100128Y533196D01*
X100462Y533030D01*
X100837Y532988D01*
X101170Y533030D01*
X101503Y533238D01*
X101712Y533488D01*
X101753Y533738D01*
X101670Y534030D01*
X101378Y534238D01*
X101087Y534321D01*
X100712D01*
G01X101087D02*
X101337Y534446D01*
X101545Y534655D01*
X101628Y534905D01*
X101545Y535155D01*
X101337Y535363D01*
X100962Y535488D01*
X100587Y535446D01*
X100212Y535280D01*
G01X103895Y532988D02*
Y535488D01*
X103395Y534988D01*
G01Y532988D02*
X104395D01*
G01X106203Y535071D02*
X106453Y535321D01*
X106745Y535446D01*
X107078Y535488D01*
X107495Y535405D01*
X107787Y535196D01*
X107870Y534946D01*
X107828Y534696D01*
X107662Y534488D01*
X106828Y534071D01*
X106453Y533780D01*
X106203Y533363D01*
X106120Y532988D01*
X107870D01*
G01X98612Y531780D02*
X98362Y531905D01*
X98070Y531988D01*
X97737D01*
X97362Y531863D01*
X97070Y531655D01*
X96862Y531405D01*
X96695Y530988D01*
X96653Y530613D01*
X96737Y530238D01*
X96862Y529988D01*
X97112Y529738D01*
X97403Y529571D01*
X97695Y529488D01*
X97987D01*
X98278Y529571D01*
X98528Y529696D01*
X98737Y529863D01*
G01X99878Y529988D02*
X100128Y529696D01*
X100462Y529530D01*
X100837Y529488D01*
X101170Y529530D01*
X101503Y529738D01*
X101712Y529988D01*
X101753Y530238D01*
X101670Y530530D01*
X101378Y530738D01*
X101087Y530821D01*
X100712D01*
G01X101087D02*
X101337Y530946D01*
X101545Y531155D01*
X101628Y531405D01*
X101545Y531655D01*
X101337Y531863D01*
X100962Y531988D01*
X100587Y531946D01*
X100212Y531780D01*
G01X103895Y529488D02*
Y531988D01*
X103395Y531488D01*
G01Y529488D02*
X104395D01*
G01X106078Y529988D02*
X106328Y529696D01*
X106662Y529530D01*
X107037Y529488D01*
X107370Y529530D01*
X107703Y529738D01*
X107912Y529988D01*
X107953Y530238D01*
X107870Y530530D01*
X107578Y530738D01*
X107287Y530821D01*
X106912D01*
G01X107287D02*
X107537Y530946D01*
X107745Y531155D01*
X107828Y531405D01*
X107745Y531655D01*
X107537Y531863D01*
X107162Y531988D01*
X106787Y531946D01*
X106412Y531780D01*
G01X113107Y516317D02*
X112982Y516067D01*
X112899Y515775D01*
Y515442D01*
X113024Y515067D01*
X113232Y514775D01*
X113482Y514567D01*
X113899Y514400D01*
X114274Y514358D01*
X114649Y514442D01*
X114899Y514567D01*
X115149Y514817D01*
X115316Y515108D01*
X115399Y515400D01*
Y515692D01*
X115316Y515983D01*
X115191Y516233D01*
X115024Y516442D01*
G01X114899Y517583D02*
X115191Y517833D01*
X115357Y518167D01*
X115399Y518542D01*
X115357Y518875D01*
X115149Y519208D01*
X114899Y519417D01*
X114649Y519458D01*
X114357Y519375D01*
X114149Y519083D01*
X114066Y518792D01*
Y518417D01*
G01Y518792D02*
X113941Y519042D01*
X113732Y519250D01*
X113482Y519333D01*
X113232Y519250D01*
X113024Y519042D01*
X112899Y518667D01*
X112941Y518292D01*
X113107Y517917D01*
G01X113316Y520808D02*
X113066Y521058D01*
X112941Y521350D01*
X112899Y521683D01*
X112982Y522100D01*
X113191Y522392D01*
X113441Y522475D01*
X113691Y522433D01*
X113899Y522267D01*
X114316Y521433D01*
X114607Y521058D01*
X115024Y520808D01*
X115399Y520725D01*
Y522475D01*
G01X114899Y523783D02*
X115191Y524033D01*
X115357Y524367D01*
X115399Y524742D01*
X115357Y525075D01*
X115149Y525408D01*
X114899Y525617D01*
X114649Y525658D01*
X114357Y525575D01*
X114149Y525283D01*
X114066Y524992D01*
Y524617D01*
G01Y524992D02*
X113941Y525242D01*
X113732Y525450D01*
X113482Y525533D01*
X113232Y525450D01*
X113024Y525242D01*
X112899Y524867D01*
X112941Y524492D01*
X113107Y524117D01*
G01X129207Y488817D02*
X129082Y488567D01*
X128999Y488275D01*
Y487942D01*
X129124Y487567D01*
X129332Y487275D01*
X129582Y487067D01*
X129999Y486900D01*
X130374Y486858D01*
X130749Y486942D01*
X130999Y487067D01*
X131249Y487317D01*
X131416Y487608D01*
X131499Y487900D01*
Y488192D01*
X131416Y488483D01*
X131291Y488733D01*
X131124Y488942D01*
G01X130999Y490083D02*
X131291Y490333D01*
X131457Y490667D01*
X131499Y491042D01*
X131457Y491375D01*
X131249Y491708D01*
X130999Y491917D01*
X130749Y491958D01*
X130457Y491875D01*
X130249Y491583D01*
X130166Y491292D01*
Y490917D01*
G01Y491292D02*
X130041Y491542D01*
X129832Y491750D01*
X129582Y491833D01*
X129332Y491750D01*
X129124Y491542D01*
X128999Y491167D01*
X129041Y490792D01*
X129207Y490417D01*
G01X131499Y494100D02*
X128999D01*
X129499Y493600D01*
G01X131499D02*
Y494600D01*
G01X130457Y496408D02*
X130166Y496700D01*
X129999Y496950D01*
X129916Y497283D01*
X129999Y497575D01*
X130166Y497783D01*
X130416Y497950D01*
X130707Y497992D01*
X130957Y497950D01*
X131207Y497783D01*
X131416Y497533D01*
X131499Y497242D01*
X131416Y496908D01*
X131166Y496617D01*
X130791Y496450D01*
X130374Y496408D01*
X129832Y496492D01*
X129541Y496617D01*
X129249Y496825D01*
X129041Y497117D01*
X128999Y497408D01*
X129082Y497700D01*
X129291Y497908D01*
G01X128400Y557000D02*
X128067Y557042D01*
X127775Y557208D01*
X127525Y557458D01*
X127358Y557750D01*
X127275Y558083D01*
Y558417D01*
X127358Y558750D01*
X127525Y559042D01*
X127775Y559292D01*
X128067Y559458D01*
X128400Y559500D01*
X128733Y559458D01*
X129025Y559292D01*
X129275Y559042D01*
X129442Y558750D01*
X129525Y558417D01*
Y558083D01*
X129442Y557750D01*
X129275Y557458D01*
X129025Y557208D01*
X128733Y557042D01*
X128400Y557000D01*
G01X128733Y557667D02*
X129233Y557000D01*
G01X131417D02*
X131500Y557542D01*
X131625Y558000D01*
X131792Y558417D01*
X132000Y558875D01*
X132333Y559500D01*
X130667D01*
G01X133808Y559083D02*
X134058Y559333D01*
X134350Y559458D01*
X134683Y559500D01*
X135100Y559417D01*
X135392Y559208D01*
X135475Y558958D01*
X135433Y558708D01*
X135267Y558500D01*
X134433Y558083D01*
X134058Y557792D01*
X133808Y557375D01*
X133725Y557000D01*
X135475D01*
G01X137800Y547300D02*
X149200D01*
G01X137800Y560700D02*
Y547300D01*
G01X149200Y560700D02*
X137800D01*
G01X149200Y547300D02*
Y560700D01*
G01X123516Y507550D02*
Y510050D01*
X124557D01*
X124891Y509925D01*
X125099Y509758D01*
X125182Y509425D01*
X125099Y509092D01*
X124849Y508883D01*
X124557Y508758D01*
X123516D01*
G01X124557D02*
X125182Y507550D01*
G01X126657Y509633D02*
X126907Y509883D01*
X127199Y510008D01*
X127532Y510050D01*
X127949Y509967D01*
X128241Y509758D01*
X128324Y509508D01*
X128282Y509258D01*
X128116Y509050D01*
X127282Y508633D01*
X126907Y508342D01*
X126657Y507925D01*
X126574Y507550D01*
X128324D01*
G01X130549D02*
X130841Y507592D01*
X131174Y507717D01*
X131382Y507925D01*
X131466Y508217D01*
X131382Y508508D01*
X131132Y508758D01*
X130757Y508883D01*
X130341D01*
X130091Y508967D01*
X129882Y509175D01*
X129799Y509467D01*
X129924Y509758D01*
X130216Y509967D01*
X130549Y510050D01*
X130882Y509967D01*
X131174Y509758D01*
X131299Y509467D01*
X131216Y509175D01*
X131007Y508967D01*
X130757Y508883D01*
X130341D01*
X129966Y508758D01*
X129716Y508508D01*
X129632Y508217D01*
X129716Y507925D01*
X129924Y507717D01*
X130257Y507592D01*
X130549Y507550D01*
G01X132941Y507842D02*
X133232Y507633D01*
X133566Y507550D01*
X133899Y507633D01*
X134191Y507883D01*
X134399Y508258D01*
X134482Y508633D01*
Y509092D01*
X134399Y509467D01*
X134191Y509800D01*
X133941Y509967D01*
X133649Y510050D01*
X133316Y509967D01*
X133066Y509800D01*
X132899Y509550D01*
X132816Y509217D01*
X132899Y508925D01*
X133107Y508633D01*
X133357Y508467D01*
X133649Y508425D01*
X133982Y508508D01*
X134232Y508717D01*
X134482Y509092D01*
G01X163249Y501613D02*
Y514613D01*
G01X137249Y501613D02*
X163249D01*
G01X137249Y514613D02*
Y501613D01*
G01X163249Y514613D02*
X137249D01*
G01X162999Y481050D02*
X136999D01*
G01X174799Y566050D02*
Y562050D01*
X182199D01*
G01X123017Y515500D02*
Y518000D01*
X124058D01*
X124392Y517875D01*
X124600Y517708D01*
X124683Y517375D01*
X124600Y517042D01*
X124350Y516833D01*
X124058Y516708D01*
X123017D01*
G01X124058D02*
X124683Y515500D01*
G01X126158Y517583D02*
X126408Y517833D01*
X126700Y517958D01*
X127033Y518000D01*
X127450Y517917D01*
X127742Y517708D01*
X127825Y517458D01*
X127783Y517208D01*
X127617Y517000D01*
X126783Y516583D01*
X126408Y516292D01*
X126158Y515875D01*
X126075Y515500D01*
X127825D01*
G01X129342Y515792D02*
X129633Y515583D01*
X129967Y515500D01*
X130300Y515583D01*
X130592Y515833D01*
X130800Y516208D01*
X130883Y516583D01*
Y517042D01*
X130800Y517417D01*
X130592Y517750D01*
X130342Y517917D01*
X130050Y518000D01*
X129717Y517917D01*
X129467Y517750D01*
X129300Y517500D01*
X129217Y517167D01*
X129300Y516875D01*
X129508Y516583D01*
X129758Y516417D01*
X130050Y516375D01*
X130383Y516458D01*
X130633Y516667D01*
X130883Y517042D01*
G01X133150Y515500D02*
Y518000D01*
X132650Y517500D01*
G01Y515500D02*
X133650D01*
G01X153699Y515613D02*
Y519613D01*
X146299D01*
G01X119517Y542000D02*
Y544500D01*
X120558D01*
X120892Y544375D01*
X121100Y544208D01*
X121183Y543875D01*
X121100Y543542D01*
X120850Y543333D01*
X120558Y543208D01*
X119517D01*
G01X120558D02*
X121183Y542000D01*
G01X122533Y542500D02*
X122783Y542208D01*
X123117Y542042D01*
X123492Y542000D01*
X123825Y542042D01*
X124158Y542250D01*
X124367Y542500D01*
X124408Y542750D01*
X124325Y543042D01*
X124033Y543250D01*
X123742Y543333D01*
X123367D01*
G01X123742D02*
X123992Y543458D01*
X124200Y543667D01*
X124283Y543917D01*
X124200Y544167D01*
X123992Y544375D01*
X123617Y544500D01*
X123242Y544458D01*
X122867Y544292D01*
G01X126550Y542000D02*
Y544500D01*
X126050Y544000D01*
G01Y542000D02*
X127050D01*
G01X130150D02*
Y544500D01*
X128608Y542708D01*
X130692D01*
G01X152099Y542050D02*
Y538050D01*
X159499D01*
G01X157199Y515150D02*
X161199D01*
Y522550D01*
G01X165199Y515150D02*
X169199D01*
Y522550D01*
G01X172199Y515150D02*
X176199D01*
Y522550D01*
G01X119517Y550500D02*
Y553000D01*
X120558D01*
X120892Y552875D01*
X121100Y552708D01*
X121183Y552375D01*
X121100Y552042D01*
X120850Y551833D01*
X120558Y551708D01*
X119517D01*
G01X120558D02*
X121183Y550500D01*
G01X122533Y551000D02*
X122783Y550708D01*
X123117Y550542D01*
X123492Y550500D01*
X123825Y550542D01*
X124158Y550750D01*
X124367Y551000D01*
X124408Y551250D01*
X124325Y551542D01*
X124033Y551750D01*
X123742Y551833D01*
X123367D01*
G01X123742D02*
X123992Y551958D01*
X124200Y552167D01*
X124283Y552417D01*
X124200Y552667D01*
X123992Y552875D01*
X123617Y553000D01*
X123242Y552958D01*
X122867Y552792D01*
G01X126550Y550500D02*
Y553000D01*
X126050Y552500D01*
G01Y550500D02*
X127050D01*
G01X128942Y550792D02*
X129233Y550583D01*
X129567Y550500D01*
X129900Y550583D01*
X130192Y550833D01*
X130400Y551208D01*
X130483Y551583D01*
Y552042D01*
X130400Y552417D01*
X130192Y552750D01*
X129942Y552917D01*
X129650Y553000D01*
X129317Y552917D01*
X129067Y552750D01*
X128900Y552500D01*
X128817Y552167D01*
X128900Y551875D01*
X129108Y551583D01*
X129358Y551417D01*
X129650Y551375D01*
X129983Y551458D01*
X130233Y551667D01*
X130483Y552042D01*
G01X152099Y546250D02*
Y542250D01*
X159499D01*
G01X161399Y522850D02*
Y526850D01*
X153999D01*
G01X168899Y522850D02*
Y526850D01*
X161499D01*
G01X176399Y522850D02*
Y526850D01*
X168999D01*
G01X128000Y527517D02*
X125500D01*
Y528558D01*
X125625Y528892D01*
X125792Y529100D01*
X126125Y529183D01*
X126458Y529100D01*
X126667Y528850D01*
X126792Y528558D01*
Y527517D01*
G01Y528558D02*
X128000Y529183D01*
G01Y531950D02*
X125500D01*
X127292Y530408D01*
Y532492D01*
G01X125500Y534550D02*
X125583Y534217D01*
X125792Y533967D01*
X126042Y533800D01*
X126375Y533675D01*
X126750Y533633D01*
X127125Y533675D01*
X127458Y533800D01*
X127708Y533967D01*
X127917Y534217D01*
X128000Y534550D01*
X127917Y534883D01*
X127708Y535133D01*
X127458Y535300D01*
X127125Y535425D01*
X126750Y535467D01*
X126375Y535425D01*
X126042Y535300D01*
X125792Y535133D01*
X125583Y534883D01*
X125500Y534550D01*
G01X125917Y536858D02*
X125667Y537108D01*
X125542Y537400D01*
X125500Y537733D01*
X125583Y538150D01*
X125792Y538442D01*
X126042Y538525D01*
X126292Y538483D01*
X126500Y538317D01*
X126917Y537483D01*
X127208Y537108D01*
X127625Y536858D01*
X128000Y536775D01*
Y538525D01*
G01X134000Y526800D02*
X138000D01*
Y534200D01*
G01X119517Y546500D02*
Y549000D01*
X120558D01*
X120892Y548875D01*
X121100Y548708D01*
X121183Y548375D01*
X121100Y548042D01*
X120850Y547833D01*
X120558Y547708D01*
X119517D01*
G01X120558D02*
X121183Y546500D01*
G01X123950D02*
Y549000D01*
X122408Y547208D01*
X124492D01*
G01X126550Y549000D02*
X126217Y548917D01*
X125967Y548708D01*
X125800Y548458D01*
X125675Y548125D01*
X125633Y547750D01*
X125675Y547375D01*
X125800Y547042D01*
X125967Y546792D01*
X126217Y546583D01*
X126550Y546500D01*
X126883Y546583D01*
X127133Y546792D01*
X127300Y547042D01*
X127425Y547375D01*
X127467Y547750D01*
X127425Y548125D01*
X127300Y548458D01*
X127133Y548708D01*
X126883Y548917D01*
X126550Y549000D01*
G01X128733Y547000D02*
X128983Y546708D01*
X129317Y546542D01*
X129692Y546500D01*
X130025Y546542D01*
X130358Y546750D01*
X130567Y547000D01*
X130608Y547250D01*
X130525Y547542D01*
X130233Y547750D01*
X129942Y547833D01*
X129567D01*
G01X129942D02*
X130192Y547958D01*
X130400Y548167D01*
X130483Y548417D01*
X130400Y548667D01*
X130192Y548875D01*
X129817Y549000D01*
X129442Y548958D01*
X129067Y548792D01*
G01X149200Y543000D02*
Y547000D01*
X141800D01*
G01X119699Y514967D02*
X117199D01*
Y516008D01*
X117324Y516342D01*
X117491Y516550D01*
X117824Y516633D01*
X118157Y516550D01*
X118366Y516300D01*
X118491Y516008D01*
Y514967D01*
G01Y516008D02*
X119699Y516633D01*
G01X117616Y518108D02*
X117366Y518358D01*
X117241Y518650D01*
X117199Y518983D01*
X117282Y519400D01*
X117491Y519692D01*
X117741Y519775D01*
X117991Y519733D01*
X118199Y519567D01*
X118616Y518733D01*
X118907Y518358D01*
X119324Y518108D01*
X119699Y518025D01*
Y519775D01*
G01X119407Y521292D02*
X119616Y521583D01*
X119699Y521917D01*
X119616Y522250D01*
X119366Y522542D01*
X118991Y522750D01*
X118616Y522833D01*
X118157D01*
X117782Y522750D01*
X117449Y522542D01*
X117282Y522292D01*
X117199Y522000D01*
X117282Y521667D01*
X117449Y521417D01*
X117699Y521250D01*
X118032Y521167D01*
X118324Y521250D01*
X118616Y521458D01*
X118782Y521708D01*
X118824Y522000D01*
X118741Y522333D01*
X118532Y522583D01*
X118157Y522833D01*
G01X119199Y524183D02*
X119491Y524433D01*
X119657Y524767D01*
X119699Y525142D01*
X119657Y525475D01*
X119449Y525808D01*
X119199Y526017D01*
X118949Y526058D01*
X118657Y525975D01*
X118449Y525683D01*
X118366Y525392D01*
Y525017D01*
G01Y525392D02*
X118241Y525642D01*
X118032Y525850D01*
X117782Y525933D01*
X117532Y525850D01*
X117324Y525642D01*
X117199Y525267D01*
X117241Y524892D01*
X117407Y524517D01*
G01X186949Y483353D02*
X173549D01*
G01Y493353D02*
X186949D01*
G01X173549Y483353D02*
Y493353D01*
G01X151400Y558000D02*
Y555500D01*
G01X150442Y558000D02*
X152358D01*
G01X153667Y555500D02*
Y558000D01*
X154667D01*
X155000Y557875D01*
X155250Y557583D01*
X155333Y557250D01*
X155250Y556917D01*
X155042Y556667D01*
X154667Y556542D01*
X153667D01*
G01X156808Y557583D02*
X157058Y557833D01*
X157350Y557958D01*
X157683Y558000D01*
X158100Y557917D01*
X158392Y557708D01*
X158475Y557458D01*
X158433Y557208D01*
X158267Y557000D01*
X157433Y556583D01*
X157058Y556292D01*
X156808Y555875D01*
X156725Y555500D01*
X158475D01*
G01X163467Y545378D02*
Y537378D01*
X175417D01*
Y545378D01*
X163467D01*
G01X175417Y539228D02*
X173417Y541228D01*
X175417Y543228D01*
G01X133208Y488267D02*
X133083Y488017D01*
X133000Y487725D01*
Y487392D01*
X133125Y487017D01*
X133333Y486725D01*
X133583Y486517D01*
X134000Y486350D01*
X134375Y486308D01*
X134750Y486392D01*
X135000Y486517D01*
X135250Y486767D01*
X135417Y487058D01*
X135500Y487350D01*
Y487642D01*
X135417Y487933D01*
X135292Y488183D01*
X135125Y488392D01*
G01X135000Y489533D02*
X135292Y489783D01*
X135458Y490117D01*
X135500Y490492D01*
X135458Y490825D01*
X135250Y491158D01*
X135000Y491367D01*
X134750Y491408D01*
X134458Y491325D01*
X134250Y491033D01*
X134167Y490742D01*
Y490367D01*
G01Y490742D02*
X134042Y490992D01*
X133833Y491200D01*
X133583Y491283D01*
X133333Y491200D01*
X133125Y490992D01*
X133000Y490617D01*
X133042Y490242D01*
X133208Y489867D01*
G01X135500Y493550D02*
X133000D01*
X133500Y493050D01*
G01X135500D02*
Y494050D01*
G01Y496567D02*
X134958Y496650D01*
X134500Y496775D01*
X134083Y496942D01*
X133625Y497150D01*
X133000Y497483D01*
Y495817D01*
G01X150499Y500913D02*
Y495413D01*
G01X142499Y500913D02*
X150499D01*
G01X142499Y495413D02*
Y500913D01*
G01Y483313D02*
Y488813D01*
G01X150499Y483313D02*
X142499D01*
G01X150499Y488813D02*
Y483313D01*
G01X132500Y529900D02*
X132458Y529567D01*
X132292Y529275D01*
X132042Y529025D01*
X131750Y528858D01*
X131417Y528775D01*
X131083D01*
X130750Y528858D01*
X130458Y529025D01*
X130208Y529275D01*
X130042Y529567D01*
X130000Y529900D01*
X130042Y530233D01*
X130208Y530525D01*
X130458Y530775D01*
X130750Y530942D01*
X131083Y531025D01*
X131417D01*
X131750Y530942D01*
X132042Y530775D01*
X132292Y530525D01*
X132458Y530233D01*
X132500Y529900D01*
G01X131833Y530233D02*
X132500Y530733D01*
G01Y532917D02*
X131958Y533000D01*
X131500Y533125D01*
X131083Y533292D01*
X130625Y533500D01*
X130000Y533833D01*
Y532167D01*
G01X132000Y535183D02*
X132292Y535433D01*
X132458Y535767D01*
X132500Y536142D01*
X132458Y536475D01*
X132250Y536808D01*
X132000Y537017D01*
X131750Y537058D01*
X131458Y536975D01*
X131250Y536683D01*
X131167Y536392D01*
Y536017D01*
G01Y536392D02*
X131042Y536642D01*
X130833Y536850D01*
X130583Y536933D01*
X130333Y536850D01*
X130125Y536642D01*
X130000Y536267D01*
X130042Y535892D01*
X130208Y535517D01*
G01X138500Y542300D02*
Y528300D01*
G01X151500Y542300D02*
X138500D01*
G01X151500Y528300D02*
Y542300D01*
G01X138500Y528300D02*
X151500D01*
G01X99567Y492725D02*
X99775Y493058D01*
X99900Y493433D01*
Y493767D01*
X99775Y494100D01*
X99567Y494350D01*
X99275Y494475D01*
X98983Y494392D01*
X98733Y494183D01*
X98567Y493808D01*
X98483Y493308D01*
X98317Y493017D01*
X98025Y492892D01*
X97733Y492975D01*
X97525Y493183D01*
X97400Y493475D01*
Y493767D01*
X97483Y494058D01*
X97692Y494308D01*
G01X99900Y495783D02*
X97400D01*
G01Y497367D02*
X98942Y495783D01*
G01X99900Y497617D02*
X98233Y496492D01*
G01X97400Y499800D02*
X99900D01*
G01X97400Y498842D02*
Y500758D01*
G01X99900Y502900D02*
X97400D01*
X97900Y502400D01*
G01X99900D02*
Y503400D01*
G01Y506500D02*
X97400D01*
X99192Y504958D01*
Y507042D01*
G01X118705Y631357D02*
X118455Y631482D01*
X118163Y631565D01*
X117830D01*
X117455Y631440D01*
X117163Y631232D01*
X116955Y630982D01*
X116788Y630565D01*
X116746Y630190D01*
X116830Y629815D01*
X116955Y629565D01*
X117205Y629315D01*
X117496Y629148D01*
X117788Y629065D01*
X118080D01*
X118371Y629148D01*
X118621Y629273D01*
X118830Y629440D01*
G01X120096Y631148D02*
X120346Y631398D01*
X120638Y631523D01*
X120971Y631565D01*
X121388Y631482D01*
X121680Y631273D01*
X121763Y631023D01*
X121721Y630773D01*
X121555Y630565D01*
X120721Y630148D01*
X120346Y629857D01*
X120096Y629440D01*
X120013Y629065D01*
X121763D01*
G01X123071Y629565D02*
X123321Y629273D01*
X123655Y629107D01*
X124030Y629065D01*
X124363Y629107D01*
X124696Y629315D01*
X124905Y629565D01*
X124946Y629815D01*
X124863Y630107D01*
X124571Y630315D01*
X124280Y630398D01*
X123905D01*
G01X124280D02*
X124530Y630523D01*
X124738Y630732D01*
X124821Y630982D01*
X124738Y631232D01*
X124530Y631440D01*
X124155Y631565D01*
X123780Y631523D01*
X123405Y631357D01*
G01X127088Y631565D02*
X126755Y631482D01*
X126505Y631273D01*
X126338Y631023D01*
X126213Y630690D01*
X126171Y630315D01*
X126213Y629940D01*
X126338Y629607D01*
X126505Y629357D01*
X126755Y629148D01*
X127088Y629065D01*
X127421Y629148D01*
X127671Y629357D01*
X127838Y629607D01*
X127963Y629940D01*
X128005Y630315D01*
X127963Y630690D01*
X127838Y631023D01*
X127671Y631273D01*
X127421Y631482D01*
X127088Y631565D01*
G01X118766Y635342D02*
X118516Y635467D01*
X118224Y635550D01*
X117891D01*
X117516Y635425D01*
X117224Y635217D01*
X117016Y634967D01*
X116849Y634550D01*
X116807Y634175D01*
X116891Y633800D01*
X117016Y633550D01*
X117266Y633300D01*
X117557Y633133D01*
X117849Y633050D01*
X118141D01*
X118432Y633133D01*
X118682Y633258D01*
X118891Y633425D01*
G01X120157Y635133D02*
X120407Y635383D01*
X120699Y635508D01*
X121032Y635550D01*
X121449Y635467D01*
X121741Y635258D01*
X121824Y635008D01*
X121782Y634758D01*
X121616Y634550D01*
X120782Y634133D01*
X120407Y633842D01*
X120157Y633425D01*
X120074Y633050D01*
X121824D01*
G01X123132Y633550D02*
X123382Y633258D01*
X123716Y633092D01*
X124091Y633050D01*
X124424Y633092D01*
X124757Y633300D01*
X124966Y633550D01*
X125007Y633800D01*
X124924Y634092D01*
X124632Y634300D01*
X124341Y634383D01*
X123966D01*
G01X124341D02*
X124591Y634508D01*
X124799Y634717D01*
X124882Y634967D01*
X124799Y635217D01*
X124591Y635425D01*
X124216Y635550D01*
X123841Y635508D01*
X123466Y635342D01*
G01X127149Y633050D02*
Y635550D01*
X126649Y635050D01*
G01Y633050D02*
X127649D01*
G01X140317Y577700D02*
Y575200D01*
X141983D01*
G01X145083D02*
X143417D01*
Y577700D01*
X145083D01*
G01X144417Y576492D02*
X143417D01*
G01X146433Y575200D02*
Y577700D01*
X147267D01*
X147600Y577575D01*
X147850Y577408D01*
X148058Y577158D01*
X148225Y576867D01*
X148267Y576450D01*
X148225Y576033D01*
X148058Y575742D01*
X147850Y575492D01*
X147600Y575325D01*
X147267Y575200D01*
X146433D01*
G01X149742Y575492D02*
X150033Y575283D01*
X150367Y575200D01*
X150700Y575283D01*
X150992Y575533D01*
X151200Y575908D01*
X151283Y576283D01*
Y576742D01*
X151200Y577117D01*
X150992Y577450D01*
X150742Y577617D01*
X150450Y577700D01*
X150117Y577617D01*
X149867Y577450D01*
X149700Y577200D01*
X149617Y576867D01*
X149700Y576575D01*
X149908Y576283D01*
X150158Y576117D01*
X150450Y576075D01*
X150783Y576158D01*
X151033Y576367D01*
X151283Y576742D01*
G01X173023Y571359D02*
Y563759D01*
X161623D01*
Y571359D01*
X173023D01*
G01X174799Y574050D02*
Y570050D01*
X182199D01*
G01X139516Y568550D02*
Y571050D01*
X140557D01*
X140891Y570925D01*
X141099Y570758D01*
X141182Y570425D01*
X141099Y570092D01*
X140849Y569883D01*
X140557Y569758D01*
X139516D01*
G01X140557D02*
X141182Y568550D01*
G01X142657Y570633D02*
X142907Y570883D01*
X143199Y571008D01*
X143532Y571050D01*
X143949Y570967D01*
X144241Y570758D01*
X144324Y570508D01*
X144282Y570258D01*
X144116Y570050D01*
X143282Y569633D01*
X142907Y569342D01*
X142657Y568925D01*
X142574Y568550D01*
X144324D01*
G01X146549D02*
Y571050D01*
X146049Y570550D01*
G01Y568550D02*
X147049D01*
G01X148732Y569050D02*
X148982Y568758D01*
X149316Y568592D01*
X149691Y568550D01*
X150024Y568592D01*
X150357Y568800D01*
X150566Y569050D01*
X150607Y569300D01*
X150524Y569592D01*
X150232Y569800D01*
X149941Y569883D01*
X149566D01*
G01X149941D02*
X150191Y570008D01*
X150399Y570217D01*
X150482Y570467D01*
X150399Y570717D01*
X150191Y570925D01*
X149816Y571050D01*
X149441Y571008D01*
X149066Y570842D01*
G01X152299Y572050D02*
Y568050D01*
X159699D01*
G01X174799Y570050D02*
Y566050D01*
X182199D01*
G01X139516Y564550D02*
Y567050D01*
X140557D01*
X140891Y566925D01*
X141099Y566758D01*
X141182Y566425D01*
X141099Y566092D01*
X140849Y565883D01*
X140557Y565758D01*
X139516D01*
G01X140557D02*
X141182Y564550D01*
G01X142657Y566633D02*
X142907Y566883D01*
X143199Y567008D01*
X143532Y567050D01*
X143949Y566967D01*
X144241Y566758D01*
X144324Y566508D01*
X144282Y566258D01*
X144116Y566050D01*
X143282Y565633D01*
X142907Y565342D01*
X142657Y564925D01*
X142574Y564550D01*
X144324D01*
G01X146549D02*
Y567050D01*
X146049Y566550D01*
G01Y564550D02*
X147049D01*
G01X148732Y564925D02*
X148982Y564717D01*
X149274Y564592D01*
X149649Y564550D01*
X150024Y564633D01*
X150316Y564800D01*
X150524Y565092D01*
X150566Y565425D01*
X150482Y565758D01*
X150274Y565967D01*
X149982Y566133D01*
X149691Y566175D01*
X149399Y566133D01*
X149024Y565967D01*
X149149Y567050D01*
X150274D01*
G01X152299Y568050D02*
Y564050D01*
X159699D01*
G01X144623Y591329D02*
Y752529D01*
X158223D01*
Y765479D01*
X176423D01*
Y752529D01*
X205323D01*
Y742179D01*
X198623D01*
Y601679D01*
X205323D01*
Y591329D01*
X176423D01*
Y578379D01*
X158223D01*
Y591329D01*
X144623D01*
G01X118205Y655357D02*
X117955Y655482D01*
X117663Y655565D01*
X117330D01*
X116955Y655440D01*
X116663Y655232D01*
X116455Y654982D01*
X116288Y654565D01*
X116246Y654190D01*
X116330Y653815D01*
X116455Y653565D01*
X116705Y653315D01*
X116996Y653148D01*
X117288Y653065D01*
X117580D01*
X117871Y653148D01*
X118121Y653273D01*
X118330Y653440D01*
G01X119596Y655148D02*
X119846Y655398D01*
X120138Y655523D01*
X120471Y655565D01*
X120888Y655482D01*
X121180Y655273D01*
X121263Y655023D01*
X121221Y654773D01*
X121055Y654565D01*
X120221Y654148D01*
X119846Y653857D01*
X119596Y653440D01*
X119513Y653065D01*
X121263D01*
G01X122571Y653565D02*
X122821Y653273D01*
X123155Y653107D01*
X123530Y653065D01*
X123863Y653107D01*
X124196Y653315D01*
X124405Y653565D01*
X124446Y653815D01*
X124363Y654107D01*
X124071Y654315D01*
X123780Y654398D01*
X123405D01*
G01X123780D02*
X124030Y654523D01*
X124238Y654732D01*
X124321Y654982D01*
X124238Y655232D01*
X124030Y655440D01*
X123655Y655565D01*
X123280Y655523D01*
X122905Y655357D01*
G01X125796Y655148D02*
X126046Y655398D01*
X126338Y655523D01*
X126671Y655565D01*
X127088Y655482D01*
X127380Y655273D01*
X127463Y655023D01*
X127421Y654773D01*
X127255Y654565D01*
X126421Y654148D01*
X126046Y653857D01*
X125796Y653440D01*
X125713Y653065D01*
X127463D01*
G01X118266Y659342D02*
X118016Y659467D01*
X117724Y659550D01*
X117391D01*
X117016Y659425D01*
X116724Y659217D01*
X116516Y658967D01*
X116349Y658550D01*
X116307Y658175D01*
X116391Y657800D01*
X116516Y657550D01*
X116766Y657300D01*
X117057Y657133D01*
X117349Y657050D01*
X117641D01*
X117932Y657133D01*
X118182Y657258D01*
X118391Y657425D01*
G01X119657Y659133D02*
X119907Y659383D01*
X120199Y659508D01*
X120532Y659550D01*
X120949Y659467D01*
X121241Y659258D01*
X121324Y659008D01*
X121282Y658758D01*
X121116Y658550D01*
X120282Y658133D01*
X119907Y657842D01*
X119657Y657425D01*
X119574Y657050D01*
X121324D01*
G01X122632Y657550D02*
X122882Y657258D01*
X123216Y657092D01*
X123591Y657050D01*
X123924Y657092D01*
X124257Y657300D01*
X124466Y657550D01*
X124507Y657800D01*
X124424Y658092D01*
X124132Y658300D01*
X123841Y658383D01*
X123466D01*
G01X123841D02*
X124091Y658508D01*
X124299Y658717D01*
X124382Y658967D01*
X124299Y659217D01*
X124091Y659425D01*
X123716Y659550D01*
X123341Y659508D01*
X122966Y659342D01*
G01X125732Y657550D02*
X125982Y657258D01*
X126316Y657092D01*
X126691Y657050D01*
X127024Y657092D01*
X127357Y657300D01*
X127566Y657550D01*
X127607Y657800D01*
X127524Y658092D01*
X127232Y658300D01*
X126941Y658383D01*
X126566D01*
G01X126941D02*
X127191Y658508D01*
X127399Y658717D01*
X127482Y658967D01*
X127399Y659217D01*
X127191Y659425D01*
X126816Y659550D01*
X126441Y659508D01*
X126066Y659342D01*
G01X171499Y794630D02*
X168999D01*
Y795671D01*
X169124Y796005D01*
X169291Y796213D01*
X169624Y796296D01*
X169957Y796213D01*
X170166Y795963D01*
X170291Y795671D01*
Y794630D01*
G01Y795671D02*
X171499Y796296D01*
G01Y799063D02*
X168999D01*
X170791Y797521D01*
Y799605D01*
G01X171499Y801580D02*
X170957Y801663D01*
X170499Y801788D01*
X170082Y801955D01*
X169624Y802163D01*
X168999Y802496D01*
Y800830D01*
G01Y804763D02*
X169082Y804430D01*
X169291Y804180D01*
X169541Y804013D01*
X169874Y803888D01*
X170249Y803846D01*
X170624Y803888D01*
X170957Y804013D01*
X171207Y804180D01*
X171416Y804430D01*
X171499Y804763D01*
X171416Y805096D01*
X171207Y805346D01*
X170957Y805513D01*
X170624Y805638D01*
X170249Y805680D01*
X169874Y805638D01*
X169541Y805513D01*
X169291Y805346D01*
X169082Y805096D01*
X168999Y804763D01*
G01X168499Y806913D02*
X172499D01*
Y814313D01*
G01X167499Y794630D02*
X164999D01*
Y795671D01*
X165124Y796005D01*
X165291Y796213D01*
X165624Y796296D01*
X165957Y796213D01*
X166166Y795963D01*
X166291Y795671D01*
Y794630D01*
G01Y795671D02*
X167499Y796296D01*
G01Y799063D02*
X164999D01*
X166791Y797521D01*
Y799605D01*
G01X167499Y801580D02*
X166957Y801663D01*
X166499Y801788D01*
X166082Y801955D01*
X165624Y802163D01*
X164999Y802496D01*
Y800830D01*
G01X167499Y804763D02*
X164999D01*
X165499Y804263D01*
G01X167499D02*
Y805263D01*
G01X164499Y806913D02*
X168499D01*
Y814313D01*
G01X175009Y806402D02*
X176801D01*
X177176Y806569D01*
X177426Y806902D01*
X177509Y807319D01*
X177426Y807736D01*
X177176Y808069D01*
X176801Y808236D01*
X175009D01*
G01X177009Y809502D02*
X177301Y809752D01*
X177467Y810086D01*
X177509Y810461D01*
X177467Y810794D01*
X177259Y811127D01*
X177009Y811336D01*
X176759Y811377D01*
X176467Y811294D01*
X176259Y811002D01*
X176176Y810711D01*
Y810336D01*
G01Y810711D02*
X176051Y810961D01*
X175842Y811169D01*
X175592Y811252D01*
X175342Y811169D01*
X175134Y810961D01*
X175009Y810586D01*
X175051Y810211D01*
X175217Y809836D01*
G01X177217Y812811D02*
X177426Y813102D01*
X177509Y813436D01*
X177426Y813769D01*
X177176Y814061D01*
X176801Y814269D01*
X176426Y814352D01*
X175967D01*
X175592Y814269D01*
X175259Y814061D01*
X175092Y813811D01*
X175009Y813519D01*
X175092Y813186D01*
X175259Y812936D01*
X175509Y812769D01*
X175842Y812686D01*
X176134Y812769D01*
X176426Y812977D01*
X176592Y813227D01*
X176634Y813519D01*
X176551Y813852D01*
X176342Y814102D01*
X175967Y814352D01*
G01X109999Y864050D02*
X119999D01*
G01Y857050D02*
X109999D01*
G01X114999D02*
Y864050D01*
G01X109999Y853617D02*
X119999D01*
Y850283D01*
X119499Y848950D01*
X118832Y847950D01*
X117832Y847117D01*
X116665Y846450D01*
X114999Y846283D01*
X113332Y846450D01*
X112166Y847117D01*
X111165Y847950D01*
X110499Y848950D01*
X109999Y850283D01*
Y853617D01*
G01Y843017D02*
X119999D01*
Y839683D01*
X119499Y838350D01*
X118832Y837350D01*
X117832Y836517D01*
X116665Y835850D01*
X114999Y835683D01*
X113332Y835850D01*
X112166Y836517D01*
X111165Y837350D01*
X110499Y838350D01*
X109999Y839683D01*
Y843017D01*
G01Y828750D02*
X119999D01*
X117999Y830750D01*
G01X109999D02*
Y826750D01*
G01X118332Y821317D02*
X119332Y820317D01*
X119832Y819150D01*
X119999Y817817D01*
X119666Y816150D01*
X118832Y814983D01*
X117832Y814650D01*
X116832Y814817D01*
X115999Y815483D01*
X114332Y818817D01*
X113166Y820317D01*
X111499Y821317D01*
X109999Y821650D01*
Y814650D01*
G01X154208Y816267D02*
X154083Y816017D01*
X154000Y815725D01*
Y815392D01*
X154125Y815017D01*
X154333Y814725D01*
X154583Y814517D01*
X155000Y814350D01*
X155375Y814308D01*
X155750Y814392D01*
X156000Y814517D01*
X156250Y814767D01*
X156417Y815058D01*
X156500Y815350D01*
Y815642D01*
X156417Y815933D01*
X156292Y816183D01*
X156125Y816392D01*
G01X156000Y817533D02*
X156292Y817783D01*
X156458Y818117D01*
X156500Y818492D01*
X156458Y818825D01*
X156250Y819158D01*
X156000Y819367D01*
X155750Y819408D01*
X155458Y819325D01*
X155250Y819033D01*
X155167Y818742D01*
Y818367D01*
G01Y818742D02*
X155042Y818992D01*
X154833Y819200D01*
X154583Y819283D01*
X154333Y819200D01*
X154125Y818992D01*
X154000Y818617D01*
X154042Y818242D01*
X154208Y817867D01*
G01X154000Y821550D02*
X154083Y821217D01*
X154292Y820967D01*
X154542Y820800D01*
X154875Y820675D01*
X155250Y820633D01*
X155625Y820675D01*
X155958Y820800D01*
X156208Y820967D01*
X156417Y821217D01*
X156500Y821550D01*
X156417Y821883D01*
X156208Y822133D01*
X155958Y822300D01*
X155625Y822425D01*
X155250Y822467D01*
X154875Y822425D01*
X154542Y822300D01*
X154292Y822133D01*
X154083Y821883D01*
X154000Y821550D01*
G01X156500Y824650D02*
X154000D01*
X154500Y824150D01*
G01X156500D02*
Y825150D01*
G01X138307Y887317D02*
X138182Y887067D01*
X138099Y886775D01*
Y886442D01*
X138224Y886067D01*
X138432Y885775D01*
X138682Y885567D01*
X139099Y885400D01*
X139474Y885358D01*
X139849Y885442D01*
X140099Y885567D01*
X140349Y885817D01*
X140516Y886108D01*
X140599Y886400D01*
Y886692D01*
X140516Y886983D01*
X140391Y887233D01*
X140224Y887442D01*
G01X138516Y888708D02*
X138266Y888958D01*
X138141Y889250D01*
X138099Y889583D01*
X138182Y890000D01*
X138391Y890292D01*
X138641Y890375D01*
X138891Y890333D01*
X139099Y890167D01*
X139516Y889333D01*
X139807Y888958D01*
X140224Y888708D01*
X140599Y888625D01*
Y890375D01*
G01X140307Y891892D02*
X140516Y892183D01*
X140599Y892517D01*
X140516Y892850D01*
X140266Y893142D01*
X139891Y893350D01*
X139516Y893433D01*
X139057D01*
X138682Y893350D01*
X138349Y893142D01*
X138182Y892892D01*
X138099Y892600D01*
X138182Y892267D01*
X138349Y892017D01*
X138599Y891850D01*
X138932Y891767D01*
X139224Y891850D01*
X139516Y892058D01*
X139682Y892308D01*
X139724Y892600D01*
X139641Y892933D01*
X139432Y893183D01*
X139057Y893433D01*
G01X140599Y895700D02*
X140557Y895992D01*
X140432Y896325D01*
X140224Y896533D01*
X139932Y896617D01*
X139641Y896533D01*
X139391Y896283D01*
X139266Y895908D01*
Y895492D01*
X139182Y895242D01*
X138974Y895033D01*
X138682Y894950D01*
X138391Y895075D01*
X138182Y895367D01*
X138099Y895700D01*
X138182Y896033D01*
X138391Y896325D01*
X138682Y896450D01*
X138974Y896367D01*
X139182Y896158D01*
X139266Y895908D01*
Y895492D01*
X139391Y895117D01*
X139641Y894867D01*
X139932Y894783D01*
X140224Y894867D01*
X140432Y895075D01*
X140557Y895408D01*
X140599Y895700D01*
G01X143708Y852767D02*
X143583Y852517D01*
X143500Y852225D01*
Y851892D01*
X143625Y851517D01*
X143833Y851225D01*
X144083Y851017D01*
X144500Y850850D01*
X144875Y850808D01*
X145250Y850892D01*
X145500Y851017D01*
X145750Y851267D01*
X145917Y851558D01*
X146000Y851850D01*
Y852142D01*
X145917Y852433D01*
X145792Y852683D01*
X145625Y852892D01*
G01X145500Y854033D02*
X145792Y854283D01*
X145958Y854617D01*
X146000Y854992D01*
X145958Y855325D01*
X145750Y855658D01*
X145500Y855867D01*
X145250Y855908D01*
X144958Y855825D01*
X144750Y855533D01*
X144667Y855242D01*
Y854867D01*
G01Y855242D02*
X144542Y855492D01*
X144333Y855700D01*
X144083Y855783D01*
X143833Y855700D01*
X143625Y855492D01*
X143500Y855117D01*
X143542Y854742D01*
X143708Y854367D01*
G01X143500Y858050D02*
X143583Y857717D01*
X143792Y857467D01*
X144042Y857300D01*
X144375Y857175D01*
X144750Y857133D01*
X145125Y857175D01*
X145458Y857300D01*
X145708Y857467D01*
X145917Y857717D01*
X146000Y858050D01*
X145917Y858383D01*
X145708Y858633D01*
X145458Y858800D01*
X145125Y858925D01*
X144750Y858967D01*
X144375Y858925D01*
X144042Y858800D01*
X143792Y858633D01*
X143583Y858383D01*
X143500Y858050D01*
G01X146000Y861067D02*
X145458Y861150D01*
X145000Y861275D01*
X144583Y861442D01*
X144125Y861650D01*
X143500Y861983D01*
Y860317D01*
G01X147516Y872050D02*
Y874550D01*
X148557D01*
X148891Y874425D01*
X149099Y874258D01*
X149182Y873925D01*
X149099Y873592D01*
X148849Y873383D01*
X148557Y873258D01*
X147516D01*
G01X148557D02*
X149182Y872050D01*
G01X150657Y874133D02*
X150907Y874383D01*
X151199Y874508D01*
X151532Y874550D01*
X151949Y874467D01*
X152241Y874258D01*
X152324Y874008D01*
X152282Y873758D01*
X152116Y873550D01*
X151282Y873133D01*
X150907Y872842D01*
X150657Y872425D01*
X150574Y872050D01*
X152324D01*
G01X154466D02*
X154549Y872592D01*
X154674Y873050D01*
X154841Y873467D01*
X155049Y873925D01*
X155382Y874550D01*
X153716D01*
G01X156857Y873092D02*
X157149Y873383D01*
X157399Y873550D01*
X157732Y873633D01*
X158024Y873550D01*
X158232Y873383D01*
X158399Y873133D01*
X158441Y872842D01*
X158399Y872592D01*
X158232Y872342D01*
X157982Y872133D01*
X157691Y872050D01*
X157357Y872133D01*
X157066Y872383D01*
X156899Y872758D01*
X156857Y873175D01*
X156941Y873717D01*
X157066Y874008D01*
X157274Y874300D01*
X157566Y874508D01*
X157857Y874550D01*
X158149Y874467D01*
X158357Y874258D01*
G01X160499Y866613D02*
X186499D01*
G01X160499Y879613D02*
Y866613D01*
G01X186499Y879613D02*
X160499D01*
G01X154999Y832630D02*
X152499D01*
Y833671D01*
X152624Y834005D01*
X152791Y834213D01*
X153124Y834296D01*
X153457Y834213D01*
X153666Y833963D01*
X153791Y833671D01*
Y832630D01*
G01Y833671D02*
X154999Y834296D01*
G01X152916Y835771D02*
X152666Y836021D01*
X152541Y836313D01*
X152499Y836646D01*
X152582Y837063D01*
X152791Y837355D01*
X153041Y837438D01*
X153291Y837396D01*
X153499Y837230D01*
X153916Y836396D01*
X154207Y836021D01*
X154624Y835771D01*
X154999Y835688D01*
Y837438D01*
G01Y839580D02*
X154457Y839663D01*
X153999Y839788D01*
X153582Y839955D01*
X153124Y840163D01*
X152499Y840496D01*
Y838830D01*
G01X154999Y842680D02*
X154457Y842763D01*
X153999Y842888D01*
X153582Y843055D01*
X153124Y843263D01*
X152499Y843596D01*
Y841930D01*
G01X165499Y831413D02*
X169499D01*
Y838813D01*
G01X162999Y832567D02*
X160499D01*
Y833608D01*
X160624Y833942D01*
X160791Y834150D01*
X161124Y834233D01*
X161457Y834150D01*
X161666Y833900D01*
X161791Y833608D01*
Y832567D01*
G01Y833608D02*
X162999Y834233D01*
G01X160916Y835708D02*
X160666Y835958D01*
X160541Y836250D01*
X160499Y836583D01*
X160582Y837000D01*
X160791Y837292D01*
X161041Y837375D01*
X161291Y837333D01*
X161499Y837167D01*
X161916Y836333D01*
X162207Y835958D01*
X162624Y835708D01*
X162999Y835625D01*
Y837375D01*
G01Y839600D02*
X162957Y839892D01*
X162832Y840225D01*
X162624Y840433D01*
X162332Y840517D01*
X162041Y840433D01*
X161791Y840183D01*
X161666Y839808D01*
Y839392D01*
X161582Y839142D01*
X161374Y838933D01*
X161082Y838850D01*
X160791Y838975D01*
X160582Y839267D01*
X160499Y839600D01*
X160582Y839933D01*
X160791Y840225D01*
X161082Y840350D01*
X161374Y840267D01*
X161582Y840058D01*
X161666Y839808D01*
Y839392D01*
X161791Y839017D01*
X162041Y838767D01*
X162332Y838683D01*
X162624Y838767D01*
X162832Y838975D01*
X162957Y839308D01*
X162999Y839600D01*
G01X160499Y842700D02*
X160582Y842367D01*
X160791Y842117D01*
X161041Y841950D01*
X161374Y841825D01*
X161749Y841783D01*
X162124Y841825D01*
X162457Y841950D01*
X162707Y842117D01*
X162916Y842367D01*
X162999Y842700D01*
X162916Y843033D01*
X162707Y843283D01*
X162457Y843450D01*
X162124Y843575D01*
X161749Y843617D01*
X161374Y843575D01*
X161041Y843450D01*
X160791Y843283D01*
X160582Y843033D01*
X160499Y842700D01*
G01X178499Y838813D02*
X174499D01*
Y831413D01*
G01X158999Y832567D02*
X156499D01*
Y833608D01*
X156624Y833942D01*
X156791Y834150D01*
X157124Y834233D01*
X157457Y834150D01*
X157666Y833900D01*
X157791Y833608D01*
Y832567D01*
G01Y833608D02*
X158999Y834233D01*
G01X156916Y835708D02*
X156666Y835958D01*
X156541Y836250D01*
X156499Y836583D01*
X156582Y837000D01*
X156791Y837292D01*
X157041Y837375D01*
X157291Y837333D01*
X157499Y837167D01*
X157916Y836333D01*
X158207Y835958D01*
X158624Y835708D01*
X158999Y835625D01*
Y837375D01*
G01Y839600D02*
X158957Y839892D01*
X158832Y840225D01*
X158624Y840433D01*
X158332Y840517D01*
X158041Y840433D01*
X157791Y840183D01*
X157666Y839808D01*
Y839392D01*
X157582Y839142D01*
X157374Y838933D01*
X157082Y838850D01*
X156791Y838975D01*
X156582Y839267D01*
X156499Y839600D01*
X156582Y839933D01*
X156791Y840225D01*
X157082Y840350D01*
X157374Y840267D01*
X157582Y840058D01*
X157666Y839808D01*
Y839392D01*
X157791Y839017D01*
X158041Y838767D01*
X158332Y838683D01*
X158624Y838767D01*
X158832Y838975D01*
X158957Y839308D01*
X158999Y839600D01*
G01Y842700D02*
X156499D01*
X156999Y842200D01*
G01X158999D02*
Y843200D01*
G01X170499Y831413D02*
X174499D01*
Y838813D01*
G01X174999Y830313D02*
Y816913D01*
G01X164999Y830313D02*
X174999D01*
G01X164999Y816913D02*
Y830313D01*
G01X174999Y816913D02*
X164999D01*
G01X115349Y873550D02*
Y871050D01*
G01X114391Y873550D02*
X116307D01*
G01X117616Y871050D02*
Y873550D01*
X118616D01*
X118949Y873425D01*
X119199Y873133D01*
X119282Y872800D01*
X119199Y872467D01*
X118991Y872217D01*
X118616Y872092D01*
X117616D01*
G01X120632Y871550D02*
X120882Y871258D01*
X121216Y871092D01*
X121591Y871050D01*
X121924Y871092D01*
X122257Y871300D01*
X122466Y871550D01*
X122507Y871800D01*
X122424Y872092D01*
X122132Y872300D01*
X121841Y872383D01*
X121466D01*
G01X121841D02*
X122091Y872508D01*
X122299Y872717D01*
X122382Y872967D01*
X122299Y873217D01*
X122091Y873425D01*
X121716Y873550D01*
X121341Y873508D01*
X120966Y873342D01*
G01X124566Y871050D02*
X124649Y871592D01*
X124774Y872050D01*
X124941Y872467D01*
X125149Y872925D01*
X125482Y873550D01*
X123816D01*
G01X157208Y852767D02*
X157083Y852517D01*
X157000Y852225D01*
Y851892D01*
X157125Y851517D01*
X157333Y851225D01*
X157583Y851017D01*
X158000Y850850D01*
X158375Y850808D01*
X158750Y850892D01*
X159000Y851017D01*
X159250Y851267D01*
X159417Y851558D01*
X159500Y851850D01*
Y852142D01*
X159417Y852433D01*
X159292Y852683D01*
X159125Y852892D01*
G01X159000Y854033D02*
X159292Y854283D01*
X159458Y854617D01*
X159500Y854992D01*
X159458Y855325D01*
X159250Y855658D01*
X159000Y855867D01*
X158750Y855908D01*
X158458Y855825D01*
X158250Y855533D01*
X158167Y855242D01*
Y854867D01*
G01Y855242D02*
X158042Y855492D01*
X157833Y855700D01*
X157583Y855783D01*
X157333Y855700D01*
X157125Y855492D01*
X157000Y855117D01*
X157042Y854742D01*
X157208Y854367D01*
G01X157000Y858050D02*
X157083Y857717D01*
X157292Y857467D01*
X157542Y857300D01*
X157875Y857175D01*
X158250Y857133D01*
X158625Y857175D01*
X158958Y857300D01*
X159208Y857467D01*
X159417Y857717D01*
X159500Y858050D01*
X159417Y858383D01*
X159208Y858633D01*
X158958Y858800D01*
X158625Y858925D01*
X158250Y858967D01*
X157875Y858925D01*
X157542Y858800D01*
X157292Y858633D01*
X157083Y858383D01*
X157000Y858050D01*
G01X159500Y861650D02*
X157000D01*
X158792Y860108D01*
Y862192D01*
G01X152708Y852767D02*
X152583Y852517D01*
X152500Y852225D01*
Y851892D01*
X152625Y851517D01*
X152833Y851225D01*
X153083Y851017D01*
X153500Y850850D01*
X153875Y850808D01*
X154250Y850892D01*
X154500Y851017D01*
X154750Y851267D01*
X154917Y851558D01*
X155000Y851850D01*
Y852142D01*
X154917Y852433D01*
X154792Y852683D01*
X154625Y852892D01*
G01X154500Y854033D02*
X154792Y854283D01*
X154958Y854617D01*
X155000Y854992D01*
X154958Y855325D01*
X154750Y855658D01*
X154500Y855867D01*
X154250Y855908D01*
X153958Y855825D01*
X153750Y855533D01*
X153667Y855242D01*
Y854867D01*
G01Y855242D02*
X153542Y855492D01*
X153333Y855700D01*
X153083Y855783D01*
X152833Y855700D01*
X152625Y855492D01*
X152500Y855117D01*
X152542Y854742D01*
X152708Y854367D01*
G01X152500Y858050D02*
X152583Y857717D01*
X152792Y857467D01*
X153042Y857300D01*
X153375Y857175D01*
X153750Y857133D01*
X154125Y857175D01*
X154458Y857300D01*
X154708Y857467D01*
X154917Y857717D01*
X155000Y858050D01*
X154917Y858383D01*
X154708Y858633D01*
X154458Y858800D01*
X154125Y858925D01*
X153750Y858967D01*
X153375Y858925D01*
X153042Y858800D01*
X152792Y858633D01*
X152583Y858383D01*
X152500Y858050D01*
G01X154625Y860233D02*
X154833Y860483D01*
X154958Y860775D01*
X155000Y861150D01*
X154917Y861525D01*
X154750Y861817D01*
X154458Y862025D01*
X154125Y862067D01*
X153792Y861983D01*
X153583Y861775D01*
X153417Y861483D01*
X153375Y861192D01*
X153417Y860900D01*
X153583Y860525D01*
X152500Y860650D01*
Y861775D01*
G01X174999Y865913D02*
X182999D01*
G01X174999Y860413D02*
Y865913D01*
G01Y848313D02*
Y853813D01*
G01X182999Y848313D02*
X174999D01*
G01X148208Y852767D02*
X148083Y852517D01*
X148000Y852225D01*
Y851892D01*
X148125Y851517D01*
X148333Y851225D01*
X148583Y851017D01*
X149000Y850850D01*
X149375Y850808D01*
X149750Y850892D01*
X150000Y851017D01*
X150250Y851267D01*
X150417Y851558D01*
X150500Y851850D01*
Y852142D01*
X150417Y852433D01*
X150292Y852683D01*
X150125Y852892D01*
G01X150000Y854033D02*
X150292Y854283D01*
X150458Y854617D01*
X150500Y854992D01*
X150458Y855325D01*
X150250Y855658D01*
X150000Y855867D01*
X149750Y855908D01*
X149458Y855825D01*
X149250Y855533D01*
X149167Y855242D01*
Y854867D01*
G01Y855242D02*
X149042Y855492D01*
X148833Y855700D01*
X148583Y855783D01*
X148333Y855700D01*
X148125Y855492D01*
X148000Y855117D01*
X148042Y854742D01*
X148208Y854367D01*
G01X148000Y858050D02*
X148083Y857717D01*
X148292Y857467D01*
X148542Y857300D01*
X148875Y857175D01*
X149250Y857133D01*
X149625Y857175D01*
X149958Y857300D01*
X150208Y857467D01*
X150417Y857717D01*
X150500Y858050D01*
X150417Y858383D01*
X150208Y858633D01*
X149958Y858800D01*
X149625Y858925D01*
X149250Y858967D01*
X148875Y858925D01*
X148542Y858800D01*
X148292Y858633D01*
X148083Y858383D01*
X148000Y858050D01*
G01X149458Y860358D02*
X149167Y860650D01*
X149000Y860900D01*
X148917Y861233D01*
X149000Y861525D01*
X149167Y861733D01*
X149417Y861900D01*
X149708Y861942D01*
X149958Y861900D01*
X150208Y861733D01*
X150417Y861483D01*
X150500Y861192D01*
X150417Y860858D01*
X150167Y860567D01*
X149792Y860400D01*
X149375Y860358D01*
X148833Y860442D01*
X148542Y860567D01*
X148250Y860775D01*
X148042Y861067D01*
X148000Y861358D01*
X148083Y861650D01*
X148292Y861858D01*
G01X173999Y865913D02*
Y860413D01*
G01X165999Y865913D02*
X173999D01*
G01X165999Y860413D02*
Y865913D01*
G01Y848313D02*
Y853813D01*
G01X173999Y848313D02*
X165999D01*
G01X173999Y853813D02*
Y848313D01*
G01X142308Y887267D02*
X142183Y887017D01*
X142100Y886725D01*
Y886392D01*
X142225Y886017D01*
X142433Y885725D01*
X142683Y885517D01*
X143100Y885350D01*
X143475Y885308D01*
X143850Y885392D01*
X144100Y885517D01*
X144350Y885767D01*
X144517Y886058D01*
X144600Y886350D01*
Y886642D01*
X144517Y886933D01*
X144392Y887183D01*
X144225Y887392D01*
G01X142517Y888658D02*
X142267Y888908D01*
X142142Y889200D01*
X142100Y889533D01*
X142183Y889950D01*
X142392Y890242D01*
X142642Y890325D01*
X142892Y890283D01*
X143100Y890117D01*
X143517Y889283D01*
X143808Y888908D01*
X144225Y888658D01*
X144600Y888575D01*
Y890325D01*
G01X144308Y891842D02*
X144517Y892133D01*
X144600Y892467D01*
X144517Y892800D01*
X144267Y893092D01*
X143892Y893300D01*
X143517Y893383D01*
X143058D01*
X142683Y893300D01*
X142350Y893092D01*
X142183Y892842D01*
X142100Y892550D01*
X142183Y892217D01*
X142350Y891967D01*
X142600Y891800D01*
X142933Y891717D01*
X143225Y891800D01*
X143517Y892008D01*
X143683Y892258D01*
X143725Y892550D01*
X143642Y892883D01*
X143433Y893133D01*
X143058Y893383D01*
G01X144308Y894942D02*
X144517Y895233D01*
X144600Y895567D01*
X144517Y895900D01*
X144267Y896192D01*
X143892Y896400D01*
X143517Y896483D01*
X143058D01*
X142683Y896400D01*
X142350Y896192D01*
X142183Y895942D01*
X142100Y895650D01*
X142183Y895317D01*
X142350Y895067D01*
X142600Y894900D01*
X142933Y894817D01*
X143225Y894900D01*
X143517Y895108D01*
X143683Y895358D01*
X143725Y895650D01*
X143642Y895983D01*
X143433Y896233D01*
X143058Y896483D01*
G01X173499Y899413D02*
Y893913D01*
G01X165499D02*
Y899413D01*
G01Y881813D02*
Y887313D01*
G01X173499Y881813D02*
X165499D01*
G01X173499Y887313D02*
Y881813D01*
G01X112812Y957781D02*
X112562Y957906D01*
X112270Y957989D01*
X111937D01*
X111562Y957864D01*
X111270Y957656D01*
X111062Y957406D01*
X110895Y956989D01*
X110853Y956614D01*
X110937Y956239D01*
X111062Y955989D01*
X111312Y955739D01*
X111603Y955572D01*
X111895Y955489D01*
X112187D01*
X112478Y955572D01*
X112728Y955697D01*
X112937Y955864D01*
G01X114203Y957572D02*
X114453Y957822D01*
X114745Y957947D01*
X115078Y957989D01*
X115495Y957906D01*
X115787Y957697D01*
X115870Y957447D01*
X115828Y957197D01*
X115662Y956989D01*
X114828Y956572D01*
X114453Y956281D01*
X114203Y955864D01*
X114120Y955489D01*
X115870D01*
G01X117387Y955781D02*
X117678Y955572D01*
X118012Y955489D01*
X118345Y955572D01*
X118637Y955822D01*
X118845Y956197D01*
X118928Y956572D01*
Y957031D01*
X118845Y957406D01*
X118637Y957739D01*
X118387Y957906D01*
X118095Y957989D01*
X117762Y957906D01*
X117512Y957739D01*
X117345Y957489D01*
X117262Y957156D01*
X117345Y956864D01*
X117553Y956572D01*
X117803Y956406D01*
X118095Y956364D01*
X118428Y956447D01*
X118678Y956656D01*
X118928Y957031D01*
G01X121695Y955489D02*
Y957989D01*
X120153Y956197D01*
X122237D01*
G01X112812Y954281D02*
X112562Y954406D01*
X112270Y954489D01*
X111937D01*
X111562Y954364D01*
X111270Y954156D01*
X111062Y953906D01*
X110895Y953489D01*
X110853Y953114D01*
X110937Y952739D01*
X111062Y952489D01*
X111312Y952239D01*
X111603Y952072D01*
X111895Y951989D01*
X112187D01*
X112478Y952072D01*
X112728Y952197D01*
X112937Y952364D01*
G01X114203Y954072D02*
X114453Y954322D01*
X114745Y954447D01*
X115078Y954489D01*
X115495Y954406D01*
X115787Y954197D01*
X115870Y953947D01*
X115828Y953697D01*
X115662Y953489D01*
X114828Y953072D01*
X114453Y952781D01*
X114203Y952364D01*
X114120Y951989D01*
X115870D01*
G01X117387Y952281D02*
X117678Y952072D01*
X118012Y951989D01*
X118345Y952072D01*
X118637Y952322D01*
X118845Y952697D01*
X118928Y953072D01*
Y953531D01*
X118845Y953906D01*
X118637Y954239D01*
X118387Y954406D01*
X118095Y954489D01*
X117762Y954406D01*
X117512Y954239D01*
X117345Y953989D01*
X117262Y953656D01*
X117345Y953364D01*
X117553Y953072D01*
X117803Y952906D01*
X118095Y952864D01*
X118428Y952947D01*
X118678Y953156D01*
X118928Y953531D01*
G01X120278Y952364D02*
X120528Y952156D01*
X120820Y952031D01*
X121195Y951989D01*
X121570Y952072D01*
X121862Y952239D01*
X122070Y952531D01*
X122112Y952864D01*
X122028Y953197D01*
X121820Y953406D01*
X121528Y953572D01*
X121237Y953614D01*
X120945Y953572D01*
X120570Y953406D01*
X120695Y954489D01*
X121820D01*
G01X109312Y932281D02*
X109062Y932406D01*
X108770Y932489D01*
X108437D01*
X108062Y932364D01*
X107770Y932156D01*
X107562Y931906D01*
X107395Y931489D01*
X107353Y931114D01*
X107437Y930739D01*
X107562Y930489D01*
X107812Y930239D01*
X108103Y930072D01*
X108395Y929989D01*
X108687D01*
X108978Y930072D01*
X109228Y930197D01*
X109437Y930364D01*
G01X110703Y932072D02*
X110953Y932322D01*
X111245Y932447D01*
X111578Y932489D01*
X111995Y932406D01*
X112287Y932197D01*
X112370Y931947D01*
X112328Y931697D01*
X112162Y931489D01*
X111328Y931072D01*
X110953Y930781D01*
X110703Y930364D01*
X110620Y929989D01*
X112370D01*
G01X113887Y930281D02*
X114178Y930072D01*
X114512Y929989D01*
X114845Y930072D01*
X115137Y930322D01*
X115345Y930697D01*
X115428Y931072D01*
Y931531D01*
X115345Y931906D01*
X115137Y932239D01*
X114887Y932406D01*
X114595Y932489D01*
X114262Y932406D01*
X114012Y932239D01*
X113845Y931989D01*
X113762Y931656D01*
X113845Y931364D01*
X114053Y931072D01*
X114303Y930906D01*
X114595Y930864D01*
X114928Y930947D01*
X115178Y931156D01*
X115428Y931531D01*
G01X116903Y931031D02*
X117195Y931322D01*
X117445Y931489D01*
X117778Y931572D01*
X118070Y931489D01*
X118278Y931322D01*
X118445Y931072D01*
X118487Y930781D01*
X118445Y930531D01*
X118278Y930281D01*
X118028Y930072D01*
X117737Y929989D01*
X117403Y930072D01*
X117112Y930322D01*
X116945Y930697D01*
X116903Y931114D01*
X116987Y931656D01*
X117112Y931947D01*
X117320Y932239D01*
X117612Y932447D01*
X117903Y932489D01*
X118195Y932406D01*
X118403Y932197D01*
G01X109312Y928781D02*
X109062Y928906D01*
X108770Y928989D01*
X108437D01*
X108062Y928864D01*
X107770Y928656D01*
X107562Y928406D01*
X107395Y927989D01*
X107353Y927614D01*
X107437Y927239D01*
X107562Y926989D01*
X107812Y926739D01*
X108103Y926572D01*
X108395Y926489D01*
X108687D01*
X108978Y926572D01*
X109228Y926697D01*
X109437Y926864D01*
G01X110703Y928572D02*
X110953Y928822D01*
X111245Y928947D01*
X111578Y928989D01*
X111995Y928906D01*
X112287Y928697D01*
X112370Y928447D01*
X112328Y928197D01*
X112162Y927989D01*
X111328Y927572D01*
X110953Y927281D01*
X110703Y926864D01*
X110620Y926489D01*
X112370D01*
G01X113887Y926781D02*
X114178Y926572D01*
X114512Y926489D01*
X114845Y926572D01*
X115137Y926822D01*
X115345Y927197D01*
X115428Y927572D01*
Y928031D01*
X115345Y928406D01*
X115137Y928739D01*
X114887Y928906D01*
X114595Y928989D01*
X114262Y928906D01*
X114012Y928739D01*
X113845Y928489D01*
X113762Y928156D01*
X113845Y927864D01*
X114053Y927572D01*
X114303Y927406D01*
X114595Y927364D01*
X114928Y927447D01*
X115178Y927656D01*
X115428Y928031D01*
G01X117612Y926489D02*
X117695Y927031D01*
X117820Y927489D01*
X117987Y927906D01*
X118195Y928364D01*
X118528Y928989D01*
X116862D01*
G01X148208Y925267D02*
X148083Y925017D01*
X148000Y924725D01*
Y924392D01*
X148125Y924017D01*
X148333Y923725D01*
X148583Y923517D01*
X149000Y923350D01*
X149375Y923308D01*
X149750Y923392D01*
X150000Y923517D01*
X150250Y923767D01*
X150417Y924058D01*
X150500Y924350D01*
Y924642D01*
X150417Y924933D01*
X150292Y925183D01*
X150125Y925392D01*
G01X150000Y926533D02*
X150292Y926783D01*
X150458Y927117D01*
X150500Y927492D01*
X150458Y927825D01*
X150250Y928158D01*
X150000Y928367D01*
X149750Y928408D01*
X149458Y928325D01*
X149250Y928033D01*
X149167Y927742D01*
Y927367D01*
G01Y927742D02*
X149042Y927992D01*
X148833Y928200D01*
X148583Y928283D01*
X148333Y928200D01*
X148125Y927992D01*
X148000Y927617D01*
X148042Y927242D01*
X148208Y926867D01*
G01X148000Y930550D02*
X148083Y930217D01*
X148292Y929967D01*
X148542Y929800D01*
X148875Y929675D01*
X149250Y929633D01*
X149625Y929675D01*
X149958Y929800D01*
X150208Y929967D01*
X150417Y930217D01*
X150500Y930550D01*
X150417Y930883D01*
X150208Y931133D01*
X149958Y931300D01*
X149625Y931425D01*
X149250Y931467D01*
X148875Y931425D01*
X148542Y931300D01*
X148292Y931133D01*
X148083Y930883D01*
X148000Y930550D01*
G01X150000Y932733D02*
X150292Y932983D01*
X150458Y933317D01*
X150500Y933692D01*
X150458Y934025D01*
X150250Y934358D01*
X150000Y934567D01*
X149750Y934608D01*
X149458Y934525D01*
X149250Y934233D01*
X149167Y933942D01*
Y933567D01*
G01Y933942D02*
X149042Y934192D01*
X148833Y934400D01*
X148583Y934483D01*
X148333Y934400D01*
X148125Y934192D01*
X148000Y933817D01*
X148042Y933442D01*
X148208Y933067D01*
G01X173023Y976871D02*
Y969271D01*
X161623D01*
Y976871D01*
X173023D01*
G01X147516Y905550D02*
Y908050D01*
X148557D01*
X148891Y907925D01*
X149099Y907758D01*
X149182Y907425D01*
X149099Y907092D01*
X148849Y906883D01*
X148557Y906758D01*
X147516D01*
G01X148557D02*
X149182Y905550D01*
G01X150657Y907633D02*
X150907Y907883D01*
X151199Y908008D01*
X151532Y908050D01*
X151949Y907967D01*
X152241Y907758D01*
X152324Y907508D01*
X152282Y907258D01*
X152116Y907050D01*
X151282Y906633D01*
X150907Y906342D01*
X150657Y905925D01*
X150574Y905550D01*
X152324D01*
G01X154466D02*
X154549Y906092D01*
X154674Y906550D01*
X154841Y906967D01*
X155049Y907425D01*
X155382Y908050D01*
X153716D01*
G01X156732Y906050D02*
X156982Y905758D01*
X157316Y905592D01*
X157691Y905550D01*
X158024Y905592D01*
X158357Y905800D01*
X158566Y906050D01*
X158607Y906300D01*
X158524Y906592D01*
X158232Y906800D01*
X157941Y906883D01*
X157566D01*
G01X157941D02*
X158191Y907008D01*
X158399Y907217D01*
X158482Y907467D01*
X158399Y907717D01*
X158191Y907925D01*
X157816Y908050D01*
X157441Y908008D01*
X157066Y907842D01*
G01X160499Y900113D02*
X186499D01*
G01X160499Y913113D02*
Y900113D01*
G01X186499Y913113D02*
X160499D01*
G01X164287Y959310D02*
Y961810D01*
X165328D01*
X165662Y961685D01*
X165870Y961518D01*
X165953Y961185D01*
X165870Y960852D01*
X165620Y960643D01*
X165328Y960518D01*
X164287D01*
G01X165328D02*
X165953Y959310D01*
G01X168220D02*
Y961810D01*
X167720Y961310D01*
G01Y959310D02*
X168720D01*
G01X170612Y959602D02*
X170903Y959393D01*
X171237Y959310D01*
X171570Y959393D01*
X171862Y959643D01*
X172070Y960018D01*
X172153Y960393D01*
Y960852D01*
X172070Y961227D01*
X171862Y961560D01*
X171612Y961727D01*
X171320Y961810D01*
X170987Y961727D01*
X170737Y961560D01*
X170570Y961310D01*
X170487Y960977D01*
X170570Y960685D01*
X170778Y960393D01*
X171028Y960227D01*
X171320Y960185D01*
X171653Y960268D01*
X171903Y960477D01*
X172153Y960852D01*
G01X174420Y959310D02*
X174712Y959352D01*
X175045Y959477D01*
X175253Y959685D01*
X175337Y959977D01*
X175253Y960268D01*
X175003Y960518D01*
X174628Y960643D01*
X174212D01*
X173962Y960727D01*
X173753Y960935D01*
X173670Y961227D01*
X173795Y961518D01*
X174087Y961727D01*
X174420Y961810D01*
X174753Y961727D01*
X175045Y961518D01*
X175170Y961227D01*
X175087Y960935D01*
X174878Y960727D01*
X174628Y960643D01*
X174212D01*
X173837Y960518D01*
X173587Y960268D01*
X173503Y959977D01*
X173587Y959685D01*
X173795Y959477D01*
X174128Y959352D01*
X174420Y959310D01*
G01X174549Y978550D02*
Y974550D01*
X181949D01*
G01X138516Y975050D02*
Y977550D01*
X139557D01*
X139891Y977425D01*
X140099Y977258D01*
X140182Y976925D01*
X140099Y976592D01*
X139849Y976383D01*
X139557Y976258D01*
X138516D01*
G01X139557D02*
X140182Y975050D01*
G01X142449D02*
Y977550D01*
X141949Y977050D01*
G01Y975050D02*
X142949D01*
G01X144841Y975342D02*
X145132Y975133D01*
X145466Y975050D01*
X145799Y975133D01*
X146091Y975383D01*
X146299Y975758D01*
X146382Y976133D01*
Y976592D01*
X146299Y976967D01*
X146091Y977300D01*
X145841Y977467D01*
X145549Y977550D01*
X145216Y977467D01*
X144966Y977300D01*
X144799Y977050D01*
X144716Y976717D01*
X144799Y976425D01*
X145007Y976133D01*
X145257Y975967D01*
X145549Y975925D01*
X145882Y976008D01*
X146132Y976217D01*
X146382Y976592D01*
G01X147941Y975342D02*
X148232Y975133D01*
X148566Y975050D01*
X148899Y975133D01*
X149191Y975383D01*
X149399Y975758D01*
X149482Y976133D01*
Y976592D01*
X149399Y976967D01*
X149191Y977300D01*
X148941Y977467D01*
X148649Y977550D01*
X148316Y977467D01*
X148066Y977300D01*
X147899Y977050D01*
X147816Y976717D01*
X147899Y976425D01*
X148107Y976133D01*
X148357Y975967D01*
X148649Y975925D01*
X148982Y976008D01*
X149232Y976217D01*
X149482Y976592D01*
G01X152799Y977550D02*
Y973550D01*
X160199D01*
G01X164287Y955310D02*
Y957810D01*
X165328D01*
X165662Y957685D01*
X165870Y957518D01*
X165953Y957185D01*
X165870Y956852D01*
X165620Y956643D01*
X165328Y956518D01*
X164287D01*
G01X165328D02*
X165953Y955310D01*
G01X167428Y957393D02*
X167678Y957643D01*
X167970Y957768D01*
X168303Y957810D01*
X168720Y957727D01*
X169012Y957518D01*
X169095Y957268D01*
X169053Y957018D01*
X168887Y956810D01*
X168053Y956393D01*
X167678Y956102D01*
X167428Y955685D01*
X167345Y955310D01*
X169095D01*
G01X171320Y957810D02*
X170987Y957727D01*
X170737Y957518D01*
X170570Y957268D01*
X170445Y956935D01*
X170403Y956560D01*
X170445Y956185D01*
X170570Y955852D01*
X170737Y955602D01*
X170987Y955393D01*
X171320Y955310D01*
X171653Y955393D01*
X171903Y955602D01*
X172070Y955852D01*
X172195Y956185D01*
X172237Y956560D01*
X172195Y956935D01*
X172070Y957268D01*
X171903Y957518D01*
X171653Y957727D01*
X171320Y957810D01*
G01X174420D02*
X174087Y957727D01*
X173837Y957518D01*
X173670Y957268D01*
X173545Y956935D01*
X173503Y956560D01*
X173545Y956185D01*
X173670Y955852D01*
X173837Y955602D01*
X174087Y955393D01*
X174420Y955310D01*
X174753Y955393D01*
X175003Y955602D01*
X175170Y955852D01*
X175295Y956185D01*
X175337Y956560D01*
X175295Y956935D01*
X175170Y957268D01*
X175003Y957518D01*
X174753Y957727D01*
X174420Y957810D01*
G01X174549Y974550D02*
Y970550D01*
X181949D01*
G01X138516Y971050D02*
Y973550D01*
X139557D01*
X139891Y973425D01*
X140099Y973258D01*
X140182Y972925D01*
X140099Y972592D01*
X139849Y972383D01*
X139557Y972258D01*
X138516D01*
G01X139557D02*
X140182Y971050D01*
G01X141657Y973133D02*
X141907Y973383D01*
X142199Y973508D01*
X142532Y973550D01*
X142949Y973467D01*
X143241Y973258D01*
X143324Y973008D01*
X143282Y972758D01*
X143116Y972550D01*
X142282Y972133D01*
X141907Y971842D01*
X141657Y971425D01*
X141574Y971050D01*
X143324D01*
G01X145549Y973550D02*
X145216Y973467D01*
X144966Y973258D01*
X144799Y973008D01*
X144674Y972675D01*
X144632Y972300D01*
X144674Y971925D01*
X144799Y971592D01*
X144966Y971342D01*
X145216Y971133D01*
X145549Y971050D01*
X145882Y971133D01*
X146132Y971342D01*
X146299Y971592D01*
X146424Y971925D01*
X146466Y972300D01*
X146424Y972675D01*
X146299Y973008D01*
X146132Y973258D01*
X145882Y973467D01*
X145549Y973550D01*
G01X148649Y971050D02*
Y973550D01*
X148149Y973050D01*
G01Y971050D02*
X149149D01*
G01X152799Y973550D02*
Y969550D01*
X160199D01*
G01X164537Y950310D02*
Y952810D01*
X165578D01*
X165912Y952685D01*
X166120Y952518D01*
X166203Y952185D01*
X166120Y951852D01*
X165870Y951643D01*
X165578Y951518D01*
X164537D01*
G01X165578D02*
X166203Y950310D01*
G01X167678Y952393D02*
X167928Y952643D01*
X168220Y952768D01*
X168553Y952810D01*
X168970Y952727D01*
X169262Y952518D01*
X169345Y952268D01*
X169303Y952018D01*
X169137Y951810D01*
X168303Y951393D01*
X167928Y951102D01*
X167678Y950685D01*
X167595Y950310D01*
X169345D01*
G01X171570Y952810D02*
X171237Y952727D01*
X170987Y952518D01*
X170820Y952268D01*
X170695Y951935D01*
X170653Y951560D01*
X170695Y951185D01*
X170820Y950852D01*
X170987Y950602D01*
X171237Y950393D01*
X171570Y950310D01*
X171903Y950393D01*
X172153Y950602D01*
X172320Y950852D01*
X172445Y951185D01*
X172487Y951560D01*
X172445Y951935D01*
X172320Y952268D01*
X172153Y952518D01*
X171903Y952727D01*
X171570Y952810D01*
G01X173878Y952393D02*
X174128Y952643D01*
X174420Y952768D01*
X174753Y952810D01*
X175170Y952727D01*
X175462Y952518D01*
X175545Y952268D01*
X175503Y952018D01*
X175337Y951810D01*
X174503Y951393D01*
X174128Y951102D01*
X173878Y950685D01*
X173795Y950310D01*
X175545D01*
G01X174799Y969550D02*
Y965550D01*
X182199D01*
G01X158500Y923517D02*
X156000D01*
Y924558D01*
X156125Y924892D01*
X156292Y925100D01*
X156625Y925183D01*
X156958Y925100D01*
X157167Y924850D01*
X157292Y924558D01*
Y923517D01*
G01Y924558D02*
X158500Y925183D01*
G01X156417Y926658D02*
X156167Y926908D01*
X156042Y927200D01*
X156000Y927533D01*
X156083Y927950D01*
X156292Y928242D01*
X156542Y928325D01*
X156792Y928283D01*
X157000Y928117D01*
X157417Y927283D01*
X157708Y926908D01*
X158125Y926658D01*
X158500Y926575D01*
Y928325D01*
G01Y930467D02*
X157958Y930550D01*
X157500Y930675D01*
X157083Y930842D01*
X156625Y931050D01*
X156000Y931383D01*
Y929717D01*
G01X158500Y934150D02*
X156000D01*
X157792Y932608D01*
Y934692D01*
G01X176699Y914113D02*
Y918113D01*
X169299D01*
G01X112767Y970000D02*
Y972500D01*
X113808D01*
X114142Y972375D01*
X114350Y972208D01*
X114433Y971875D01*
X114350Y971542D01*
X114100Y971333D01*
X113808Y971208D01*
X112767D01*
G01X113808D02*
X114433Y970000D01*
G01X115783Y970500D02*
X116033Y970208D01*
X116367Y970042D01*
X116742Y970000D01*
X117075Y970042D01*
X117408Y970250D01*
X117617Y970500D01*
X117658Y970750D01*
X117575Y971042D01*
X117283Y971250D01*
X116992Y971333D01*
X116617D01*
G01X116992D02*
X117242Y971458D01*
X117450Y971667D01*
X117533Y971917D01*
X117450Y972167D01*
X117242Y972375D01*
X116867Y972500D01*
X116492Y972458D01*
X116117Y972292D01*
G01X119008Y971042D02*
X119300Y971333D01*
X119550Y971500D01*
X119883Y971583D01*
X120175Y971500D01*
X120383Y971333D01*
X120550Y971083D01*
X120592Y970792D01*
X120550Y970542D01*
X120383Y970292D01*
X120133Y970083D01*
X119842Y970000D01*
X119508Y970083D01*
X119217Y970333D01*
X119050Y970708D01*
X119008Y971125D01*
X119092Y971667D01*
X119217Y971958D01*
X119425Y972250D01*
X119717Y972458D01*
X120008Y972500D01*
X120300Y972417D01*
X120508Y972208D01*
G01X122817Y970000D02*
X122900Y970542D01*
X123025Y971000D01*
X123192Y971417D01*
X123400Y971875D01*
X123733Y972500D01*
X122067D01*
G01X110950Y970000D02*
Y974000D01*
X103550D01*
G01X112716Y965850D02*
Y968350D01*
X113757D01*
X114091Y968225D01*
X114299Y968058D01*
X114382Y967725D01*
X114299Y967392D01*
X114049Y967183D01*
X113757Y967058D01*
X112716D01*
G01X113757D02*
X114382Y965850D01*
G01X115732Y966350D02*
X115982Y966058D01*
X116316Y965892D01*
X116691Y965850D01*
X117024Y965892D01*
X117357Y966100D01*
X117566Y966350D01*
X117607Y966600D01*
X117524Y966892D01*
X117232Y967100D01*
X116941Y967183D01*
X116566D01*
G01X116941D02*
X117191Y967308D01*
X117399Y967517D01*
X117482Y967767D01*
X117399Y968017D01*
X117191Y968225D01*
X116816Y968350D01*
X116441Y968308D01*
X116066Y968142D01*
G01X118957Y966892D02*
X119249Y967183D01*
X119499Y967350D01*
X119832Y967433D01*
X120124Y967350D01*
X120332Y967183D01*
X120499Y966933D01*
X120541Y966642D01*
X120499Y966392D01*
X120332Y966142D01*
X120082Y965933D01*
X119791Y965850D01*
X119457Y965933D01*
X119166Y966183D01*
X118999Y966558D01*
X118957Y966975D01*
X119041Y967517D01*
X119166Y967808D01*
X119374Y968100D01*
X119666Y968308D01*
X119957Y968350D01*
X120249Y968267D01*
X120457Y968058D01*
G01X122849Y965850D02*
X123141Y965892D01*
X123474Y966017D01*
X123682Y966225D01*
X123766Y966517D01*
X123682Y966808D01*
X123432Y967058D01*
X123057Y967183D01*
X122641D01*
X122391Y967267D01*
X122182Y967475D01*
X122099Y967767D01*
X122224Y968058D01*
X122516Y968267D01*
X122849Y968350D01*
X123182Y968267D01*
X123474Y968058D01*
X123599Y967767D01*
X123516Y967475D01*
X123307Y967267D01*
X123057Y967183D01*
X122641D01*
X122266Y967058D01*
X122016Y966808D01*
X121932Y966517D01*
X122016Y966225D01*
X122224Y966017D01*
X122557Y965892D01*
X122849Y965850D01*
G01X110899D02*
Y969850D01*
X103499D01*
G01X162500Y923517D02*
X160000D01*
Y924558D01*
X160125Y924892D01*
X160292Y925100D01*
X160625Y925183D01*
X160958Y925100D01*
X161167Y924850D01*
X161292Y924558D01*
Y923517D01*
G01Y924558D02*
X162500Y925183D01*
G01Y927950D02*
X160000D01*
X161792Y926408D01*
Y928492D01*
G01X160000Y930550D02*
X160083Y930217D01*
X160292Y929967D01*
X160542Y929800D01*
X160875Y929675D01*
X161250Y929633D01*
X161625Y929675D01*
X161958Y929800D01*
X162208Y929967D01*
X162417Y930217D01*
X162500Y930550D01*
X162417Y930883D01*
X162208Y931133D01*
X161958Y931300D01*
X161625Y931425D01*
X161250Y931467D01*
X160875Y931425D01*
X160542Y931300D01*
X160292Y931133D01*
X160083Y930883D01*
X160000Y930550D01*
G01Y933650D02*
X160083Y933317D01*
X160292Y933067D01*
X160542Y932900D01*
X160875Y932775D01*
X161250Y932733D01*
X161625Y932775D01*
X161958Y932900D01*
X162208Y933067D01*
X162417Y933317D01*
X162500Y933650D01*
X162417Y933983D01*
X162208Y934233D01*
X161958Y934400D01*
X161625Y934525D01*
X161250Y934567D01*
X160875Y934525D01*
X160542Y934400D01*
X160292Y934233D01*
X160083Y933983D01*
X160000Y933650D01*
G01X169300Y924700D02*
Y920700D01*
X176700D01*
G01X154500Y923517D02*
X152000D01*
Y924558D01*
X152125Y924892D01*
X152292Y925100D01*
X152625Y925183D01*
X152958Y925100D01*
X153167Y924850D01*
X153292Y924558D01*
Y923517D01*
G01Y924558D02*
X154500Y925183D01*
G01X152417Y926658D02*
X152167Y926908D01*
X152042Y927200D01*
X152000Y927533D01*
X152083Y927950D01*
X152292Y928242D01*
X152542Y928325D01*
X152792Y928283D01*
X153000Y928117D01*
X153417Y927283D01*
X153708Y926908D01*
X154125Y926658D01*
X154500Y926575D01*
Y928325D01*
G01Y930467D02*
X153958Y930550D01*
X153500Y930675D01*
X153083Y930842D01*
X152625Y931050D01*
X152000Y931383D01*
Y929717D01*
G01X154208Y932942D02*
X154417Y933233D01*
X154500Y933567D01*
X154417Y933900D01*
X154167Y934192D01*
X153792Y934400D01*
X153417Y934483D01*
X152958D01*
X152583Y934400D01*
X152250Y934192D01*
X152083Y933942D01*
X152000Y933650D01*
X152083Y933317D01*
X152250Y933067D01*
X152500Y932900D01*
X152833Y932817D01*
X153125Y932900D01*
X153417Y933108D01*
X153583Y933358D01*
X153625Y933650D01*
X153542Y933983D01*
X153333Y934233D01*
X152958Y934483D01*
G01X165499Y899413D02*
X173499D01*
G01X176000Y926900D02*
X175958Y926567D01*
X175792Y926275D01*
X175542Y926025D01*
X175250Y925858D01*
X174917Y925775D01*
X174583D01*
X174250Y925858D01*
X173958Y926025D01*
X173708Y926275D01*
X173542Y926567D01*
X173500Y926900D01*
X173542Y927233D01*
X173708Y927525D01*
X173958Y927775D01*
X174250Y927942D01*
X174583Y928025D01*
X174917D01*
X175250Y927942D01*
X175542Y927775D01*
X175792Y927525D01*
X175958Y927233D01*
X176000Y926900D01*
G01X175333Y927233D02*
X176000Y927733D01*
G01Y929917D02*
X175458Y930000D01*
X175000Y930125D01*
X174583Y930292D01*
X174125Y930500D01*
X173500Y930833D01*
Y929167D01*
G01X176000Y933100D02*
X173500D01*
X174000Y932600D01*
G01X176000D02*
Y933600D01*
G01X177400Y929000D02*
Y915000D01*
G01X190400Y929000D02*
X177400D01*
G01Y915000D02*
X190400D01*
G01X103267Y900925D02*
X103475Y901258D01*
X103600Y901633D01*
Y901967D01*
X103475Y902300D01*
X103267Y902550D01*
X102975Y902675D01*
X102683Y902592D01*
X102433Y902383D01*
X102267Y902008D01*
X102183Y901508D01*
X102017Y901217D01*
X101725Y901092D01*
X101433Y901175D01*
X101225Y901383D01*
X101100Y901675D01*
Y901967D01*
X101183Y902258D01*
X101392Y902508D01*
G01X103600Y903983D02*
X101100D01*
G01Y905567D02*
X102642Y903983D01*
G01X103600Y905817D02*
X101933Y904692D01*
G01X101100Y908000D02*
X103600D01*
G01X101100Y907042D02*
Y908958D01*
G01X103600Y911100D02*
X101100D01*
X101600Y910600D01*
G01X103600D02*
Y911600D01*
G01X103100Y913283D02*
X103392Y913533D01*
X103558Y913867D01*
X103600Y914242D01*
X103558Y914575D01*
X103350Y914908D01*
X103100Y915117D01*
X102850Y915158D01*
X102558Y915075D01*
X102350Y914783D01*
X102267Y914492D01*
Y914117D01*
G01Y914492D02*
X102142Y914742D01*
X101933Y914950D01*
X101683Y915033D01*
X101433Y914950D01*
X101225Y914742D01*
X101100Y914367D01*
X101142Y913992D01*
X101308Y913617D01*
G01X126466Y1027842D02*
X126216Y1027967D01*
X125924Y1028050D01*
X125591D01*
X125216Y1027925D01*
X124924Y1027717D01*
X124716Y1027467D01*
X124549Y1027050D01*
X124507Y1026675D01*
X124591Y1026300D01*
X124716Y1026050D01*
X124966Y1025800D01*
X125257Y1025633D01*
X125549Y1025550D01*
X125841D01*
X126132Y1025633D01*
X126382Y1025758D01*
X126591Y1025925D01*
G01X127857Y1027633D02*
X128107Y1027883D01*
X128399Y1028008D01*
X128732Y1028050D01*
X129149Y1027967D01*
X129441Y1027758D01*
X129524Y1027508D01*
X129482Y1027258D01*
X129316Y1027050D01*
X128482Y1026633D01*
X128107Y1026342D01*
X127857Y1025925D01*
X127774Y1025550D01*
X129524D01*
G01X131749D02*
Y1028050D01*
X131249Y1027550D01*
G01Y1025550D02*
X132249D01*
G01X135349D02*
Y1028050D01*
X133807Y1026258D01*
X135891D01*
G01X126466Y1031342D02*
X126216Y1031467D01*
X125924Y1031550D01*
X125591D01*
X125216Y1031425D01*
X124924Y1031217D01*
X124716Y1030967D01*
X124549Y1030550D01*
X124507Y1030175D01*
X124591Y1029800D01*
X124716Y1029550D01*
X124966Y1029300D01*
X125257Y1029133D01*
X125549Y1029050D01*
X125841D01*
X126132Y1029133D01*
X126382Y1029258D01*
X126591Y1029425D01*
G01X127857Y1031133D02*
X128107Y1031383D01*
X128399Y1031508D01*
X128732Y1031550D01*
X129149Y1031467D01*
X129441Y1031258D01*
X129524Y1031008D01*
X129482Y1030758D01*
X129316Y1030550D01*
X128482Y1030133D01*
X128107Y1029842D01*
X127857Y1029425D01*
X127774Y1029050D01*
X129524D01*
G01X131749D02*
Y1031550D01*
X131249Y1031050D01*
G01Y1029050D02*
X132249D01*
G01X133932Y1029425D02*
X134182Y1029217D01*
X134474Y1029092D01*
X134849Y1029050D01*
X135224Y1029133D01*
X135516Y1029300D01*
X135724Y1029592D01*
X135766Y1029925D01*
X135682Y1030258D01*
X135474Y1030467D01*
X135182Y1030633D01*
X134891Y1030675D01*
X134599Y1030633D01*
X134224Y1030467D01*
X134349Y1031550D01*
X135474D01*
G01X128266Y1053342D02*
X128016Y1053467D01*
X127724Y1053550D01*
X127391D01*
X127016Y1053425D01*
X126724Y1053217D01*
X126516Y1052967D01*
X126349Y1052550D01*
X126307Y1052175D01*
X126391Y1051800D01*
X126516Y1051550D01*
X126766Y1051300D01*
X127057Y1051133D01*
X127349Y1051050D01*
X127641D01*
X127932Y1051133D01*
X128182Y1051258D01*
X128391Y1051425D01*
G01X129657Y1053133D02*
X129907Y1053383D01*
X130199Y1053508D01*
X130532Y1053550D01*
X130949Y1053467D01*
X131241Y1053258D01*
X131324Y1053008D01*
X131282Y1052758D01*
X131116Y1052550D01*
X130282Y1052133D01*
X129907Y1051842D01*
X129657Y1051425D01*
X129574Y1051050D01*
X131324D01*
G01X133549D02*
Y1053550D01*
X133049Y1053050D01*
G01Y1051050D02*
X134049D01*
G01X135857Y1052092D02*
X136149Y1052383D01*
X136399Y1052550D01*
X136732Y1052633D01*
X137024Y1052550D01*
X137232Y1052383D01*
X137399Y1052133D01*
X137441Y1051842D01*
X137399Y1051592D01*
X137232Y1051342D01*
X136982Y1051133D01*
X136691Y1051050D01*
X136357Y1051133D01*
X136066Y1051383D01*
X135899Y1051758D01*
X135857Y1052175D01*
X135941Y1052717D01*
X136066Y1053008D01*
X136274Y1053300D01*
X136566Y1053508D01*
X136857Y1053550D01*
X137149Y1053467D01*
X137357Y1053258D01*
G01X128266Y1056842D02*
X128016Y1056967D01*
X127724Y1057050D01*
X127391D01*
X127016Y1056925D01*
X126724Y1056717D01*
X126516Y1056467D01*
X126349Y1056050D01*
X126307Y1055675D01*
X126391Y1055300D01*
X126516Y1055050D01*
X126766Y1054800D01*
X127057Y1054633D01*
X127349Y1054550D01*
X127641D01*
X127932Y1054633D01*
X128182Y1054758D01*
X128391Y1054925D01*
G01X129657Y1056633D02*
X129907Y1056883D01*
X130199Y1057008D01*
X130532Y1057050D01*
X130949Y1056967D01*
X131241Y1056758D01*
X131324Y1056508D01*
X131282Y1056258D01*
X131116Y1056050D01*
X130282Y1055633D01*
X129907Y1055342D01*
X129657Y1054925D01*
X129574Y1054550D01*
X131324D01*
G01X133549D02*
Y1057050D01*
X133049Y1056550D01*
G01Y1054550D02*
X134049D01*
G01X136566D02*
X136649Y1055092D01*
X136774Y1055550D01*
X136941Y1055967D01*
X137149Y1056425D01*
X137482Y1057050D01*
X135816D01*
G01X161517Y981563D02*
Y979063D01*
X163183D01*
G01X166283D02*
X164617D01*
Y981563D01*
X166283D01*
G01X165617Y980355D02*
X164617D01*
G01X167633Y979063D02*
Y981563D01*
X168467D01*
X168800Y981438D01*
X169050Y981271D01*
X169258Y981021D01*
X169425Y980730D01*
X169467Y980313D01*
X169425Y979896D01*
X169258Y979605D01*
X169050Y979355D01*
X168800Y979188D01*
X168467Y979063D01*
X167633D01*
G01X171650D02*
X171942Y979105D01*
X172275Y979230D01*
X172483Y979438D01*
X172567Y979730D01*
X172483Y980021D01*
X172233Y980271D01*
X171858Y980396D01*
X171442D01*
X171192Y980480D01*
X170983Y980688D01*
X170900Y980980D01*
X171025Y981271D01*
X171317Y981480D01*
X171650Y981563D01*
X171983Y981480D01*
X172275Y981271D01*
X172400Y980980D01*
X172317Y980688D01*
X172108Y980480D01*
X171858Y980396D01*
X171442D01*
X171067Y980271D01*
X170817Y980021D01*
X170733Y979730D01*
X170817Y979438D01*
X171025Y979230D01*
X171358Y979105D01*
X171650Y979063D01*
G01X144623Y996841D02*
Y1158041D01*
X158223D01*
Y1170991D01*
X176423D01*
Y1158041D01*
X205323D01*
Y1147691D01*
X198623D01*
Y1007191D01*
X205323D01*
Y996841D01*
X176423D01*
Y983891D01*
X158223D01*
Y996841D01*
X144623D01*
G01X98100Y1116500D02*
Y1109500D01*
G01X128767Y1112292D02*
X128517Y1112417D01*
X128225Y1112500D01*
X127892D01*
X127517Y1112375D01*
X127225Y1112167D01*
X127017Y1111917D01*
X126850Y1111500D01*
X126808Y1111125D01*
X126892Y1110750D01*
X127017Y1110500D01*
X127267Y1110250D01*
X127558Y1110083D01*
X127850Y1110000D01*
X128142D01*
X128433Y1110083D01*
X128683Y1110208D01*
X128892Y1110375D01*
G01X130033Y1110500D02*
X130283Y1110208D01*
X130617Y1110042D01*
X130992Y1110000D01*
X131325Y1110042D01*
X131658Y1110250D01*
X131867Y1110500D01*
X131908Y1110750D01*
X131825Y1111042D01*
X131533Y1111250D01*
X131242Y1111333D01*
X130867D01*
G01X131242D02*
X131492Y1111458D01*
X131700Y1111667D01*
X131783Y1111917D01*
X131700Y1112167D01*
X131492Y1112375D01*
X131117Y1112500D01*
X130742Y1112458D01*
X130367Y1112292D01*
G01X133967Y1110000D02*
X134050Y1110542D01*
X134175Y1111000D01*
X134342Y1111417D01*
X134550Y1111875D01*
X134883Y1112500D01*
X133217D01*
G01X137150Y1110000D02*
Y1112500D01*
X136650Y1112000D01*
G01Y1110000D02*
X137650D01*
G01X136208Y1134267D02*
X136083Y1134017D01*
X136000Y1133725D01*
Y1133392D01*
X136125Y1133017D01*
X136333Y1132725D01*
X136583Y1132517D01*
X137000Y1132350D01*
X137375Y1132308D01*
X137750Y1132392D01*
X138000Y1132517D01*
X138250Y1132767D01*
X138417Y1133058D01*
X138500Y1133350D01*
Y1133642D01*
X138417Y1133933D01*
X138292Y1134183D01*
X138125Y1134392D01*
G01X138000Y1135533D02*
X138292Y1135783D01*
X138458Y1136117D01*
X138500Y1136492D01*
X138458Y1136825D01*
X138250Y1137158D01*
X138000Y1137367D01*
X137750Y1137408D01*
X137458Y1137325D01*
X137250Y1137033D01*
X137167Y1136742D01*
Y1136367D01*
G01Y1136742D02*
X137042Y1136992D01*
X136833Y1137200D01*
X136583Y1137283D01*
X136333Y1137200D01*
X136125Y1136992D01*
X136000Y1136617D01*
X136042Y1136242D01*
X136208Y1135867D01*
G01X138500Y1139550D02*
X138458Y1139842D01*
X138333Y1140175D01*
X138125Y1140383D01*
X137833Y1140467D01*
X137542Y1140383D01*
X137292Y1140133D01*
X137167Y1139758D01*
Y1139342D01*
X137083Y1139092D01*
X136875Y1138883D01*
X136583Y1138800D01*
X136292Y1138925D01*
X136083Y1139217D01*
X136000Y1139550D01*
X136083Y1139883D01*
X136292Y1140175D01*
X136583Y1140300D01*
X136875Y1140217D01*
X137083Y1140008D01*
X137167Y1139758D01*
Y1139342D01*
X137292Y1138967D01*
X137542Y1138717D01*
X137833Y1138633D01*
X138125Y1138717D01*
X138333Y1138925D01*
X138458Y1139258D01*
X138500Y1139550D01*
G01X137458Y1141858D02*
X137167Y1142150D01*
X137000Y1142400D01*
X136917Y1142733D01*
X137000Y1143025D01*
X137167Y1143233D01*
X137417Y1143400D01*
X137708Y1143442D01*
X137958Y1143400D01*
X138208Y1143233D01*
X138417Y1142983D01*
X138500Y1142692D01*
X138417Y1142358D01*
X138167Y1142067D01*
X137792Y1141900D01*
X137375Y1141858D01*
X136833Y1141942D01*
X136542Y1142067D01*
X136250Y1142275D01*
X136042Y1142567D01*
X136000Y1142858D01*
X136083Y1143150D01*
X136292Y1143358D01*
G01X117317Y1071792D02*
X117067Y1071917D01*
X116775Y1072000D01*
X116442D01*
X116067Y1071875D01*
X115775Y1071667D01*
X115567Y1071417D01*
X115400Y1071000D01*
X115358Y1070625D01*
X115442Y1070250D01*
X115567Y1070000D01*
X115817Y1069750D01*
X116108Y1069583D01*
X116400Y1069500D01*
X116692D01*
X116983Y1069583D01*
X117233Y1069708D01*
X117442Y1069875D01*
G01X118583Y1070000D02*
X118833Y1069708D01*
X119167Y1069542D01*
X119542Y1069500D01*
X119875Y1069542D01*
X120208Y1069750D01*
X120417Y1070000D01*
X120458Y1070250D01*
X120375Y1070542D01*
X120083Y1070750D01*
X119792Y1070833D01*
X119417D01*
G01X119792D02*
X120042Y1070958D01*
X120250Y1071167D01*
X120333Y1071417D01*
X120250Y1071667D01*
X120042Y1071875D01*
X119667Y1072000D01*
X119292Y1071958D01*
X118917Y1071792D01*
G01X122517Y1069500D02*
X122600Y1070042D01*
X122725Y1070500D01*
X122892Y1070917D01*
X123100Y1071375D01*
X123433Y1072000D01*
X121767D01*
G01X117317Y1067792D02*
X117067Y1067917D01*
X116775Y1068000D01*
X116442D01*
X116067Y1067875D01*
X115775Y1067667D01*
X115567Y1067417D01*
X115400Y1067000D01*
X115358Y1066625D01*
X115442Y1066250D01*
X115567Y1066000D01*
X115817Y1065750D01*
X116108Y1065583D01*
X116400Y1065500D01*
X116692D01*
X116983Y1065583D01*
X117233Y1065708D01*
X117442Y1065875D01*
G01X118583Y1066000D02*
X118833Y1065708D01*
X119167Y1065542D01*
X119542Y1065500D01*
X119875Y1065542D01*
X120208Y1065750D01*
X120417Y1066000D01*
X120458Y1066250D01*
X120375Y1066542D01*
X120083Y1066750D01*
X119792Y1066833D01*
X119417D01*
G01X119792D02*
X120042Y1066958D01*
X120250Y1067167D01*
X120333Y1067417D01*
X120250Y1067667D01*
X120042Y1067875D01*
X119667Y1068000D01*
X119292Y1067958D01*
X118917Y1067792D01*
G01X121808Y1066542D02*
X122100Y1066833D01*
X122350Y1067000D01*
X122683Y1067083D01*
X122975Y1067000D01*
X123183Y1066833D01*
X123350Y1066583D01*
X123392Y1066292D01*
X123350Y1066042D01*
X123183Y1065792D01*
X122933Y1065583D01*
X122642Y1065500D01*
X122308Y1065583D01*
X122017Y1065833D01*
X121850Y1066208D01*
X121808Y1066625D01*
X121892Y1067167D01*
X122017Y1067458D01*
X122225Y1067750D01*
X122517Y1067958D01*
X122808Y1068000D01*
X123100Y1067917D01*
X123308Y1067708D01*
G01X111399Y1116550D02*
X111066Y1116592D01*
X110774Y1116758D01*
X110524Y1117008D01*
X110357Y1117300D01*
X110274Y1117633D01*
Y1117967D01*
X110357Y1118300D01*
X110524Y1118592D01*
X110774Y1118842D01*
X111066Y1119008D01*
X111399Y1119050D01*
X111732Y1119008D01*
X112024Y1118842D01*
X112274Y1118592D01*
X112441Y1118300D01*
X112524Y1117967D01*
Y1117633D01*
X112441Y1117300D01*
X112274Y1117008D01*
X112024Y1116758D01*
X111732Y1116592D01*
X111399Y1116550D01*
G01X111732Y1117217D02*
X112232Y1116550D01*
G01X114499D02*
Y1119050D01*
X113999Y1118550D01*
G01Y1116550D02*
X114999D01*
G01X116807Y1117592D02*
X117099Y1117883D01*
X117349Y1118050D01*
X117682Y1118133D01*
X117974Y1118050D01*
X118182Y1117883D01*
X118349Y1117633D01*
X118391Y1117342D01*
X118349Y1117092D01*
X118182Y1116842D01*
X117932Y1116633D01*
X117641Y1116550D01*
X117307Y1116633D01*
X117016Y1116883D01*
X116849Y1117258D01*
X116807Y1117675D01*
X116891Y1118217D01*
X117016Y1118508D01*
X117224Y1118800D01*
X117516Y1119008D01*
X117807Y1119050D01*
X118099Y1118967D01*
X118307Y1118758D01*
G01X116499Y1103500D02*
Y1114900D01*
G01X103099Y1103500D02*
X116499D01*
G01X103099Y1114900D02*
Y1103500D01*
G01X116499Y1114900D02*
X103099D01*
G01X124499Y1139800D02*
Y1165800D01*
G01X111499Y1139800D02*
X124499D01*
G01X111499Y1165800D02*
Y1139800D01*
G01X142500Y1132517D02*
X140000D01*
Y1133558D01*
X140125Y1133892D01*
X140292Y1134100D01*
X140625Y1134183D01*
X140958Y1134100D01*
X141167Y1133850D01*
X141292Y1133558D01*
Y1132517D01*
G01Y1133558D02*
X142500Y1134183D01*
G01X142125Y1135533D02*
X142333Y1135783D01*
X142458Y1136075D01*
X142500Y1136450D01*
X142417Y1136825D01*
X142250Y1137117D01*
X141958Y1137325D01*
X141625Y1137367D01*
X141292Y1137283D01*
X141083Y1137075D01*
X140917Y1136783D01*
X140875Y1136492D01*
X140917Y1136200D01*
X141083Y1135825D01*
X140000Y1135950D01*
Y1137075D01*
G01X142500Y1139467D02*
X141958Y1139550D01*
X141500Y1139675D01*
X141083Y1139842D01*
X140625Y1140050D01*
X140000Y1140383D01*
Y1138717D01*
G01Y1142650D02*
X140083Y1142317D01*
X140292Y1142067D01*
X140542Y1141900D01*
X140875Y1141775D01*
X141250Y1141733D01*
X141625Y1141775D01*
X141958Y1141900D01*
X142208Y1142067D01*
X142417Y1142317D01*
X142500Y1142650D01*
X142417Y1142983D01*
X142208Y1143233D01*
X141958Y1143400D01*
X141625Y1143525D01*
X141250Y1143567D01*
X140875Y1143525D01*
X140542Y1143400D01*
X140292Y1143233D01*
X140083Y1142983D01*
X140000Y1142650D01*
G01X129000Y1138700D02*
X125000D01*
Y1131300D01*
G01X134500Y1132517D02*
X132000D01*
Y1133558D01*
X132125Y1133892D01*
X132292Y1134100D01*
X132625Y1134183D01*
X132958Y1134100D01*
X133167Y1133850D01*
X133292Y1133558D01*
Y1132517D01*
G01Y1133558D02*
X134500Y1134183D01*
G01X134125Y1135533D02*
X134333Y1135783D01*
X134458Y1136075D01*
X134500Y1136450D01*
X134417Y1136825D01*
X134250Y1137117D01*
X133958Y1137325D01*
X133625Y1137367D01*
X133292Y1137283D01*
X133083Y1137075D01*
X132917Y1136783D01*
X132875Y1136492D01*
X132917Y1136200D01*
X133083Y1135825D01*
X132000Y1135950D01*
Y1137075D01*
G01X134125Y1138633D02*
X134333Y1138883D01*
X134458Y1139175D01*
X134500Y1139550D01*
X134417Y1139925D01*
X134250Y1140217D01*
X133958Y1140425D01*
X133625Y1140467D01*
X133292Y1140383D01*
X133083Y1140175D01*
X132917Y1139883D01*
X132875Y1139592D01*
X132917Y1139300D01*
X133083Y1138925D01*
X132000Y1139050D01*
Y1140175D01*
G01X133458Y1141858D02*
X133167Y1142150D01*
X133000Y1142400D01*
X132917Y1142733D01*
X133000Y1143025D01*
X133167Y1143233D01*
X133417Y1143400D01*
X133708Y1143442D01*
X133958Y1143400D01*
X134208Y1143233D01*
X134417Y1142983D01*
X134500Y1142692D01*
X134417Y1142358D01*
X134167Y1142067D01*
X133792Y1141900D01*
X133375Y1141858D01*
X132833Y1141942D01*
X132542Y1142067D01*
X132250Y1142275D01*
X132042Y1142567D01*
X132000Y1142858D01*
X132083Y1143150D01*
X132292Y1143358D01*
G01X117000Y1131300D02*
X121000D01*
Y1138700D01*
G01X102500Y1117200D02*
X98500D01*
Y1109800D01*
G01X99499Y1092250D02*
X95499D01*
Y1084850D01*
G01X114000Y1121017D02*
X111500D01*
Y1122058D01*
X111625Y1122392D01*
X111792Y1122600D01*
X112125Y1122683D01*
X112458Y1122600D01*
X112667Y1122350D01*
X112792Y1122058D01*
Y1121017D01*
G01Y1122058D02*
X114000Y1122683D01*
G01X111917Y1124158D02*
X111667Y1124408D01*
X111542Y1124700D01*
X111500Y1125033D01*
X111583Y1125450D01*
X111792Y1125742D01*
X112042Y1125825D01*
X112292Y1125783D01*
X112500Y1125617D01*
X112917Y1124783D01*
X113208Y1124408D01*
X113625Y1124158D01*
X114000Y1124075D01*
Y1125825D01*
G01X111500Y1128050D02*
X111583Y1127717D01*
X111792Y1127467D01*
X112042Y1127300D01*
X112375Y1127175D01*
X112750Y1127133D01*
X113125Y1127175D01*
X113458Y1127300D01*
X113708Y1127467D01*
X113917Y1127717D01*
X114000Y1128050D01*
X113917Y1128383D01*
X113708Y1128633D01*
X113458Y1128800D01*
X113125Y1128925D01*
X112750Y1128967D01*
X112375Y1128925D01*
X112042Y1128800D01*
X111792Y1128633D01*
X111583Y1128383D01*
X111500Y1128050D01*
G01X114000Y1131067D02*
X113458Y1131150D01*
X113000Y1131275D01*
X112583Y1131442D01*
X112125Y1131650D01*
X111500Y1131983D01*
Y1130317D01*
G01X116799Y1127050D02*
Y1123050D01*
X124199D01*
G01X127617Y1104300D02*
Y1106800D01*
X128658D01*
X128992Y1106675D01*
X129200Y1106508D01*
X129283Y1106175D01*
X129200Y1105842D01*
X128950Y1105633D01*
X128658Y1105508D01*
X127617D01*
G01X128658D02*
X129283Y1104300D01*
G01X130758Y1106383D02*
X131008Y1106633D01*
X131300Y1106758D01*
X131633Y1106800D01*
X132050Y1106717D01*
X132342Y1106508D01*
X132425Y1106258D01*
X132383Y1106008D01*
X132217Y1105800D01*
X131383Y1105383D01*
X131008Y1105092D01*
X130758Y1104675D01*
X130675Y1104300D01*
X132425D01*
G01X134650D02*
Y1106800D01*
X134150Y1106300D01*
G01Y1104300D02*
X135150D01*
G01X137750Y1106800D02*
X137417Y1106717D01*
X137167Y1106508D01*
X137000Y1106258D01*
X136875Y1105925D01*
X136833Y1105550D01*
X136875Y1105175D01*
X137000Y1104842D01*
X137167Y1104592D01*
X137417Y1104383D01*
X137750Y1104300D01*
X138083Y1104383D01*
X138333Y1104592D01*
X138500Y1104842D01*
X138625Y1105175D01*
X138667Y1105550D01*
X138625Y1105925D01*
X138500Y1106258D01*
X138333Y1106508D01*
X138083Y1106717D01*
X137750Y1106800D01*
G01X117499Y1104350D02*
X121499D01*
Y1111750D01*
G01X103999Y1092250D02*
X99999D01*
Y1084850D01*
G01X131497Y1097482D02*
Y1099982D01*
X132538D01*
X132872Y1099857D01*
X133080Y1099690D01*
X133163Y1099357D01*
X133080Y1099024D01*
X132830Y1098815D01*
X132538Y1098690D01*
X131497D01*
G01X132538D02*
X133163Y1097482D01*
G01X135930D02*
Y1099982D01*
X134388Y1098190D01*
X136472D01*
G01X137613Y1097857D02*
X137863Y1097649D01*
X138155Y1097524D01*
X138530Y1097482D01*
X138905Y1097565D01*
X139197Y1097732D01*
X139405Y1098024D01*
X139447Y1098357D01*
X139363Y1098690D01*
X139155Y1098899D01*
X138863Y1099065D01*
X138572Y1099107D01*
X138280Y1099065D01*
X137905Y1098899D01*
X138030Y1099982D01*
X139155D01*
G01X141630D02*
X141297Y1099899D01*
X141047Y1099690D01*
X140880Y1099440D01*
X140755Y1099107D01*
X140713Y1098732D01*
X140755Y1098357D01*
X140880Y1098024D01*
X141047Y1097774D01*
X141297Y1097565D01*
X141630Y1097482D01*
X141963Y1097565D01*
X142213Y1097774D01*
X142380Y1098024D01*
X142505Y1098357D01*
X142547Y1098732D01*
X142505Y1099107D01*
X142380Y1099440D01*
X142213Y1099690D01*
X141963Y1099899D01*
X141630Y1099982D01*
G01X130180Y1096482D02*
Y1100482D01*
X122780D01*
G01X131497Y1093482D02*
Y1095982D01*
X132538D01*
X132872Y1095857D01*
X133080Y1095690D01*
X133163Y1095357D01*
X133080Y1095024D01*
X132830Y1094815D01*
X132538Y1094690D01*
X131497D01*
G01X132538D02*
X133163Y1093482D01*
G01X135930D02*
Y1095982D01*
X134388Y1094190D01*
X136472D01*
G01X137613Y1093857D02*
X137863Y1093649D01*
X138155Y1093524D01*
X138530Y1093482D01*
X138905Y1093565D01*
X139197Y1093732D01*
X139405Y1094024D01*
X139447Y1094357D01*
X139363Y1094690D01*
X139155Y1094899D01*
X138863Y1095065D01*
X138572Y1095107D01*
X138280Y1095065D01*
X137905Y1094899D01*
X138030Y1095982D01*
X139155D01*
G01X141630Y1093482D02*
Y1095982D01*
X141130Y1095482D01*
G01Y1093482D02*
X142130D01*
G01X130180Y1092482D02*
Y1096482D01*
X122780D01*
G01X95899Y1083700D02*
Y1079700D01*
X103299D01*
G01X95899Y1079400D02*
Y1075400D01*
X103299D01*
G01X98500Y1101800D02*
X102500D01*
Y1109200D01*
G01X119499Y1078033D02*
X121291D01*
X121666Y1078200D01*
X121916Y1078533D01*
X121999Y1078950D01*
X121916Y1079367D01*
X121666Y1079700D01*
X121291Y1079867D01*
X119499D01*
G01X119916Y1081258D02*
X119666Y1081508D01*
X119541Y1081800D01*
X119499Y1082133D01*
X119582Y1082550D01*
X119791Y1082842D01*
X120041Y1082925D01*
X120291Y1082883D01*
X120499Y1082717D01*
X120916Y1081883D01*
X121207Y1081508D01*
X121624Y1081258D01*
X121999Y1081175D01*
Y1082925D01*
G01X119916Y1084358D02*
X119666Y1084608D01*
X119541Y1084900D01*
X119499Y1085233D01*
X119582Y1085650D01*
X119791Y1085942D01*
X120041Y1086025D01*
X120291Y1085983D01*
X120499Y1085817D01*
X120916Y1084983D01*
X121207Y1084608D01*
X121624Y1084358D01*
X121999Y1084275D01*
Y1086025D01*
G01X116999Y1089250D02*
Y1075850D01*
G01X106999Y1089250D02*
X116999D01*
G01X106999Y1075850D02*
Y1089250D01*
G01X116999Y1075850D02*
X106999D01*
G01X106299Y1101550D02*
X119699D01*
G01X106299Y1091550D02*
Y1101550D01*
G01X119699Y1091550D02*
X106299D01*
G01X119699Y1101550D02*
Y1091550D01*
G01X131999Y1115400D02*
X134499D01*
G01X131999Y1114442D02*
Y1116358D01*
G01X134499Y1117667D02*
X131999D01*
Y1118667D01*
X132124Y1119000D01*
X132416Y1119250D01*
X132749Y1119333D01*
X133082Y1119250D01*
X133332Y1119042D01*
X133457Y1118667D01*
Y1117667D01*
G01X133999Y1120683D02*
X134291Y1120933D01*
X134457Y1121267D01*
X134499Y1121642D01*
X134457Y1121975D01*
X134249Y1122308D01*
X133999Y1122517D01*
X133749Y1122558D01*
X133457Y1122475D01*
X133249Y1122183D01*
X133166Y1121892D01*
Y1121517D01*
G01Y1121892D02*
X133041Y1122142D01*
X132832Y1122350D01*
X132582Y1122433D01*
X132332Y1122350D01*
X132124Y1122142D01*
X131999Y1121767D01*
X132041Y1121392D01*
X132207Y1121017D01*
G01X132416Y1123908D02*
X132166Y1124158D01*
X132041Y1124450D01*
X131999Y1124783D01*
X132082Y1125200D01*
X132291Y1125492D01*
X132541Y1125575D01*
X132791Y1125533D01*
X132999Y1125367D01*
X133416Y1124533D01*
X133707Y1124158D01*
X134124Y1123908D01*
X134499Y1123825D01*
Y1125575D01*
G01X154683Y1194500D02*
Y1197000D01*
X155517D01*
X155850Y1196875D01*
X156100Y1196708D01*
X156308Y1196458D01*
X156475Y1196167D01*
X156517Y1195750D01*
X156475Y1195333D01*
X156308Y1195042D01*
X156100Y1194792D01*
X155850Y1194625D01*
X155517Y1194500D01*
X154683D01*
G01X157908Y1196583D02*
X158158Y1196833D01*
X158450Y1196958D01*
X158783Y1197000D01*
X159200Y1196917D01*
X159492Y1196708D01*
X159575Y1196458D01*
X159533Y1196208D01*
X159367Y1196000D01*
X158533Y1195583D01*
X158158Y1195292D01*
X157908Y1194875D01*
X157825Y1194500D01*
X159575D01*
G01X161008Y1195542D02*
X161300Y1195833D01*
X161550Y1196000D01*
X161883Y1196083D01*
X162175Y1196000D01*
X162383Y1195833D01*
X162550Y1195583D01*
X162592Y1195292D01*
X162550Y1195042D01*
X162383Y1194792D01*
X162133Y1194583D01*
X161842Y1194500D01*
X161508Y1194583D01*
X161217Y1194833D01*
X161050Y1195208D01*
X161008Y1195625D01*
X161092Y1196167D01*
X161217Y1196458D01*
X161425Y1196750D01*
X161717Y1196958D01*
X162008Y1197000D01*
X162300Y1196917D01*
X162508Y1196708D01*
G01X146000Y1192500D02*
X129900D01*
G01X146000Y1199500D02*
Y1192500D01*
G01X129900Y1199500D02*
X146000D01*
G01X129900Y1192500D02*
Y1199500D01*
G01X167167Y1205692D02*
X166917Y1205817D01*
X166625Y1205900D01*
X166292D01*
X165917Y1205775D01*
X165625Y1205567D01*
X165417Y1205317D01*
X165250Y1204900D01*
X165208Y1204525D01*
X165292Y1204150D01*
X165417Y1203900D01*
X165667Y1203650D01*
X165958Y1203483D01*
X166250Y1203400D01*
X166542D01*
X166833Y1203483D01*
X167083Y1203608D01*
X167292Y1203775D01*
G01X168433Y1203900D02*
X168683Y1203608D01*
X169017Y1203442D01*
X169392Y1203400D01*
X169725Y1203442D01*
X170058Y1203650D01*
X170267Y1203900D01*
X170308Y1204150D01*
X170225Y1204442D01*
X169933Y1204650D01*
X169642Y1204733D01*
X169267D01*
G01X169642D02*
X169892Y1204858D01*
X170100Y1205067D01*
X170183Y1205317D01*
X170100Y1205567D01*
X169892Y1205775D01*
X169517Y1205900D01*
X169142Y1205858D01*
X168767Y1205692D01*
G01X171742Y1203692D02*
X172033Y1203483D01*
X172367Y1203400D01*
X172700Y1203483D01*
X172992Y1203733D01*
X173200Y1204108D01*
X173283Y1204483D01*
Y1204942D01*
X173200Y1205317D01*
X172992Y1205650D01*
X172742Y1205817D01*
X172450Y1205900D01*
X172117Y1205817D01*
X171867Y1205650D01*
X171700Y1205400D01*
X171617Y1205067D01*
X171700Y1204775D01*
X171908Y1204483D01*
X172158Y1204317D01*
X172450Y1204275D01*
X172783Y1204358D01*
X173033Y1204567D01*
X173283Y1204942D01*
G01X175550Y1205900D02*
X175217Y1205817D01*
X174967Y1205608D01*
X174800Y1205358D01*
X174675Y1205025D01*
X174633Y1204650D01*
X174675Y1204275D01*
X174800Y1203942D01*
X174967Y1203692D01*
X175217Y1203483D01*
X175550Y1203400D01*
X175883Y1203483D01*
X176133Y1203692D01*
X176300Y1203942D01*
X176425Y1204275D01*
X176467Y1204650D01*
X176425Y1205025D01*
X176300Y1205358D01*
X176133Y1205608D01*
X175883Y1205817D01*
X175550Y1205900D01*
G01X161308Y1176467D02*
X161183Y1176217D01*
X161100Y1175925D01*
Y1175592D01*
X161225Y1175217D01*
X161433Y1174925D01*
X161683Y1174717D01*
X162100Y1174550D01*
X162475Y1174508D01*
X162850Y1174592D01*
X163100Y1174717D01*
X163350Y1174967D01*
X163517Y1175258D01*
X163600Y1175550D01*
Y1175842D01*
X163517Y1176133D01*
X163392Y1176383D01*
X163225Y1176592D01*
G01X161517Y1177858D02*
X161267Y1178108D01*
X161142Y1178400D01*
X161100Y1178733D01*
X161183Y1179150D01*
X161392Y1179442D01*
X161642Y1179525D01*
X161892Y1179483D01*
X162100Y1179317D01*
X162517Y1178483D01*
X162808Y1178108D01*
X163225Y1177858D01*
X163600Y1177775D01*
Y1179525D01*
G01X161517Y1180958D02*
X161267Y1181208D01*
X161142Y1181500D01*
X161100Y1181833D01*
X161183Y1182250D01*
X161392Y1182542D01*
X161642Y1182625D01*
X161892Y1182583D01*
X162100Y1182417D01*
X162517Y1181583D01*
X162808Y1181208D01*
X163225Y1180958D01*
X163600Y1180875D01*
Y1182625D01*
G01Y1184767D02*
X163058Y1184850D01*
X162600Y1184975D01*
X162183Y1185142D01*
X161725Y1185350D01*
X161100Y1185683D01*
Y1184017D01*
G01X118600Y1191300D02*
X118267Y1191342D01*
X117975Y1191508D01*
X117725Y1191758D01*
X117558Y1192050D01*
X117475Y1192383D01*
Y1192717D01*
X117558Y1193050D01*
X117725Y1193342D01*
X117975Y1193592D01*
X118267Y1193758D01*
X118600Y1193800D01*
X118933Y1193758D01*
X119225Y1193592D01*
X119475Y1193342D01*
X119642Y1193050D01*
X119725Y1192717D01*
Y1192383D01*
X119642Y1192050D01*
X119475Y1191758D01*
X119225Y1191508D01*
X118933Y1191342D01*
X118600Y1191300D01*
G01X118933Y1191967D02*
X119433Y1191300D01*
G01X120908Y1193383D02*
X121158Y1193633D01*
X121450Y1193758D01*
X121783Y1193800D01*
X122200Y1193717D01*
X122492Y1193508D01*
X122575Y1193258D01*
X122533Y1193008D01*
X122367Y1192800D01*
X121533Y1192383D01*
X121158Y1192092D01*
X120908Y1191675D01*
X120825Y1191300D01*
X122575D01*
G01X125300D02*
Y1193800D01*
X123758Y1192008D01*
X125842D01*
G01X120299Y1221813D02*
Y1210413D01*
G01X133699Y1221813D02*
X120299D01*
G01X133699Y1210413D02*
Y1221813D01*
G01X120299Y1210413D02*
X133699D01*
G01X133499Y1150067D02*
X130999D01*
Y1151108D01*
X131124Y1151442D01*
X131291Y1151650D01*
X131624Y1151733D01*
X131957Y1151650D01*
X132166Y1151400D01*
X132291Y1151108D01*
Y1150067D01*
G01Y1151108D02*
X133499Y1151733D01*
G01X131416Y1153208D02*
X131166Y1153458D01*
X131041Y1153750D01*
X130999Y1154083D01*
X131082Y1154500D01*
X131291Y1154792D01*
X131541Y1154875D01*
X131791Y1154833D01*
X131999Y1154667D01*
X132416Y1153833D01*
X132707Y1153458D01*
X133124Y1153208D01*
X133499Y1153125D01*
Y1154875D01*
G01X130999Y1157100D02*
X131082Y1156767D01*
X131291Y1156517D01*
X131541Y1156350D01*
X131874Y1156225D01*
X132249Y1156183D01*
X132624Y1156225D01*
X132957Y1156350D01*
X133207Y1156517D01*
X133416Y1156767D01*
X133499Y1157100D01*
X133416Y1157433D01*
X133207Y1157683D01*
X132957Y1157850D01*
X132624Y1157975D01*
X132249Y1158017D01*
X131874Y1157975D01*
X131541Y1157850D01*
X131291Y1157683D01*
X131082Y1157433D01*
X130999Y1157100D01*
G01X133207Y1159492D02*
X133416Y1159783D01*
X133499Y1160117D01*
X133416Y1160450D01*
X133166Y1160742D01*
X132791Y1160950D01*
X132416Y1161033D01*
X131957D01*
X131582Y1160950D01*
X131249Y1160742D01*
X131082Y1160492D01*
X130999Y1160200D01*
X131082Y1159867D01*
X131249Y1159617D01*
X131499Y1159450D01*
X131832Y1159367D01*
X132124Y1159450D01*
X132416Y1159658D01*
X132582Y1159908D01*
X132624Y1160200D01*
X132541Y1160533D01*
X132332Y1160783D01*
X131957Y1161033D01*
G01X124499Y1165800D02*
X111499D01*
G01X165817Y1198800D02*
Y1201300D01*
X166858D01*
X167192Y1201175D01*
X167400Y1201008D01*
X167483Y1200675D01*
X167400Y1200342D01*
X167150Y1200133D01*
X166858Y1200008D01*
X165817D01*
G01X166858D02*
X167483Y1198800D01*
G01X168833Y1199175D02*
X169083Y1198967D01*
X169375Y1198842D01*
X169750Y1198800D01*
X170125Y1198883D01*
X170417Y1199050D01*
X170625Y1199342D01*
X170667Y1199675D01*
X170583Y1200008D01*
X170375Y1200217D01*
X170083Y1200383D01*
X169792Y1200425D01*
X169500Y1200383D01*
X169125Y1200217D01*
X169250Y1201300D01*
X170375D01*
G01X172767Y1198800D02*
X172850Y1199342D01*
X172975Y1199800D01*
X173142Y1200217D01*
X173350Y1200675D01*
X173683Y1201300D01*
X172017D01*
G01X176450Y1198800D02*
Y1201300D01*
X174908Y1199508D01*
X176992D01*
G01X137800Y1204000D02*
Y1200000D01*
X145200D01*
G01X147917Y1208700D02*
Y1211200D01*
X148958D01*
X149292Y1211075D01*
X149500Y1210908D01*
X149583Y1210575D01*
X149500Y1210242D01*
X149250Y1210033D01*
X148958Y1209908D01*
X147917D01*
G01X148958D02*
X149583Y1208700D01*
G01X150933Y1209075D02*
X151183Y1208867D01*
X151475Y1208742D01*
X151850Y1208700D01*
X152225Y1208783D01*
X152517Y1208950D01*
X152725Y1209242D01*
X152767Y1209575D01*
X152683Y1209908D01*
X152475Y1210117D01*
X152183Y1210283D01*
X151892Y1210325D01*
X151600Y1210283D01*
X151225Y1210117D01*
X151350Y1211200D01*
X152475D01*
G01X154033Y1209075D02*
X154283Y1208867D01*
X154575Y1208742D01*
X154950Y1208700D01*
X155325Y1208783D01*
X155617Y1208950D01*
X155825Y1209242D01*
X155867Y1209575D01*
X155783Y1209908D01*
X155575Y1210117D01*
X155283Y1210283D01*
X154992Y1210325D01*
X154700Y1210283D01*
X154325Y1210117D01*
X154450Y1211200D01*
X155575D01*
G01X157342Y1208992D02*
X157633Y1208783D01*
X157967Y1208700D01*
X158300Y1208783D01*
X158592Y1209033D01*
X158800Y1209408D01*
X158883Y1209783D01*
Y1210242D01*
X158800Y1210617D01*
X158592Y1210950D01*
X158342Y1211117D01*
X158050Y1211200D01*
X157717Y1211117D01*
X157467Y1210950D01*
X157300Y1210700D01*
X157217Y1210367D01*
X157300Y1210075D01*
X157508Y1209783D01*
X157758Y1209617D01*
X158050Y1209575D01*
X158383Y1209658D01*
X158633Y1209867D01*
X158883Y1210242D01*
G01X134300Y1212000D02*
Y1208000D01*
X141700D01*
G01X104999Y1221913D02*
X108999D01*
Y1229313D01*
G01X152817Y1198600D02*
Y1201100D01*
X153858D01*
X154192Y1200975D01*
X154400Y1200808D01*
X154483Y1200475D01*
X154400Y1200142D01*
X154150Y1199933D01*
X153858Y1199808D01*
X152817D01*
G01X153858D02*
X154483Y1198600D01*
G01X155958Y1200683D02*
X156208Y1200933D01*
X156500Y1201058D01*
X156833Y1201100D01*
X157250Y1201017D01*
X157542Y1200808D01*
X157625Y1200558D01*
X157583Y1200308D01*
X157417Y1200100D01*
X156583Y1199683D01*
X156208Y1199392D01*
X155958Y1198975D01*
X155875Y1198600D01*
X157625D01*
G01X159058Y1199642D02*
X159350Y1199933D01*
X159600Y1200100D01*
X159933Y1200183D01*
X160225Y1200100D01*
X160433Y1199933D01*
X160600Y1199683D01*
X160642Y1199392D01*
X160600Y1199142D01*
X160433Y1198892D01*
X160183Y1198683D01*
X159892Y1198600D01*
X159558Y1198683D01*
X159267Y1198933D01*
X159100Y1199308D01*
X159058Y1199725D01*
X159142Y1200267D01*
X159267Y1200558D01*
X159475Y1200850D01*
X159767Y1201058D01*
X160058Y1201100D01*
X160350Y1201017D01*
X160558Y1200808D01*
G01X162158Y1200683D02*
X162408Y1200933D01*
X162700Y1201058D01*
X163033Y1201100D01*
X163450Y1201017D01*
X163742Y1200808D01*
X163825Y1200558D01*
X163783Y1200308D01*
X163617Y1200100D01*
X162783Y1199683D01*
X162408Y1199392D01*
X162158Y1198975D01*
X162075Y1198600D01*
X163825D01*
G01X129300Y1204000D02*
Y1200000D01*
X136700D01*
G01X129499Y1229813D02*
X125499D01*
Y1222413D01*
G01X118499Y1229313D02*
X114499D01*
Y1221913D01*
G01X109999D02*
X113999D01*
Y1229313D01*
G01X107499Y1196413D02*
X111499D01*
Y1203813D01*
G01X103499Y1196413D02*
X107499D01*
Y1203813D01*
G01X152017Y1203500D02*
Y1206000D01*
X153058D01*
X153392Y1205875D01*
X153600Y1205708D01*
X153683Y1205375D01*
X153600Y1205042D01*
X153350Y1204833D01*
X153058Y1204708D01*
X152017D01*
G01X153058D02*
X153683Y1203500D01*
G01X156450D02*
Y1206000D01*
X154908Y1204208D01*
X156992D01*
G01X159050Y1203500D02*
Y1206000D01*
X158550Y1205500D01*
G01Y1203500D02*
X159550D01*
G01X161442Y1203792D02*
X161733Y1203583D01*
X162067Y1203500D01*
X162400Y1203583D01*
X162692Y1203833D01*
X162900Y1204208D01*
X162983Y1204583D01*
Y1205042D01*
X162900Y1205417D01*
X162692Y1205750D01*
X162442Y1205917D01*
X162150Y1206000D01*
X161817Y1205917D01*
X161567Y1205750D01*
X161400Y1205500D01*
X161317Y1205167D01*
X161400Y1204875D01*
X161608Y1204583D01*
X161858Y1204417D01*
X162150Y1204375D01*
X162483Y1204458D01*
X162733Y1204667D01*
X162983Y1205042D01*
G01X129300Y1208000D02*
Y1204000D01*
X136700D01*
G01X114482Y1204550D02*
Y1202758D01*
X114649Y1202383D01*
X114982Y1202133D01*
X115399Y1202050D01*
X115816Y1202133D01*
X116149Y1202383D01*
X116316Y1202758D01*
Y1204550D01*
G01X117582Y1202550D02*
X117832Y1202258D01*
X118166Y1202092D01*
X118541Y1202050D01*
X118874Y1202092D01*
X119207Y1202300D01*
X119416Y1202550D01*
X119457Y1202800D01*
X119374Y1203092D01*
X119082Y1203300D01*
X118791Y1203383D01*
X118416D01*
G01X118791D02*
X119041Y1203508D01*
X119249Y1203717D01*
X119332Y1203967D01*
X119249Y1204217D01*
X119041Y1204425D01*
X118666Y1204550D01*
X118291Y1204508D01*
X117916Y1204342D01*
G01X120807Y1203092D02*
X121099Y1203383D01*
X121349Y1203550D01*
X121682Y1203633D01*
X121974Y1203550D01*
X122182Y1203383D01*
X122349Y1203133D01*
X122391Y1202842D01*
X122349Y1202592D01*
X122182Y1202342D01*
X121932Y1202133D01*
X121641Y1202050D01*
X121307Y1202133D01*
X121016Y1202383D01*
X120849Y1202758D01*
X120807Y1203175D01*
X120891Y1203717D01*
X121016Y1204008D01*
X121224Y1204300D01*
X121516Y1204508D01*
X121807Y1204550D01*
X122099Y1204467D01*
X122307Y1204258D01*
G01X114499Y1220313D02*
Y1206913D01*
G01X104499Y1220313D02*
X114499D01*
G01X104499Y1206913D02*
Y1220313D01*
G01X114499Y1206913D02*
X104499D01*
G01X165983Y1228000D02*
Y1226208D01*
X166150Y1225833D01*
X166483Y1225583D01*
X166900Y1225500D01*
X167317Y1225583D01*
X167650Y1225833D01*
X167817Y1226208D01*
Y1228000D01*
G01X169083Y1226000D02*
X169333Y1225708D01*
X169667Y1225542D01*
X170042Y1225500D01*
X170375Y1225542D01*
X170708Y1225750D01*
X170917Y1226000D01*
X170958Y1226250D01*
X170875Y1226542D01*
X170583Y1226750D01*
X170292Y1226833D01*
X169917D01*
G01X170292D02*
X170542Y1226958D01*
X170750Y1227167D01*
X170833Y1227417D01*
X170750Y1227667D01*
X170542Y1227875D01*
X170167Y1228000D01*
X169792Y1227958D01*
X169417Y1227792D01*
G01X172183Y1225875D02*
X172433Y1225667D01*
X172725Y1225542D01*
X173100Y1225500D01*
X173475Y1225583D01*
X173767Y1225750D01*
X173975Y1226042D01*
X174017Y1226375D01*
X173933Y1226708D01*
X173725Y1226917D01*
X173433Y1227083D01*
X173142Y1227125D01*
X172850Y1227083D01*
X172475Y1226917D01*
X172600Y1228000D01*
X173725D01*
G01X142899Y1234413D02*
Y1215213D01*
X154099D01*
Y1234413D01*
X142899D01*
G01X152608Y1176167D02*
X152483Y1175917D01*
X152400Y1175625D01*
Y1175292D01*
X152525Y1174917D01*
X152733Y1174625D01*
X152983Y1174417D01*
X153400Y1174250D01*
X153775Y1174208D01*
X154150Y1174292D01*
X154400Y1174417D01*
X154650Y1174667D01*
X154817Y1174958D01*
X154900Y1175250D01*
Y1175542D01*
X154817Y1175833D01*
X154692Y1176083D01*
X154525Y1176292D01*
G01X152817Y1177558D02*
X152567Y1177808D01*
X152442Y1178100D01*
X152400Y1178433D01*
X152483Y1178850D01*
X152692Y1179142D01*
X152942Y1179225D01*
X153192Y1179183D01*
X153400Y1179017D01*
X153817Y1178183D01*
X154108Y1177808D01*
X154525Y1177558D01*
X154900Y1177475D01*
Y1179225D01*
G01X152817Y1180658D02*
X152567Y1180908D01*
X152442Y1181200D01*
X152400Y1181533D01*
X152483Y1181950D01*
X152692Y1182242D01*
X152942Y1182325D01*
X153192Y1182283D01*
X153400Y1182117D01*
X153817Y1181283D01*
X154108Y1180908D01*
X154525Y1180658D01*
X154900Y1180575D01*
Y1182325D01*
G01X154400Y1183633D02*
X154692Y1183883D01*
X154858Y1184217D01*
X154900Y1184592D01*
X154858Y1184925D01*
X154650Y1185258D01*
X154400Y1185467D01*
X154150Y1185508D01*
X153858Y1185425D01*
X153650Y1185133D01*
X153567Y1184842D01*
Y1184467D01*
G01Y1184842D02*
X153442Y1185092D01*
X153233Y1185300D01*
X152983Y1185383D01*
X152733Y1185300D01*
X152525Y1185092D01*
X152400Y1184717D01*
X152442Y1184342D01*
X152608Y1183967D01*
G01X125900Y1168200D02*
Y1173700D01*
G01X133900Y1168200D02*
X125900D01*
G01X133900Y1173700D02*
Y1168200D01*
G01Y1185800D02*
Y1180300D01*
G01X125900Y1185800D02*
X133900D01*
G01X125900Y1180300D02*
Y1185800D01*
G01X140208Y1176267D02*
X140083Y1176017D01*
X140000Y1175725D01*
Y1175392D01*
X140125Y1175017D01*
X140333Y1174725D01*
X140583Y1174517D01*
X141000Y1174350D01*
X141375Y1174308D01*
X141750Y1174392D01*
X142000Y1174517D01*
X142250Y1174767D01*
X142417Y1175058D01*
X142500Y1175350D01*
Y1175642D01*
X142417Y1175933D01*
X142292Y1176183D01*
X142125Y1176392D01*
G01X140417Y1177658D02*
X140167Y1177908D01*
X140042Y1178200D01*
X140000Y1178533D01*
X140083Y1178950D01*
X140292Y1179242D01*
X140542Y1179325D01*
X140792Y1179283D01*
X141000Y1179117D01*
X141417Y1178283D01*
X141708Y1177908D01*
X142125Y1177658D01*
X142500Y1177575D01*
Y1179325D01*
G01X140417Y1180758D02*
X140167Y1181008D01*
X140042Y1181300D01*
X140000Y1181633D01*
X140083Y1182050D01*
X140292Y1182342D01*
X140542Y1182425D01*
X140792Y1182383D01*
X141000Y1182217D01*
X141417Y1181383D01*
X141708Y1181008D01*
X142125Y1180758D01*
X142500Y1180675D01*
Y1182425D01*
G01Y1185150D02*
X140000D01*
X141792Y1183608D01*
Y1185692D01*
G01X98999Y1168250D02*
Y1173750D01*
G01X106999Y1168250D02*
X98999D01*
G01X106999Y1173750D02*
Y1168250D01*
G01Y1185850D02*
Y1180350D01*
G01X98999Y1185850D02*
X106999D01*
G01X98999Y1180350D02*
Y1185850D01*
G01X144208Y1176267D02*
X144083Y1176017D01*
X144000Y1175725D01*
Y1175392D01*
X144125Y1175017D01*
X144333Y1174725D01*
X144583Y1174517D01*
X145000Y1174350D01*
X145375Y1174308D01*
X145750Y1174392D01*
X146000Y1174517D01*
X146250Y1174767D01*
X146417Y1175058D01*
X146500Y1175350D01*
Y1175642D01*
X146417Y1175933D01*
X146292Y1176183D01*
X146125Y1176392D01*
G01X144417Y1177658D02*
X144167Y1177908D01*
X144042Y1178200D01*
X144000Y1178533D01*
X144083Y1178950D01*
X144292Y1179242D01*
X144542Y1179325D01*
X144792Y1179283D01*
X145000Y1179117D01*
X145417Y1178283D01*
X145708Y1177908D01*
X146125Y1177658D01*
X146500Y1177575D01*
Y1179325D01*
G01X144417Y1180758D02*
X144167Y1181008D01*
X144042Y1181300D01*
X144000Y1181633D01*
X144083Y1182050D01*
X144292Y1182342D01*
X144542Y1182425D01*
X144792Y1182383D01*
X145000Y1182217D01*
X145417Y1181383D01*
X145708Y1181008D01*
X146125Y1180758D01*
X146500Y1180675D01*
Y1182425D01*
G01X146125Y1183733D02*
X146333Y1183983D01*
X146458Y1184275D01*
X146500Y1184650D01*
X146417Y1185025D01*
X146250Y1185317D01*
X145958Y1185525D01*
X145625Y1185567D01*
X145292Y1185483D01*
X145083Y1185275D01*
X144917Y1184983D01*
X144875Y1184692D01*
X144917Y1184400D01*
X145083Y1184025D01*
X144000Y1184150D01*
Y1185275D01*
G01X107999Y1168250D02*
Y1173750D01*
G01X115999Y1168250D02*
X107999D01*
G01X115999Y1173750D02*
Y1168250D01*
G01Y1185850D02*
Y1180350D01*
G01X107999Y1185850D02*
X115999D01*
G01X107999Y1180350D02*
Y1185850D01*
G01X148208Y1176267D02*
X148083Y1176017D01*
X148000Y1175725D01*
Y1175392D01*
X148125Y1175017D01*
X148333Y1174725D01*
X148583Y1174517D01*
X149000Y1174350D01*
X149375Y1174308D01*
X149750Y1174392D01*
X150000Y1174517D01*
X150250Y1174767D01*
X150417Y1175058D01*
X150500Y1175350D01*
Y1175642D01*
X150417Y1175933D01*
X150292Y1176183D01*
X150125Y1176392D01*
G01X148417Y1177658D02*
X148167Y1177908D01*
X148042Y1178200D01*
X148000Y1178533D01*
X148083Y1178950D01*
X148292Y1179242D01*
X148542Y1179325D01*
X148792Y1179283D01*
X149000Y1179117D01*
X149417Y1178283D01*
X149708Y1177908D01*
X150125Y1177658D01*
X150500Y1177575D01*
Y1179325D01*
G01X148417Y1180758D02*
X148167Y1181008D01*
X148042Y1181300D01*
X148000Y1181633D01*
X148083Y1182050D01*
X148292Y1182342D01*
X148542Y1182425D01*
X148792Y1182383D01*
X149000Y1182217D01*
X149417Y1181383D01*
X149708Y1181008D01*
X150125Y1180758D01*
X150500Y1180675D01*
Y1182425D01*
G01X149458Y1183858D02*
X149167Y1184150D01*
X149000Y1184400D01*
X148917Y1184733D01*
X149000Y1185025D01*
X149167Y1185233D01*
X149417Y1185400D01*
X149708Y1185442D01*
X149958Y1185400D01*
X150208Y1185233D01*
X150417Y1184983D01*
X150500Y1184692D01*
X150417Y1184358D01*
X150167Y1184067D01*
X149792Y1183900D01*
X149375Y1183858D01*
X148833Y1183942D01*
X148542Y1184067D01*
X148250Y1184275D01*
X148042Y1184567D01*
X148000Y1184858D01*
X148083Y1185150D01*
X148292Y1185358D01*
G01X116999Y1168250D02*
Y1173750D01*
G01X124999Y1168250D02*
X116999D01*
G01X124999Y1173750D02*
Y1168250D01*
G01Y1185850D02*
Y1180350D01*
G01X116999Y1185850D02*
X124999D01*
G01X116999Y1180350D02*
Y1185850D01*
G01X151708Y1305317D02*
X151583Y1305067D01*
X151500Y1304775D01*
Y1304442D01*
X151625Y1304067D01*
X151833Y1303775D01*
X152083Y1303567D01*
X152500Y1303400D01*
X152875Y1303358D01*
X153250Y1303442D01*
X153500Y1303567D01*
X153750Y1303817D01*
X153917Y1304108D01*
X154000Y1304400D01*
Y1304692D01*
X153917Y1304983D01*
X153792Y1305233D01*
X153625Y1305442D01*
G01X151917Y1306708D02*
X151667Y1306958D01*
X151542Y1307250D01*
X151500Y1307583D01*
X151583Y1308000D01*
X151792Y1308292D01*
X152042Y1308375D01*
X152292Y1308333D01*
X152500Y1308167D01*
X152917Y1307333D01*
X153208Y1306958D01*
X153625Y1306708D01*
X154000Y1306625D01*
Y1308375D01*
G01Y1310600D02*
X153958Y1310892D01*
X153833Y1311225D01*
X153625Y1311433D01*
X153333Y1311517D01*
X153042Y1311433D01*
X152792Y1311183D01*
X152667Y1310808D01*
Y1310392D01*
X152583Y1310142D01*
X152375Y1309933D01*
X152083Y1309850D01*
X151792Y1309975D01*
X151583Y1310267D01*
X151500Y1310600D01*
X151583Y1310933D01*
X151792Y1311225D01*
X152083Y1311350D01*
X152375Y1311267D01*
X152583Y1311058D01*
X152667Y1310808D01*
Y1310392D01*
X152792Y1310017D01*
X153042Y1309767D01*
X153333Y1309683D01*
X153625Y1309767D01*
X153833Y1309975D01*
X153958Y1310308D01*
X154000Y1310600D01*
G01X153500Y1312783D02*
X153792Y1313033D01*
X153958Y1313367D01*
X154000Y1313742D01*
X153958Y1314075D01*
X153750Y1314408D01*
X153500Y1314617D01*
X153250Y1314658D01*
X152958Y1314575D01*
X152750Y1314283D01*
X152667Y1313992D01*
Y1313617D01*
G01Y1313992D02*
X152542Y1314242D01*
X152333Y1314450D01*
X152083Y1314533D01*
X151833Y1314450D01*
X151625Y1314242D01*
X151500Y1313867D01*
X151542Y1313492D01*
X151708Y1313117D01*
G01X147708Y1305317D02*
X147583Y1305067D01*
X147500Y1304775D01*
Y1304442D01*
X147625Y1304067D01*
X147833Y1303775D01*
X148083Y1303567D01*
X148500Y1303400D01*
X148875Y1303358D01*
X149250Y1303442D01*
X149500Y1303567D01*
X149750Y1303817D01*
X149917Y1304108D01*
X150000Y1304400D01*
Y1304692D01*
X149917Y1304983D01*
X149792Y1305233D01*
X149625Y1305442D01*
G01X147917Y1306708D02*
X147667Y1306958D01*
X147542Y1307250D01*
X147500Y1307583D01*
X147583Y1308000D01*
X147792Y1308292D01*
X148042Y1308375D01*
X148292Y1308333D01*
X148500Y1308167D01*
X148917Y1307333D01*
X149208Y1306958D01*
X149625Y1306708D01*
X150000Y1306625D01*
Y1308375D01*
G01Y1310517D02*
X149458Y1310600D01*
X149000Y1310725D01*
X148583Y1310892D01*
X148125Y1311100D01*
X147500Y1311433D01*
Y1309767D01*
G01X150000Y1313617D02*
X149458Y1313700D01*
X149000Y1313825D01*
X148583Y1313992D01*
X148125Y1314200D01*
X147500Y1314533D01*
Y1312867D01*
G01X179499Y1281950D02*
X179457Y1281617D01*
X179291Y1281325D01*
X179041Y1281075D01*
X178749Y1280908D01*
X178416Y1280825D01*
X178082D01*
X177749Y1280908D01*
X177457Y1281075D01*
X177207Y1281325D01*
X177041Y1281617D01*
X176999Y1281950D01*
X177041Y1282283D01*
X177207Y1282575D01*
X177457Y1282825D01*
X177749Y1282992D01*
X178082Y1283075D01*
X178416D01*
X178749Y1282992D01*
X179041Y1282825D01*
X179291Y1282575D01*
X179457Y1282283D01*
X179499Y1281950D01*
G01X178832Y1282283D02*
X179499Y1282783D01*
G01X177416Y1284258D02*
X177166Y1284508D01*
X177041Y1284800D01*
X176999Y1285133D01*
X177082Y1285550D01*
X177291Y1285842D01*
X177541Y1285925D01*
X177791Y1285883D01*
X177999Y1285717D01*
X178416Y1284883D01*
X178707Y1284508D01*
X179124Y1284258D01*
X179499Y1284175D01*
Y1285925D01*
G01X178999Y1287233D02*
X179291Y1287483D01*
X179457Y1287817D01*
X179499Y1288192D01*
X179457Y1288525D01*
X179249Y1288858D01*
X178999Y1289067D01*
X178749Y1289108D01*
X178457Y1289025D01*
X178249Y1288733D01*
X178166Y1288442D01*
Y1288067D01*
G01Y1288442D02*
X178041Y1288692D01*
X177832Y1288900D01*
X177582Y1288983D01*
X177332Y1288900D01*
X177124Y1288692D01*
X176999Y1288317D01*
X177041Y1287942D01*
X177207Y1287567D01*
G01X153299Y1289113D02*
X155399Y1287313D01*
X153299Y1285113D01*
G01X153199Y1281513D02*
X172399D01*
Y1292713D01*
X153199D01*
Y1281513D01*
X153599D01*
G01X99500Y1282517D02*
X97000D01*
Y1283558D01*
X97125Y1283892D01*
X97292Y1284100D01*
X97625Y1284183D01*
X97958Y1284100D01*
X98167Y1283850D01*
X98292Y1283558D01*
Y1282517D01*
G01Y1283558D02*
X99500Y1284183D01*
G01X97417Y1285658D02*
X97167Y1285908D01*
X97042Y1286200D01*
X97000Y1286533D01*
X97083Y1286950D01*
X97292Y1287242D01*
X97542Y1287325D01*
X97792Y1287283D01*
X98000Y1287117D01*
X98417Y1286283D01*
X98708Y1285908D01*
X99125Y1285658D01*
X99500Y1285575D01*
Y1287325D01*
G01X98458Y1288758D02*
X98167Y1289050D01*
X98000Y1289300D01*
X97917Y1289633D01*
X98000Y1289925D01*
X98167Y1290133D01*
X98417Y1290300D01*
X98708Y1290342D01*
X98958Y1290300D01*
X99208Y1290133D01*
X99417Y1289883D01*
X99500Y1289592D01*
X99417Y1289258D01*
X99167Y1288967D01*
X98792Y1288800D01*
X98375Y1288758D01*
X97833Y1288842D01*
X97542Y1288967D01*
X97250Y1289175D01*
X97042Y1289467D01*
X97000Y1289758D01*
X97083Y1290050D01*
X97292Y1290258D01*
G01X97000Y1292650D02*
X97083Y1292317D01*
X97292Y1292067D01*
X97542Y1291900D01*
X97875Y1291775D01*
X98250Y1291733D01*
X98625Y1291775D01*
X98958Y1291900D01*
X99208Y1292067D01*
X99417Y1292317D01*
X99500Y1292650D01*
X99417Y1292983D01*
X99208Y1293233D01*
X98958Y1293400D01*
X98625Y1293525D01*
X98250Y1293567D01*
X97875Y1293525D01*
X97542Y1293400D01*
X97292Y1293233D01*
X97083Y1292983D01*
X97000Y1292650D01*
G01X127999Y1282113D02*
Y1295113D01*
G01X101999Y1282113D02*
X127999D01*
G01X101999Y1295113D02*
Y1282113D01*
G01X127999Y1295113D02*
X101999D01*
G01X99499Y1250067D02*
X96999D01*
Y1251108D01*
X97124Y1251442D01*
X97291Y1251650D01*
X97624Y1251733D01*
X97957Y1251650D01*
X98166Y1251400D01*
X98291Y1251108D01*
Y1250067D01*
G01Y1251108D02*
X99499Y1251733D01*
G01X97416Y1253208D02*
X97166Y1253458D01*
X97041Y1253750D01*
X96999Y1254083D01*
X97082Y1254500D01*
X97291Y1254792D01*
X97541Y1254875D01*
X97791Y1254833D01*
X97999Y1254667D01*
X98416Y1253833D01*
X98707Y1253458D01*
X99124Y1253208D01*
X99499Y1253125D01*
Y1254875D01*
G01X98457Y1256308D02*
X98166Y1256600D01*
X97999Y1256850D01*
X97916Y1257183D01*
X97999Y1257475D01*
X98166Y1257683D01*
X98416Y1257850D01*
X98707Y1257892D01*
X98957Y1257850D01*
X99207Y1257683D01*
X99416Y1257433D01*
X99499Y1257142D01*
X99416Y1256808D01*
X99166Y1256517D01*
X98791Y1256350D01*
X98374Y1256308D01*
X97832Y1256392D01*
X97541Y1256517D01*
X97249Y1256725D01*
X97041Y1257017D01*
X96999Y1257308D01*
X97082Y1257600D01*
X97291Y1257808D01*
G01X99499Y1260700D02*
X96999D01*
X98791Y1259158D01*
Y1261242D01*
G01X127999Y1248613D02*
Y1261613D01*
G01X101999Y1248613D02*
X127999D01*
G01X101999Y1261613D02*
Y1248613D01*
G01X127999Y1261613D02*
X101999D01*
G01X119516Y1296050D02*
Y1298550D01*
X120557D01*
X120891Y1298425D01*
X121099Y1298258D01*
X121182Y1297925D01*
X121099Y1297592D01*
X120849Y1297383D01*
X120557Y1297258D01*
X119516D01*
G01X120557D02*
X121182Y1296050D01*
G01X122657Y1298133D02*
X122907Y1298383D01*
X123199Y1298508D01*
X123532Y1298550D01*
X123949Y1298467D01*
X124241Y1298258D01*
X124324Y1298008D01*
X124282Y1297758D01*
X124116Y1297550D01*
X123282Y1297133D01*
X122907Y1296842D01*
X122657Y1296425D01*
X122574Y1296050D01*
X124324D01*
G01X125757Y1297092D02*
X126049Y1297383D01*
X126299Y1297550D01*
X126632Y1297633D01*
X126924Y1297550D01*
X127132Y1297383D01*
X127299Y1297133D01*
X127341Y1296842D01*
X127299Y1296592D01*
X127132Y1296342D01*
X126882Y1296133D01*
X126591Y1296050D01*
X126257Y1296133D01*
X125966Y1296383D01*
X125799Y1296758D01*
X125757Y1297175D01*
X125841Y1297717D01*
X125966Y1298008D01*
X126174Y1298300D01*
X126466Y1298508D01*
X126757Y1298550D01*
X127049Y1298467D01*
X127257Y1298258D01*
G01X129649Y1296050D02*
Y1298550D01*
X129149Y1298050D01*
G01Y1296050D02*
X130149D01*
G01X118199Y1296113D02*
Y1300113D01*
X110799D01*
G01X99999Y1295567D02*
X97499D01*
Y1296608D01*
X97624Y1296942D01*
X97791Y1297150D01*
X98124Y1297233D01*
X98457Y1297150D01*
X98666Y1296900D01*
X98791Y1296608D01*
Y1295567D01*
G01Y1296608D02*
X99999Y1297233D01*
G01X97916Y1298708D02*
X97666Y1298958D01*
X97541Y1299250D01*
X97499Y1299583D01*
X97582Y1300000D01*
X97791Y1300292D01*
X98041Y1300375D01*
X98291Y1300333D01*
X98499Y1300167D01*
X98916Y1299333D01*
X99207Y1298958D01*
X99624Y1298708D01*
X99999Y1298625D01*
Y1300375D01*
G01X98957Y1301808D02*
X98666Y1302100D01*
X98499Y1302350D01*
X98416Y1302683D01*
X98499Y1302975D01*
X98666Y1303183D01*
X98916Y1303350D01*
X99207Y1303392D01*
X99457Y1303350D01*
X99707Y1303183D01*
X99916Y1302933D01*
X99999Y1302642D01*
X99916Y1302308D01*
X99666Y1302017D01*
X99291Y1301850D01*
X98874Y1301808D01*
X98332Y1301892D01*
X98041Y1302017D01*
X97749Y1302225D01*
X97541Y1302517D01*
X97499Y1302808D01*
X97582Y1303100D01*
X97791Y1303308D01*
G01X99624Y1304783D02*
X99832Y1305033D01*
X99957Y1305325D01*
X99999Y1305700D01*
X99916Y1306075D01*
X99749Y1306367D01*
X99457Y1306575D01*
X99124Y1306617D01*
X98791Y1306533D01*
X98582Y1306325D01*
X98416Y1306033D01*
X98374Y1305742D01*
X98416Y1305450D01*
X98582Y1305075D01*
X97499Y1305200D01*
Y1306325D01*
G01X125983Y1303500D02*
Y1301708D01*
X126150Y1301333D01*
X126483Y1301083D01*
X126900Y1301000D01*
X127317Y1301083D01*
X127650Y1301333D01*
X127817Y1301708D01*
Y1303500D01*
G01X129083Y1301500D02*
X129333Y1301208D01*
X129667Y1301042D01*
X130042Y1301000D01*
X130375Y1301042D01*
X130708Y1301250D01*
X130917Y1301500D01*
X130958Y1301750D01*
X130875Y1302042D01*
X130583Y1302250D01*
X130292Y1302333D01*
X129917D01*
G01X130292D02*
X130542Y1302458D01*
X130750Y1302667D01*
X130833Y1302917D01*
X130750Y1303167D01*
X130542Y1303375D01*
X130167Y1303500D01*
X129792Y1303458D01*
X129417Y1303292D01*
G01X133600Y1301000D02*
Y1303500D01*
X132058Y1301708D01*
X134142D01*
G01X112499Y1301850D02*
Y1315250D01*
G01X122499Y1301850D02*
X112499D01*
G01X122499Y1315250D02*
Y1301850D01*
G01X150499Y1234413D02*
X148499Y1232413D01*
X146499Y1234413D01*
G01X137250Y1273800D02*
Y1271300D01*
G01X136292Y1273800D02*
X138208D01*
G01X139517Y1271300D02*
Y1273800D01*
X140517D01*
X140850Y1273675D01*
X141100Y1273383D01*
X141183Y1273050D01*
X141100Y1272717D01*
X140892Y1272467D01*
X140517Y1272342D01*
X139517D01*
G01X142533Y1271800D02*
X142783Y1271508D01*
X143117Y1271342D01*
X143492Y1271300D01*
X143825Y1271342D01*
X144158Y1271550D01*
X144367Y1271800D01*
X144408Y1272050D01*
X144325Y1272342D01*
X144033Y1272550D01*
X143742Y1272633D01*
X143367D01*
G01X143742D02*
X143992Y1272758D01*
X144200Y1272967D01*
X144283Y1273217D01*
X144200Y1273467D01*
X143992Y1273675D01*
X143617Y1273800D01*
X143242Y1273758D01*
X142867Y1273592D01*
G01X145758Y1272342D02*
X146050Y1272633D01*
X146300Y1272800D01*
X146633Y1272883D01*
X146925Y1272800D01*
X147133Y1272633D01*
X147300Y1272383D01*
X147342Y1272092D01*
X147300Y1271842D01*
X147133Y1271592D01*
X146883Y1271383D01*
X146592Y1271300D01*
X146258Y1271383D01*
X145967Y1271633D01*
X145800Y1272008D01*
X145758Y1272425D01*
X145842Y1272967D01*
X145967Y1273258D01*
X146175Y1273550D01*
X146467Y1273758D01*
X146758Y1273800D01*
X147050Y1273717D01*
X147258Y1273508D01*
G01X138908Y1248267D02*
X138783Y1248017D01*
X138700Y1247725D01*
Y1247392D01*
X138825Y1247017D01*
X139033Y1246725D01*
X139283Y1246517D01*
X139700Y1246350D01*
X140075Y1246308D01*
X140450Y1246392D01*
X140700Y1246517D01*
X140950Y1246767D01*
X141117Y1247058D01*
X141200Y1247350D01*
Y1247642D01*
X141117Y1247933D01*
X140992Y1248183D01*
X140825Y1248392D01*
G01X139117Y1249658D02*
X138867Y1249908D01*
X138742Y1250200D01*
X138700Y1250533D01*
X138783Y1250950D01*
X138992Y1251242D01*
X139242Y1251325D01*
X139492Y1251283D01*
X139700Y1251117D01*
X140117Y1250283D01*
X140408Y1249908D01*
X140825Y1249658D01*
X141200Y1249575D01*
Y1251325D01*
G01Y1253550D02*
X141158Y1253842D01*
X141033Y1254175D01*
X140825Y1254383D01*
X140533Y1254467D01*
X140242Y1254383D01*
X139992Y1254133D01*
X139867Y1253758D01*
Y1253342D01*
X139783Y1253092D01*
X139575Y1252883D01*
X139283Y1252800D01*
X138992Y1252925D01*
X138783Y1253217D01*
X138700Y1253550D01*
X138783Y1253883D01*
X138992Y1254175D01*
X139283Y1254300D01*
X139575Y1254217D01*
X139783Y1254008D01*
X139867Y1253758D01*
Y1253342D01*
X139992Y1252967D01*
X140242Y1252717D01*
X140533Y1252633D01*
X140825Y1252717D01*
X141033Y1252925D01*
X141158Y1253258D01*
X141200Y1253550D01*
G01Y1256567D02*
X140658Y1256650D01*
X140200Y1256775D01*
X139783Y1256942D01*
X139325Y1257150D01*
X138700Y1257483D01*
Y1255817D01*
G01X128700Y1251100D02*
Y1256600D01*
G01X136700Y1251100D02*
X128700D01*
G01X136700Y1256600D02*
Y1251100D01*
G01Y1268700D02*
Y1263200D01*
G01X128700Y1268700D02*
X136700D01*
G01X128700Y1263200D02*
Y1268700D01*
G01X133499Y1247913D02*
Y1242413D01*
G01X125499Y1247913D02*
X133499D01*
G01X125499Y1242413D02*
Y1247913D01*
G01Y1230313D02*
Y1235813D01*
G01X133499Y1230313D02*
X125499D01*
G01X133499Y1235813D02*
Y1230313D01*
G01X124499Y1247913D02*
Y1242413D01*
G01X116499Y1247913D02*
X124499D01*
G01X116499Y1242413D02*
Y1247913D01*
G01Y1230313D02*
Y1235813D01*
G01X124499Y1230313D02*
X116499D01*
G01X124499Y1235813D02*
Y1230313D01*
G01X115499Y1247913D02*
Y1242413D01*
G01X107499Y1247913D02*
X115499D01*
G01X107499Y1242413D02*
Y1247913D01*
G01Y1230313D02*
Y1235813D01*
G01X115499Y1230313D02*
X107499D01*
G01X115499Y1235813D02*
Y1230313D01*
G01X98208Y1268767D02*
X98083Y1268517D01*
X98000Y1268225D01*
Y1267892D01*
X98125Y1267517D01*
X98333Y1267225D01*
X98583Y1267017D01*
X99000Y1266850D01*
X99375Y1266808D01*
X99750Y1266892D01*
X100000Y1267017D01*
X100250Y1267267D01*
X100417Y1267558D01*
X100500Y1267850D01*
Y1268142D01*
X100417Y1268433D01*
X100292Y1268683D01*
X100125Y1268892D01*
G01X98417Y1270158D02*
X98167Y1270408D01*
X98042Y1270700D01*
X98000Y1271033D01*
X98083Y1271450D01*
X98292Y1271742D01*
X98542Y1271825D01*
X98792Y1271783D01*
X99000Y1271617D01*
X99417Y1270783D01*
X99708Y1270408D01*
X100125Y1270158D01*
X100500Y1270075D01*
Y1271825D01*
G01Y1274050D02*
X100458Y1274342D01*
X100333Y1274675D01*
X100125Y1274883D01*
X99833Y1274967D01*
X99542Y1274883D01*
X99292Y1274633D01*
X99167Y1274258D01*
Y1273842D01*
X99083Y1273592D01*
X98875Y1273383D01*
X98583Y1273300D01*
X98292Y1273425D01*
X98083Y1273717D01*
X98000Y1274050D01*
X98083Y1274383D01*
X98292Y1274675D01*
X98583Y1274800D01*
X98875Y1274717D01*
X99083Y1274508D01*
X99167Y1274258D01*
Y1273842D01*
X99292Y1273467D01*
X99542Y1273217D01*
X99833Y1273133D01*
X100125Y1273217D01*
X100333Y1273425D01*
X100458Y1273758D01*
X100500Y1274050D01*
G01X100125Y1276233D02*
X100333Y1276483D01*
X100458Y1276775D01*
X100500Y1277150D01*
X100417Y1277525D01*
X100250Y1277817D01*
X99958Y1278025D01*
X99625Y1278067D01*
X99292Y1277983D01*
X99083Y1277775D01*
X98917Y1277483D01*
X98875Y1277192D01*
X98917Y1276900D01*
X99083Y1276525D01*
X98000Y1276650D01*
Y1277775D01*
G01X115499Y1280913D02*
Y1275413D01*
G01X107499Y1280913D02*
X115499D01*
G01X107499Y1275413D02*
Y1280913D01*
G01Y1263313D02*
Y1268813D01*
G01X115499Y1263313D02*
X107499D01*
G01X115499Y1268813D02*
Y1263313D01*
G01X101865Y1429550D02*
X111865D01*
G01Y1422550D02*
X101865D01*
G01X106865D02*
Y1429550D01*
G01X101865Y1419117D02*
X111865D01*
Y1415783D01*
X111365Y1414450D01*
X110698Y1413450D01*
X109698Y1412617D01*
X108531Y1411950D01*
X106865Y1411783D01*
X105198Y1411950D01*
X104032Y1412617D01*
X103031Y1413450D01*
X102365Y1414450D01*
X101865Y1415783D01*
Y1419117D01*
G01Y1408517D02*
X111865D01*
Y1405183D01*
X111365Y1403850D01*
X110698Y1402850D01*
X109698Y1402017D01*
X108531Y1401350D01*
X106865Y1401183D01*
X105198Y1401350D01*
X104032Y1402017D01*
X103031Y1402850D01*
X102365Y1403850D01*
X101865Y1405183D01*
Y1408517D01*
G01Y1394250D02*
X111865D01*
X109865Y1396250D01*
G01X101865D02*
Y1392250D01*
G01Y1383650D02*
X111865D01*
X109865Y1385650D01*
G01X101865D02*
Y1381650D01*
G01X97595Y1367244D02*
X97345Y1367369D01*
X97053Y1367452D01*
X96720D01*
X96345Y1367327D01*
X96053Y1367119D01*
X95845Y1366869D01*
X95678Y1366452D01*
X95636Y1366077D01*
X95720Y1365702D01*
X95845Y1365452D01*
X96095Y1365202D01*
X96386Y1365035D01*
X96678Y1364952D01*
X96970D01*
X97261Y1365035D01*
X97511Y1365160D01*
X97720Y1365327D01*
G01X98986Y1367035D02*
X99236Y1367285D01*
X99528Y1367410D01*
X99861Y1367452D01*
X100278Y1367369D01*
X100570Y1367160D01*
X100653Y1366910D01*
X100611Y1366660D01*
X100445Y1366452D01*
X99611Y1366035D01*
X99236Y1365744D01*
X98986Y1365327D01*
X98903Y1364952D01*
X100653D01*
G01X102795D02*
X102878Y1365494D01*
X103003Y1365952D01*
X103170Y1366369D01*
X103378Y1366827D01*
X103711Y1367452D01*
X102045D01*
G01X105270Y1365244D02*
X105561Y1365035D01*
X105895Y1364952D01*
X106228Y1365035D01*
X106520Y1365285D01*
X106728Y1365660D01*
X106811Y1366035D01*
Y1366494D01*
X106728Y1366869D01*
X106520Y1367202D01*
X106270Y1367369D01*
X105978Y1367452D01*
X105645Y1367369D01*
X105395Y1367202D01*
X105228Y1366952D01*
X105145Y1366619D01*
X105228Y1366327D01*
X105436Y1366035D01*
X105686Y1365869D01*
X105978Y1365827D01*
X106311Y1365910D01*
X106561Y1366119D01*
X106811Y1366494D01*
G01X98708Y1319267D02*
X98583Y1319017D01*
X98500Y1318725D01*
Y1318392D01*
X98625Y1318017D01*
X98833Y1317725D01*
X99083Y1317517D01*
X99500Y1317350D01*
X99875Y1317308D01*
X100250Y1317392D01*
X100500Y1317517D01*
X100750Y1317767D01*
X100917Y1318058D01*
X101000Y1318350D01*
Y1318642D01*
X100917Y1318933D01*
X100792Y1319183D01*
X100625Y1319392D01*
G01X98917Y1320658D02*
X98667Y1320908D01*
X98542Y1321200D01*
X98500Y1321533D01*
X98583Y1321950D01*
X98792Y1322242D01*
X99042Y1322325D01*
X99292Y1322283D01*
X99500Y1322117D01*
X99917Y1321283D01*
X100208Y1320908D01*
X100625Y1320658D01*
X101000Y1320575D01*
Y1322325D01*
G01Y1324550D02*
X100958Y1324842D01*
X100833Y1325175D01*
X100625Y1325383D01*
X100333Y1325467D01*
X100042Y1325383D01*
X99792Y1325133D01*
X99667Y1324758D01*
Y1324342D01*
X99583Y1324092D01*
X99375Y1323883D01*
X99083Y1323800D01*
X98792Y1323925D01*
X98583Y1324217D01*
X98500Y1324550D01*
X98583Y1324883D01*
X98792Y1325175D01*
X99083Y1325300D01*
X99375Y1325217D01*
X99583Y1325008D01*
X99667Y1324758D01*
Y1324342D01*
X99792Y1323967D01*
X100042Y1323717D01*
X100333Y1323633D01*
X100625Y1323717D01*
X100833Y1323925D01*
X100958Y1324258D01*
X101000Y1324550D01*
G01Y1327650D02*
X98500D01*
X99000Y1327150D01*
G01X101000D02*
Y1328150D01*
G01X157164Y1371777D02*
Y1369277D01*
X158830D01*
G01X161930D02*
X160264D01*
Y1371777D01*
X161930D01*
G01X161264Y1370569D02*
X160264D01*
G01X163280Y1369277D02*
Y1371777D01*
X164114D01*
X164447Y1371652D01*
X164697Y1371485D01*
X164905Y1371235D01*
X165072Y1370944D01*
X165114Y1370527D01*
X165072Y1370110D01*
X164905Y1369819D01*
X164697Y1369569D01*
X164447Y1369402D01*
X164114Y1369277D01*
X163280D01*
G01X167214D02*
X167297Y1369819D01*
X167422Y1370277D01*
X167589Y1370694D01*
X167797Y1371152D01*
X168130Y1371777D01*
X166464D01*
G01X173023Y1382383D02*
Y1374783D01*
X161623D01*
Y1382383D01*
X173023D01*
G01X153400Y1331500D02*
X153067Y1331542D01*
X152775Y1331708D01*
X152525Y1331958D01*
X152358Y1332250D01*
X152275Y1332583D01*
Y1332917D01*
X152358Y1333250D01*
X152525Y1333542D01*
X152775Y1333792D01*
X153067Y1333958D01*
X153400Y1334000D01*
X153733Y1333958D01*
X154025Y1333792D01*
X154275Y1333542D01*
X154442Y1333250D01*
X154525Y1332917D01*
Y1332583D01*
X154442Y1332250D01*
X154275Y1331958D01*
X154025Y1331708D01*
X153733Y1331542D01*
X153400Y1331500D01*
G01X153733Y1332167D02*
X154233Y1331500D01*
G01X155708Y1332542D02*
X156000Y1332833D01*
X156250Y1333000D01*
X156583Y1333083D01*
X156875Y1333000D01*
X157083Y1332833D01*
X157250Y1332583D01*
X157292Y1332292D01*
X157250Y1332042D01*
X157083Y1331792D01*
X156833Y1331583D01*
X156542Y1331500D01*
X156208Y1331583D01*
X155917Y1331833D01*
X155750Y1332208D01*
X155708Y1332625D01*
X155792Y1333167D01*
X155917Y1333458D01*
X156125Y1333750D01*
X156417Y1333958D01*
X156708Y1334000D01*
X157000Y1333917D01*
X157208Y1333708D01*
G01X159600Y1331500D02*
X159892Y1331542D01*
X160225Y1331667D01*
X160433Y1331875D01*
X160517Y1332167D01*
X160433Y1332458D01*
X160183Y1332708D01*
X159808Y1332833D01*
X159392D01*
X159142Y1332917D01*
X158933Y1333125D01*
X158850Y1333417D01*
X158975Y1333708D01*
X159267Y1333917D01*
X159600Y1334000D01*
X159933Y1333917D01*
X160225Y1333708D01*
X160350Y1333417D01*
X160267Y1333125D01*
X160058Y1332917D01*
X159808Y1332833D01*
X159392D01*
X159017Y1332708D01*
X158767Y1332458D01*
X158683Y1332167D01*
X158767Y1331875D01*
X158975Y1331667D01*
X159308Y1331542D01*
X159600Y1331500D01*
G01X150400Y1321400D02*
Y1332800D01*
G01X137000Y1321400D02*
X150400D01*
G01X137000Y1332800D02*
Y1321400D01*
G01X150400Y1332800D02*
X137000D01*
G01X143826Y1354181D02*
Y1356681D01*
X144867D01*
X145201Y1356556D01*
X145409Y1356389D01*
X145492Y1356056D01*
X145409Y1355723D01*
X145159Y1355514D01*
X144867Y1355389D01*
X143826D01*
G01X144867D02*
X145492Y1354181D01*
G01X146967Y1356264D02*
X147217Y1356514D01*
X147509Y1356639D01*
X147842Y1356681D01*
X148259Y1356598D01*
X148551Y1356389D01*
X148634Y1356139D01*
X148592Y1355889D01*
X148426Y1355681D01*
X147592Y1355264D01*
X147217Y1354973D01*
X146967Y1354556D01*
X146884Y1354181D01*
X148634D01*
G01X149942Y1354556D02*
X150192Y1354348D01*
X150484Y1354223D01*
X150859Y1354181D01*
X151234Y1354264D01*
X151526Y1354431D01*
X151734Y1354723D01*
X151776Y1355056D01*
X151692Y1355389D01*
X151484Y1355598D01*
X151192Y1355764D01*
X150901Y1355806D01*
X150609Y1355764D01*
X150234Y1355598D01*
X150359Y1356681D01*
X151484D01*
G01X154459Y1354181D02*
Y1356681D01*
X152917Y1354889D01*
X155001D01*
G01X117799Y1358050D02*
Y1354050D01*
X125199D01*
G01X138017Y1360000D02*
Y1362500D01*
X139058D01*
X139392Y1362375D01*
X139600Y1362208D01*
X139683Y1361875D01*
X139600Y1361542D01*
X139350Y1361333D01*
X139058Y1361208D01*
X138017D01*
G01X139058D02*
X139683Y1360000D01*
G01X141158Y1362083D02*
X141408Y1362333D01*
X141700Y1362458D01*
X142033Y1362500D01*
X142450Y1362417D01*
X142742Y1362208D01*
X142825Y1361958D01*
X142783Y1361708D01*
X142617Y1361500D01*
X141783Y1361083D01*
X141408Y1360792D01*
X141158Y1360375D01*
X141075Y1360000D01*
X142825D01*
G01X144133Y1360375D02*
X144383Y1360167D01*
X144675Y1360042D01*
X145050Y1360000D01*
X145425Y1360083D01*
X145717Y1360250D01*
X145925Y1360542D01*
X145967Y1360875D01*
X145883Y1361208D01*
X145675Y1361417D01*
X145383Y1361583D01*
X145092Y1361625D01*
X144800Y1361583D01*
X144425Y1361417D01*
X144550Y1362500D01*
X145675D01*
G01X147233Y1360375D02*
X147483Y1360167D01*
X147775Y1360042D01*
X148150Y1360000D01*
X148525Y1360083D01*
X148817Y1360250D01*
X149025Y1360542D01*
X149067Y1360875D01*
X148983Y1361208D01*
X148775Y1361417D01*
X148483Y1361583D01*
X148192Y1361625D01*
X147900Y1361583D01*
X147525Y1361417D01*
X147650Y1362500D01*
X148775D01*
G01X133700Y1359000D02*
Y1363000D01*
X126300D01*
G01X143826Y1350181D02*
Y1352681D01*
X144867D01*
X145201Y1352556D01*
X145409Y1352389D01*
X145492Y1352056D01*
X145409Y1351723D01*
X145159Y1351514D01*
X144867Y1351389D01*
X143826D01*
G01X144867D02*
X145492Y1350181D01*
G01X146967Y1352264D02*
X147217Y1352514D01*
X147509Y1352639D01*
X147842Y1352681D01*
X148259Y1352598D01*
X148551Y1352389D01*
X148634Y1352139D01*
X148592Y1351889D01*
X148426Y1351681D01*
X147592Y1351264D01*
X147217Y1350973D01*
X146967Y1350556D01*
X146884Y1350181D01*
X148634D01*
G01X149942Y1350556D02*
X150192Y1350348D01*
X150484Y1350223D01*
X150859Y1350181D01*
X151234Y1350264D01*
X151526Y1350431D01*
X151734Y1350723D01*
X151776Y1351056D01*
X151692Y1351389D01*
X151484Y1351598D01*
X151192Y1351764D01*
X150901Y1351806D01*
X150609Y1351764D01*
X150234Y1351598D01*
X150359Y1352681D01*
X151484D01*
G01X153167Y1351223D02*
X153459Y1351514D01*
X153709Y1351681D01*
X154042Y1351764D01*
X154334Y1351681D01*
X154542Y1351514D01*
X154709Y1351264D01*
X154751Y1350973D01*
X154709Y1350723D01*
X154542Y1350473D01*
X154292Y1350264D01*
X154001Y1350181D01*
X153667Y1350264D01*
X153376Y1350514D01*
X153209Y1350889D01*
X153167Y1351306D01*
X153251Y1351848D01*
X153376Y1352139D01*
X153584Y1352431D01*
X153876Y1352639D01*
X154167Y1352681D01*
X154459Y1352598D01*
X154667Y1352389D01*
G01X117799Y1354050D02*
Y1350050D01*
X125199D01*
G01X138017Y1364500D02*
Y1367000D01*
X139058D01*
X139392Y1366875D01*
X139600Y1366708D01*
X139683Y1366375D01*
X139600Y1366042D01*
X139350Y1365833D01*
X139058Y1365708D01*
X138017D01*
G01X139058D02*
X139683Y1364500D01*
G01X141158Y1366583D02*
X141408Y1366833D01*
X141700Y1366958D01*
X142033Y1367000D01*
X142450Y1366917D01*
X142742Y1366708D01*
X142825Y1366458D01*
X142783Y1366208D01*
X142617Y1366000D01*
X141783Y1365583D01*
X141408Y1365292D01*
X141158Y1364875D01*
X141075Y1364500D01*
X142825D01*
G01X144133Y1364875D02*
X144383Y1364667D01*
X144675Y1364542D01*
X145050Y1364500D01*
X145425Y1364583D01*
X145717Y1364750D01*
X145925Y1365042D01*
X145967Y1365375D01*
X145883Y1365708D01*
X145675Y1365917D01*
X145383Y1366083D01*
X145092Y1366125D01*
X144800Y1366083D01*
X144425Y1365917D01*
X144550Y1367000D01*
X145675D01*
G01X148067Y1364500D02*
X148150Y1365042D01*
X148275Y1365500D01*
X148442Y1365917D01*
X148650Y1366375D01*
X148983Y1367000D01*
X147317D01*
G01X126300D02*
Y1363000D01*
X133700D01*
G01X116000Y1338517D02*
X113500D01*
Y1339558D01*
X113625Y1339892D01*
X113792Y1340100D01*
X114125Y1340183D01*
X114458Y1340100D01*
X114667Y1339850D01*
X114792Y1339558D01*
Y1338517D01*
G01Y1339558D02*
X116000Y1340183D01*
G01X113917Y1341658D02*
X113667Y1341908D01*
X113542Y1342200D01*
X113500Y1342533D01*
X113583Y1342950D01*
X113792Y1343242D01*
X114042Y1343325D01*
X114292Y1343283D01*
X114500Y1343117D01*
X114917Y1342283D01*
X115208Y1341908D01*
X115625Y1341658D01*
X116000Y1341575D01*
Y1343325D01*
G01X115625Y1344633D02*
X115833Y1344883D01*
X115958Y1345175D01*
X116000Y1345550D01*
X115917Y1345925D01*
X115750Y1346217D01*
X115458Y1346425D01*
X115125Y1346467D01*
X114792Y1346383D01*
X114583Y1346175D01*
X114417Y1345883D01*
X114375Y1345592D01*
X114417Y1345300D01*
X114583Y1344925D01*
X113500Y1345050D01*
Y1346175D01*
G01X116000Y1348650D02*
X115958Y1348942D01*
X115833Y1349275D01*
X115625Y1349483D01*
X115333Y1349567D01*
X115042Y1349483D01*
X114792Y1349233D01*
X114667Y1348858D01*
Y1348442D01*
X114583Y1348192D01*
X114375Y1347983D01*
X114083Y1347900D01*
X113792Y1348025D01*
X113583Y1348317D01*
X113500Y1348650D01*
X113583Y1348983D01*
X113792Y1349275D01*
X114083Y1349400D01*
X114375Y1349317D01*
X114583Y1349108D01*
X114667Y1348858D01*
Y1348442D01*
X114792Y1348067D01*
X115042Y1347817D01*
X115333Y1347733D01*
X115625Y1347817D01*
X115833Y1348025D01*
X115958Y1348358D01*
X116000Y1348650D01*
G01X118299Y1345050D02*
Y1341050D01*
X125699D01*
G01X133517Y1316000D02*
Y1318500D01*
X134558D01*
X134892Y1318375D01*
X135100Y1318208D01*
X135183Y1317875D01*
X135100Y1317542D01*
X134850Y1317333D01*
X134558Y1317208D01*
X133517D01*
G01X134558D02*
X135183Y1316000D01*
G01X136533Y1316500D02*
X136783Y1316208D01*
X137117Y1316042D01*
X137492Y1316000D01*
X137825Y1316042D01*
X138158Y1316250D01*
X138367Y1316500D01*
X138408Y1316750D01*
X138325Y1317042D01*
X138033Y1317250D01*
X137742Y1317333D01*
X137367D01*
G01X137742D02*
X137992Y1317458D01*
X138200Y1317667D01*
X138283Y1317917D01*
X138200Y1318167D01*
X137992Y1318375D01*
X137617Y1318500D01*
X137242Y1318458D01*
X136867Y1318292D01*
G01X139842Y1316292D02*
X140133Y1316083D01*
X140467Y1316000D01*
X140800Y1316083D01*
X141092Y1316333D01*
X141300Y1316708D01*
X141383Y1317083D01*
Y1317542D01*
X141300Y1317917D01*
X141092Y1318250D01*
X140842Y1318417D01*
X140550Y1318500D01*
X140217Y1318417D01*
X139967Y1318250D01*
X139800Y1318000D01*
X139717Y1317667D01*
X139800Y1317375D01*
X140008Y1317083D01*
X140258Y1316917D01*
X140550Y1316875D01*
X140883Y1316958D01*
X141133Y1317167D01*
X141383Y1317542D01*
G01X143650Y1316000D02*
X143942Y1316042D01*
X144275Y1316167D01*
X144483Y1316375D01*
X144567Y1316667D01*
X144483Y1316958D01*
X144233Y1317208D01*
X143858Y1317333D01*
X143442D01*
X143192Y1317417D01*
X142983Y1317625D01*
X142900Y1317917D01*
X143025Y1318208D01*
X143317Y1318417D01*
X143650Y1318500D01*
X143983Y1318417D01*
X144275Y1318208D01*
X144400Y1317917D01*
X144317Y1317625D01*
X144108Y1317417D01*
X143858Y1317333D01*
X143442D01*
X143067Y1317208D01*
X142817Y1316958D01*
X142733Y1316667D01*
X142817Y1316375D01*
X143025Y1316167D01*
X143358Y1316042D01*
X143650Y1316000D01*
G01X122600Y1321900D02*
Y1317900D01*
X130000D01*
G01X145517Y1335500D02*
Y1338000D01*
X146558D01*
X146892Y1337875D01*
X147100Y1337708D01*
X147183Y1337375D01*
X147100Y1337042D01*
X146850Y1336833D01*
X146558Y1336708D01*
X145517D01*
G01X146558D02*
X147183Y1335500D01*
G01X148533Y1336000D02*
X148783Y1335708D01*
X149117Y1335542D01*
X149492Y1335500D01*
X149825Y1335542D01*
X150158Y1335750D01*
X150367Y1336000D01*
X150408Y1336250D01*
X150325Y1336542D01*
X150033Y1336750D01*
X149742Y1336833D01*
X149367D01*
G01X149742D02*
X149992Y1336958D01*
X150200Y1337167D01*
X150283Y1337417D01*
X150200Y1337667D01*
X149992Y1337875D01*
X149617Y1338000D01*
X149242Y1337958D01*
X148867Y1337792D01*
G01X151842Y1335792D02*
X152133Y1335583D01*
X152467Y1335500D01*
X152800Y1335583D01*
X153092Y1335833D01*
X153300Y1336208D01*
X153383Y1336583D01*
Y1337042D01*
X153300Y1337417D01*
X153092Y1337750D01*
X152842Y1337917D01*
X152550Y1338000D01*
X152217Y1337917D01*
X151967Y1337750D01*
X151800Y1337500D01*
X151717Y1337167D01*
X151800Y1336875D01*
X152008Y1336583D01*
X152258Y1336417D01*
X152550Y1336375D01*
X152883Y1336458D01*
X153133Y1336667D01*
X153383Y1337042D01*
G01X154942Y1335792D02*
X155233Y1335583D01*
X155567Y1335500D01*
X155900Y1335583D01*
X156192Y1335833D01*
X156400Y1336208D01*
X156483Y1336583D01*
Y1337042D01*
X156400Y1337417D01*
X156192Y1337750D01*
X155942Y1337917D01*
X155650Y1338000D01*
X155317Y1337917D01*
X155067Y1337750D01*
X154900Y1337500D01*
X154817Y1337167D01*
X154900Y1336875D01*
X155108Y1336583D01*
X155358Y1336417D01*
X155650Y1336375D01*
X155983Y1336458D01*
X156233Y1336667D01*
X156483Y1337042D01*
G01X144100Y1333800D02*
Y1337800D01*
X136700D01*
G01X106213Y1316383D02*
X103713D01*
Y1317424D01*
X103838Y1317758D01*
X104005Y1317966D01*
X104338Y1318049D01*
X104671Y1317966D01*
X104880Y1317716D01*
X105005Y1317424D01*
Y1316383D01*
G01Y1317424D02*
X106213Y1318049D01*
G01Y1320816D02*
X103713D01*
X105505Y1319274D01*
Y1321358D01*
G01X105171Y1322624D02*
X104880Y1322916D01*
X104713Y1323166D01*
X104630Y1323499D01*
X104713Y1323791D01*
X104880Y1323999D01*
X105130Y1324166D01*
X105421Y1324208D01*
X105671Y1324166D01*
X105921Y1323999D01*
X106130Y1323749D01*
X106213Y1323458D01*
X106130Y1323124D01*
X105880Y1322833D01*
X105505Y1322666D01*
X105088Y1322624D01*
X104546Y1322708D01*
X104255Y1322833D01*
X103963Y1323041D01*
X103755Y1323333D01*
X103713Y1323624D01*
X103796Y1323916D01*
X104005Y1324124D01*
G01X106213Y1327016D02*
X103713D01*
X105505Y1325474D01*
Y1327558D01*
G01X118499Y1326813D02*
X114499D01*
Y1319413D01*
G01X110213Y1316383D02*
X107713D01*
Y1317424D01*
X107838Y1317758D01*
X108005Y1317966D01*
X108338Y1318049D01*
X108671Y1317966D01*
X108880Y1317716D01*
X109005Y1317424D01*
Y1316383D01*
G01Y1317424D02*
X110213Y1318049D01*
G01Y1320816D02*
X107713D01*
X109505Y1319274D01*
Y1321358D01*
G01X109171Y1322624D02*
X108880Y1322916D01*
X108713Y1323166D01*
X108630Y1323499D01*
X108713Y1323791D01*
X108880Y1323999D01*
X109130Y1324166D01*
X109421Y1324208D01*
X109671Y1324166D01*
X109921Y1323999D01*
X110130Y1323749D01*
X110213Y1323458D01*
X110130Y1323124D01*
X109880Y1322833D01*
X109505Y1322666D01*
X109088Y1322624D01*
X108546Y1322708D01*
X108255Y1322833D01*
X107963Y1323041D01*
X107755Y1323333D01*
X107713Y1323624D01*
X107796Y1323916D01*
X108005Y1324124D01*
G01X109838Y1325599D02*
X110046Y1325849D01*
X110171Y1326141D01*
X110213Y1326516D01*
X110130Y1326891D01*
X109963Y1327183D01*
X109671Y1327391D01*
X109338Y1327433D01*
X109005Y1327349D01*
X108796Y1327141D01*
X108630Y1326849D01*
X108588Y1326558D01*
X108630Y1326266D01*
X108796Y1325891D01*
X107713Y1326016D01*
Y1327141D01*
G01X122507Y1326896D02*
X118507D01*
Y1319496D01*
G01X140517Y1340000D02*
Y1342500D01*
X141558D01*
X141892Y1342375D01*
X142100Y1342208D01*
X142183Y1341875D01*
X142100Y1341542D01*
X141850Y1341333D01*
X141558Y1341208D01*
X140517D01*
G01X141558D02*
X142183Y1340000D01*
G01X143533Y1340375D02*
X143783Y1340167D01*
X144075Y1340042D01*
X144450Y1340000D01*
X144825Y1340083D01*
X145117Y1340250D01*
X145325Y1340542D01*
X145367Y1340875D01*
X145283Y1341208D01*
X145075Y1341417D01*
X144783Y1341583D01*
X144492Y1341625D01*
X144200Y1341583D01*
X143825Y1341417D01*
X143950Y1342500D01*
X145075D01*
G01X147550D02*
X147217Y1342417D01*
X146967Y1342208D01*
X146800Y1341958D01*
X146675Y1341625D01*
X146633Y1341250D01*
X146675Y1340875D01*
X146800Y1340542D01*
X146967Y1340292D01*
X147217Y1340083D01*
X147550Y1340000D01*
X147883Y1340083D01*
X148133Y1340292D01*
X148300Y1340542D01*
X148425Y1340875D01*
X148467Y1341250D01*
X148425Y1341625D01*
X148300Y1341958D01*
X148133Y1342208D01*
X147883Y1342417D01*
X147550Y1342500D01*
G01X150650Y1340000D02*
Y1342500D01*
X150150Y1342000D01*
G01Y1340000D02*
X151150D01*
G01X133199Y1340050D02*
Y1344050D01*
X125799D01*
G01X112499Y1315250D02*
X122499D01*
G01X159000Y1350400D02*
X158958Y1350067D01*
X158792Y1349775D01*
X158542Y1349525D01*
X158250Y1349358D01*
X157917Y1349275D01*
X157583D01*
X157250Y1349358D01*
X156958Y1349525D01*
X156708Y1349775D01*
X156542Y1350067D01*
X156500Y1350400D01*
X156542Y1350733D01*
X156708Y1351025D01*
X156958Y1351275D01*
X157250Y1351442D01*
X157583Y1351525D01*
X157917D01*
X158250Y1351442D01*
X158542Y1351275D01*
X158792Y1351025D01*
X158958Y1350733D01*
X159000Y1350400D01*
G01X158333Y1350733D02*
X159000Y1351233D01*
G01Y1354000D02*
X156500D01*
X158292Y1352458D01*
Y1354542D01*
G01X158625Y1355683D02*
X158833Y1355933D01*
X158958Y1356225D01*
X159000Y1356600D01*
X158917Y1356975D01*
X158750Y1357267D01*
X158458Y1357475D01*
X158125Y1357517D01*
X157792Y1357433D01*
X157583Y1357225D01*
X157417Y1356933D01*
X157375Y1356642D01*
X157417Y1356350D01*
X157583Y1355975D01*
X156500Y1356100D01*
Y1357225D01*
G01X126499Y1345050D02*
X140499D01*
G01X126499Y1358050D02*
Y1345050D01*
G01X140499Y1358050D02*
X126499D01*
G01X140499Y1345050D02*
Y1358050D01*
G01X121500Y1329900D02*
X121458Y1329567D01*
X121292Y1329275D01*
X121042Y1329025D01*
X120750Y1328858D01*
X120417Y1328775D01*
X120083D01*
X119750Y1328858D01*
X119458Y1329025D01*
X119208Y1329275D01*
X119042Y1329567D01*
X119000Y1329900D01*
X119042Y1330233D01*
X119208Y1330525D01*
X119458Y1330775D01*
X119750Y1330942D01*
X120083Y1331025D01*
X120417D01*
X120750Y1330942D01*
X121042Y1330775D01*
X121292Y1330525D01*
X121458Y1330233D01*
X121500Y1329900D01*
G01X120833Y1330233D02*
X121500Y1330733D01*
G01X120458Y1332208D02*
X120167Y1332500D01*
X120000Y1332750D01*
X119917Y1333083D01*
X120000Y1333375D01*
X120167Y1333583D01*
X120417Y1333750D01*
X120708Y1333792D01*
X120958Y1333750D01*
X121208Y1333583D01*
X121417Y1333333D01*
X121500Y1333042D01*
X121417Y1332708D01*
X121167Y1332417D01*
X120792Y1332250D01*
X120375Y1332208D01*
X119833Y1332292D01*
X119542Y1332417D01*
X119250Y1332625D01*
X119042Y1332917D01*
X119000Y1333208D01*
X119083Y1333500D01*
X119292Y1333708D01*
G01X121208Y1335392D02*
X121417Y1335683D01*
X121500Y1336017D01*
X121417Y1336350D01*
X121167Y1336642D01*
X120792Y1336850D01*
X120417Y1336933D01*
X119958D01*
X119583Y1336850D01*
X119250Y1336642D01*
X119083Y1336392D01*
X119000Y1336100D01*
X119083Y1335767D01*
X119250Y1335517D01*
X119500Y1335350D01*
X119833Y1335267D01*
X120125Y1335350D01*
X120417Y1335558D01*
X120583Y1335808D01*
X120625Y1336100D01*
X120542Y1336433D01*
X120333Y1336683D01*
X119958Y1336933D01*
G01X123100Y1337500D02*
Y1323500D01*
G01X136100Y1337500D02*
X123100D01*
G01X136100Y1323500D02*
Y1337500D01*
G01X123100Y1323500D02*
X136100D01*
G01X144623Y1402353D02*
Y1563553D01*
X158223D01*
Y1576503D01*
X176423D01*
Y1563553D01*
X205323D01*
Y1553203D01*
X198623D01*
Y1412703D01*
X205323D01*
Y1402353D01*
X176423D01*
Y1389403D01*
X158223D01*
Y1402353D01*
X144623D01*
G01X114657Y1442533D02*
X114407Y1442658D01*
X114115Y1442741D01*
X113782D01*
X113407Y1442616D01*
X113115Y1442408D01*
X112907Y1442158D01*
X112740Y1441741D01*
X112698Y1441366D01*
X112782Y1440991D01*
X112907Y1440741D01*
X113157Y1440491D01*
X113448Y1440324D01*
X113740Y1440241D01*
X114032D01*
X114323Y1440324D01*
X114573Y1440449D01*
X114782Y1440616D01*
G01X116840Y1440241D02*
Y1442741D01*
X116340Y1442241D01*
G01Y1440241D02*
X117340D01*
G01X119232Y1440533D02*
X119523Y1440324D01*
X119857Y1440241D01*
X120190Y1440324D01*
X120482Y1440574D01*
X120690Y1440949D01*
X120773Y1441324D01*
Y1441783D01*
X120690Y1442158D01*
X120482Y1442491D01*
X120232Y1442658D01*
X119940Y1442741D01*
X119607Y1442658D01*
X119357Y1442491D01*
X119190Y1442241D01*
X119107Y1441908D01*
X119190Y1441616D01*
X119398Y1441324D01*
X119648Y1441158D01*
X119940Y1441116D01*
X120273Y1441199D01*
X120523Y1441408D01*
X120773Y1441783D01*
G01X123040Y1440241D02*
X123332Y1440283D01*
X123665Y1440408D01*
X123873Y1440616D01*
X123957Y1440908D01*
X123873Y1441199D01*
X123623Y1441449D01*
X123248Y1441574D01*
X122832D01*
X122582Y1441658D01*
X122373Y1441866D01*
X122290Y1442158D01*
X122415Y1442449D01*
X122707Y1442658D01*
X123040Y1442741D01*
X123373Y1442658D01*
X123665Y1442449D01*
X123790Y1442158D01*
X123707Y1441866D01*
X123498Y1441658D01*
X123248Y1441574D01*
X122832D01*
X122457Y1441449D01*
X122207Y1441199D01*
X122123Y1440908D01*
X122207Y1440616D01*
X122415Y1440408D01*
X122748Y1440283D01*
X123040Y1440241D01*
G01X114766Y1446342D02*
X114516Y1446467D01*
X114224Y1446550D01*
X113891D01*
X113516Y1446425D01*
X113224Y1446217D01*
X113016Y1445967D01*
X112849Y1445550D01*
X112807Y1445175D01*
X112891Y1444800D01*
X113016Y1444550D01*
X113266Y1444300D01*
X113557Y1444133D01*
X113849Y1444050D01*
X114141D01*
X114432Y1444133D01*
X114682Y1444258D01*
X114891Y1444425D01*
G01X116949Y1444050D02*
Y1446550D01*
X116449Y1446050D01*
G01Y1444050D02*
X117449D01*
G01X119341Y1444342D02*
X119632Y1444133D01*
X119966Y1444050D01*
X120299Y1444133D01*
X120591Y1444383D01*
X120799Y1444758D01*
X120882Y1445133D01*
Y1445592D01*
X120799Y1445967D01*
X120591Y1446300D01*
X120341Y1446467D01*
X120049Y1446550D01*
X119716Y1446467D01*
X119466Y1446300D01*
X119299Y1446050D01*
X119216Y1445717D01*
X119299Y1445425D01*
X119507Y1445133D01*
X119757Y1444967D01*
X120049Y1444925D01*
X120382Y1445008D01*
X120632Y1445217D01*
X120882Y1445592D01*
G01X122441Y1444342D02*
X122732Y1444133D01*
X123066Y1444050D01*
X123399Y1444133D01*
X123691Y1444383D01*
X123899Y1444758D01*
X123982Y1445133D01*
Y1445592D01*
X123899Y1445967D01*
X123691Y1446300D01*
X123441Y1446467D01*
X123149Y1446550D01*
X122816Y1446467D01*
X122566Y1446300D01*
X122399Y1446050D01*
X122316Y1445717D01*
X122399Y1445425D01*
X122607Y1445133D01*
X122857Y1444967D01*
X123149Y1444925D01*
X123482Y1445008D01*
X123732Y1445217D01*
X123982Y1445592D01*
G01X127657Y1457333D02*
X127407Y1457458D01*
X127115Y1457541D01*
X126782D01*
X126407Y1457416D01*
X126115Y1457208D01*
X125907Y1456958D01*
X125740Y1456541D01*
X125698Y1456166D01*
X125782Y1455791D01*
X125907Y1455541D01*
X126157Y1455291D01*
X126448Y1455124D01*
X126740Y1455041D01*
X127032D01*
X127323Y1455124D01*
X127573Y1455249D01*
X127782Y1455416D01*
G01X129048Y1457124D02*
X129298Y1457374D01*
X129590Y1457499D01*
X129923Y1457541D01*
X130340Y1457458D01*
X130632Y1457249D01*
X130715Y1456999D01*
X130673Y1456749D01*
X130507Y1456541D01*
X129673Y1456124D01*
X129298Y1455833D01*
X129048Y1455416D01*
X128965Y1455041D01*
X130715D01*
G01X132940Y1457541D02*
X132607Y1457458D01*
X132357Y1457249D01*
X132190Y1456999D01*
X132065Y1456666D01*
X132023Y1456291D01*
X132065Y1455916D01*
X132190Y1455583D01*
X132357Y1455333D01*
X132607Y1455124D01*
X132940Y1455041D01*
X133273Y1455124D01*
X133523Y1455333D01*
X133690Y1455583D01*
X133815Y1455916D01*
X133857Y1456291D01*
X133815Y1456666D01*
X133690Y1456999D01*
X133523Y1457249D01*
X133273Y1457458D01*
X132940Y1457541D01*
G01X136040D02*
X135707Y1457458D01*
X135457Y1457249D01*
X135290Y1456999D01*
X135165Y1456666D01*
X135123Y1456291D01*
X135165Y1455916D01*
X135290Y1455583D01*
X135457Y1455333D01*
X135707Y1455124D01*
X136040Y1455041D01*
X136373Y1455124D01*
X136623Y1455333D01*
X136790Y1455583D01*
X136915Y1455916D01*
X136957Y1456291D01*
X136915Y1456666D01*
X136790Y1456999D01*
X136623Y1457249D01*
X136373Y1457458D01*
X136040Y1457541D01*
G01X127766Y1461142D02*
X127516Y1461267D01*
X127224Y1461350D01*
X126891D01*
X126516Y1461225D01*
X126224Y1461017D01*
X126016Y1460767D01*
X125849Y1460350D01*
X125807Y1459975D01*
X125891Y1459600D01*
X126016Y1459350D01*
X126266Y1459100D01*
X126557Y1458933D01*
X126849Y1458850D01*
X127141D01*
X127432Y1458933D01*
X127682Y1459058D01*
X127891Y1459225D01*
G01X129157Y1460933D02*
X129407Y1461183D01*
X129699Y1461308D01*
X130032Y1461350D01*
X130449Y1461267D01*
X130741Y1461058D01*
X130824Y1460808D01*
X130782Y1460558D01*
X130616Y1460350D01*
X129782Y1459933D01*
X129407Y1459642D01*
X129157Y1459225D01*
X129074Y1458850D01*
X130824D01*
G01X133049Y1461350D02*
X132716Y1461267D01*
X132466Y1461058D01*
X132299Y1460808D01*
X132174Y1460475D01*
X132132Y1460100D01*
X132174Y1459725D01*
X132299Y1459392D01*
X132466Y1459142D01*
X132716Y1458933D01*
X133049Y1458850D01*
X133382Y1458933D01*
X133632Y1459142D01*
X133799Y1459392D01*
X133924Y1459725D01*
X133966Y1460100D01*
X133924Y1460475D01*
X133799Y1460808D01*
X133632Y1461058D01*
X133382Y1461267D01*
X133049Y1461350D01*
G01X136149Y1458850D02*
Y1461350D01*
X135649Y1460850D01*
G01Y1458850D02*
X136649D01*
G01X104999Y1452317D02*
X102499D01*
Y1453358D01*
X102624Y1453692D01*
X102791Y1453900D01*
X103124Y1453983D01*
X103457Y1453900D01*
X103666Y1453650D01*
X103791Y1453358D01*
Y1452317D01*
G01Y1453358D02*
X104999Y1453983D01*
G01X104499Y1455333D02*
X104791Y1455583D01*
X104957Y1455917D01*
X104999Y1456292D01*
X104957Y1456625D01*
X104749Y1456958D01*
X104499Y1457167D01*
X104249Y1457208D01*
X103957Y1457125D01*
X103749Y1456833D01*
X103666Y1456542D01*
Y1456167D01*
G01Y1456542D02*
X103541Y1456792D01*
X103332Y1457000D01*
X103082Y1457083D01*
X102832Y1457000D01*
X102624Y1456792D01*
X102499Y1456417D01*
X102541Y1456042D01*
X102707Y1455667D01*
G01X104999Y1459350D02*
X102499D01*
X102999Y1458850D01*
G01X104999D02*
Y1459850D01*
G01Y1462450D02*
X102499D01*
X102999Y1461950D01*
G01X104999D02*
Y1462950D01*
G01X101999Y1466600D02*
X105999D01*
Y1474000D01*
G01X112499Y1452317D02*
X109999D01*
Y1453358D01*
X110124Y1453692D01*
X110291Y1453900D01*
X110624Y1453983D01*
X110957Y1453900D01*
X111166Y1453650D01*
X111291Y1453358D01*
Y1452317D01*
G01Y1453358D02*
X112499Y1453983D01*
G01X111999Y1455333D02*
X112291Y1455583D01*
X112457Y1455917D01*
X112499Y1456292D01*
X112457Y1456625D01*
X112249Y1456958D01*
X111999Y1457167D01*
X111749Y1457208D01*
X111457Y1457125D01*
X111249Y1456833D01*
X111166Y1456542D01*
Y1456167D01*
G01Y1456542D02*
X111041Y1456792D01*
X110832Y1457000D01*
X110582Y1457083D01*
X110332Y1457000D01*
X110124Y1456792D01*
X109999Y1456417D01*
X110041Y1456042D01*
X110207Y1455667D01*
G01X112499Y1459350D02*
X109999D01*
X110499Y1458850D01*
G01X112499D02*
Y1459850D01*
G01X110416Y1461658D02*
X110166Y1461908D01*
X110041Y1462200D01*
X109999Y1462533D01*
X110082Y1462950D01*
X110291Y1463242D01*
X110541Y1463325D01*
X110791Y1463283D01*
X110999Y1463117D01*
X111416Y1462283D01*
X111707Y1461908D01*
X112124Y1461658D01*
X112499Y1461575D01*
Y1463325D01*
G01X109499Y1466600D02*
X113499D01*
Y1474000D01*
G01X116599Y1452267D02*
X114099D01*
Y1453308D01*
X114224Y1453642D01*
X114391Y1453850D01*
X114724Y1453933D01*
X115057Y1453850D01*
X115266Y1453600D01*
X115391Y1453308D01*
Y1452267D01*
G01Y1453308D02*
X116599Y1453933D01*
G01X116099Y1455283D02*
X116391Y1455533D01*
X116557Y1455867D01*
X116599Y1456242D01*
X116557Y1456575D01*
X116349Y1456908D01*
X116099Y1457117D01*
X115849Y1457158D01*
X115557Y1457075D01*
X115349Y1456783D01*
X115266Y1456492D01*
Y1456117D01*
G01Y1456492D02*
X115141Y1456742D01*
X114932Y1456950D01*
X114682Y1457033D01*
X114432Y1456950D01*
X114224Y1456742D01*
X114099Y1456367D01*
X114141Y1455992D01*
X114307Y1455617D01*
G01X116599Y1459300D02*
X114099D01*
X114599Y1458800D01*
G01X116599D02*
Y1459800D01*
G01X116099Y1461483D02*
X116391Y1461733D01*
X116557Y1462067D01*
X116599Y1462442D01*
X116557Y1462775D01*
X116349Y1463108D01*
X116099Y1463317D01*
X115849Y1463358D01*
X115557Y1463275D01*
X115349Y1462983D01*
X115266Y1462692D01*
Y1462317D01*
G01Y1462692D02*
X115141Y1462942D01*
X114932Y1463150D01*
X114682Y1463233D01*
X114432Y1463150D01*
X114224Y1462942D01*
X114099Y1462567D01*
X114141Y1462192D01*
X114307Y1461817D01*
G01X113599Y1466550D02*
X117599D01*
Y1473950D01*
G01X105949Y1474050D02*
Y1478050D01*
X98549D01*
G01X113449Y1474050D02*
Y1478050D01*
X106049D01*
G01X123516Y1474850D02*
Y1477350D01*
X124557D01*
X124891Y1477225D01*
X125099Y1477058D01*
X125182Y1476725D01*
X125099Y1476392D01*
X124849Y1476183D01*
X124557Y1476058D01*
X123516D01*
G01X124557D02*
X125182Y1474850D01*
G01X126532Y1475350D02*
X126782Y1475058D01*
X127116Y1474892D01*
X127491Y1474850D01*
X127824Y1474892D01*
X128157Y1475100D01*
X128366Y1475350D01*
X128407Y1475600D01*
X128324Y1475892D01*
X128032Y1476100D01*
X127741Y1476183D01*
X127366D01*
G01X127741D02*
X127991Y1476308D01*
X128199Y1476517D01*
X128282Y1476767D01*
X128199Y1477017D01*
X127991Y1477225D01*
X127616Y1477350D01*
X127241Y1477308D01*
X126866Y1477142D01*
G01X129757Y1476933D02*
X130007Y1477183D01*
X130299Y1477308D01*
X130632Y1477350D01*
X131049Y1477267D01*
X131341Y1477058D01*
X131424Y1476808D01*
X131382Y1476558D01*
X131216Y1476350D01*
X130382Y1475933D01*
X130007Y1475642D01*
X129757Y1475225D01*
X129674Y1474850D01*
X131424D01*
G01X132857Y1476933D02*
X133107Y1477183D01*
X133399Y1477308D01*
X133732Y1477350D01*
X134149Y1477267D01*
X134441Y1477058D01*
X134524Y1476808D01*
X134482Y1476558D01*
X134316Y1476350D01*
X133482Y1475933D01*
X133107Y1475642D01*
X132857Y1475225D01*
X132774Y1474850D01*
X134524D01*
G01X113549Y1478050D02*
Y1474050D01*
X120949D01*
G01X126207Y1485217D02*
X126082Y1484967D01*
X125999Y1484675D01*
Y1484342D01*
X126124Y1483967D01*
X126332Y1483675D01*
X126582Y1483467D01*
X126999Y1483300D01*
X127374Y1483258D01*
X127749Y1483342D01*
X127999Y1483467D01*
X128249Y1483717D01*
X128416Y1484008D01*
X128499Y1484300D01*
Y1484592D01*
X128416Y1484883D01*
X128291Y1485133D01*
X128124Y1485342D01*
G01X127999Y1486483D02*
X128291Y1486733D01*
X128457Y1487067D01*
X128499Y1487442D01*
X128457Y1487775D01*
X128249Y1488108D01*
X127999Y1488317D01*
X127749Y1488358D01*
X127457Y1488275D01*
X127249Y1487983D01*
X127166Y1487692D01*
Y1487317D01*
G01Y1487692D02*
X127041Y1487942D01*
X126832Y1488150D01*
X126582Y1488233D01*
X126332Y1488150D01*
X126124Y1487942D01*
X125999Y1487567D01*
X126041Y1487192D01*
X126207Y1486817D01*
G01X128499Y1491000D02*
X125999D01*
X127791Y1489458D01*
Y1491542D01*
G01X125999Y1493600D02*
X126082Y1493267D01*
X126291Y1493017D01*
X126541Y1492850D01*
X126874Y1492725D01*
X127249Y1492683D01*
X127624Y1492725D01*
X127957Y1492850D01*
X128207Y1493017D01*
X128416Y1493267D01*
X128499Y1493600D01*
X128416Y1493933D01*
X128207Y1494183D01*
X127957Y1494350D01*
X127624Y1494475D01*
X127249Y1494517D01*
X126874Y1494475D01*
X126541Y1494350D01*
X126291Y1494183D01*
X126082Y1493933D01*
X125999Y1493600D01*
G01X131449Y1508367D02*
X128949D01*
Y1509408D01*
X129074Y1509742D01*
X129241Y1509950D01*
X129574Y1510033D01*
X129907Y1509950D01*
X130116Y1509700D01*
X130241Y1509408D01*
Y1508367D01*
G01Y1509408D02*
X131449Y1510033D01*
G01X130949Y1511383D02*
X131241Y1511633D01*
X131407Y1511967D01*
X131449Y1512342D01*
X131407Y1512675D01*
X131199Y1513008D01*
X130949Y1513217D01*
X130699Y1513258D01*
X130407Y1513175D01*
X130199Y1512883D01*
X130116Y1512592D01*
Y1512217D01*
G01Y1512592D02*
X129991Y1512842D01*
X129782Y1513050D01*
X129532Y1513133D01*
X129282Y1513050D01*
X129074Y1512842D01*
X128949Y1512467D01*
X128991Y1512092D01*
X129157Y1511717D01*
G01X131449Y1515400D02*
X128949D01*
X129449Y1514900D01*
G01X131449D02*
Y1515900D01*
G01X128949Y1518500D02*
X129032Y1518167D01*
X129241Y1517917D01*
X129491Y1517750D01*
X129824Y1517625D01*
X130199Y1517583D01*
X130574Y1517625D01*
X130907Y1517750D01*
X131157Y1517917D01*
X131366Y1518167D01*
X131449Y1518500D01*
X131366Y1518833D01*
X131157Y1519083D01*
X130907Y1519250D01*
X130574Y1519375D01*
X130199Y1519417D01*
X129824Y1519375D01*
X129491Y1519250D01*
X129241Y1519083D01*
X129032Y1518833D01*
X128949Y1518500D01*
G01X118749Y1515550D02*
X114749D01*
Y1508150D01*
G01X127299Y1508367D02*
X124799D01*
Y1509408D01*
X124924Y1509742D01*
X125091Y1509950D01*
X125424Y1510033D01*
X125757Y1509950D01*
X125966Y1509700D01*
X126091Y1509408D01*
Y1508367D01*
G01Y1509408D02*
X127299Y1510033D01*
G01X126799Y1511383D02*
X127091Y1511633D01*
X127257Y1511967D01*
X127299Y1512342D01*
X127257Y1512675D01*
X127049Y1513008D01*
X126799Y1513217D01*
X126549Y1513258D01*
X126257Y1513175D01*
X126049Y1512883D01*
X125966Y1512592D01*
Y1512217D01*
G01Y1512592D02*
X125841Y1512842D01*
X125632Y1513050D01*
X125382Y1513133D01*
X125132Y1513050D01*
X124924Y1512842D01*
X124799Y1512467D01*
X124841Y1512092D01*
X125007Y1511717D01*
G01X127299Y1515400D02*
X124799D01*
X125299Y1514900D01*
G01X127299D02*
Y1515900D01*
G01Y1518500D02*
X127257Y1518792D01*
X127132Y1519125D01*
X126924Y1519333D01*
X126632Y1519417D01*
X126341Y1519333D01*
X126091Y1519083D01*
X125966Y1518708D01*
Y1518292D01*
X125882Y1518042D01*
X125674Y1517833D01*
X125382Y1517750D01*
X125091Y1517875D01*
X124882Y1518167D01*
X124799Y1518500D01*
X124882Y1518833D01*
X125091Y1519125D01*
X125382Y1519250D01*
X125674Y1519167D01*
X125882Y1518958D01*
X125966Y1518708D01*
Y1518292D01*
X126091Y1517917D01*
X126341Y1517667D01*
X126632Y1517583D01*
X126924Y1517667D01*
X127132Y1517875D01*
X127257Y1518208D01*
X127299Y1518500D01*
G01X114599Y1515550D02*
X110599D01*
Y1508150D01*
G01X97017Y1556000D02*
Y1558500D01*
X98058D01*
X98392Y1558375D01*
X98600Y1558208D01*
X98683Y1557875D01*
X98600Y1557542D01*
X98350Y1557333D01*
X98058Y1557208D01*
X97017D01*
G01X98058D02*
X98683Y1556000D01*
G01X100033Y1556375D02*
X100283Y1556167D01*
X100575Y1556042D01*
X100950Y1556000D01*
X101325Y1556083D01*
X101617Y1556250D01*
X101825Y1556542D01*
X101867Y1556875D01*
X101783Y1557208D01*
X101575Y1557417D01*
X101283Y1557583D01*
X100992Y1557625D01*
X100700Y1557583D01*
X100325Y1557417D01*
X100450Y1558500D01*
X101575D01*
G01X104050Y1556000D02*
Y1558500D01*
X103550Y1558000D01*
G01Y1556000D02*
X104550D01*
G01X107150D02*
Y1558500D01*
X106650Y1558000D01*
G01Y1556000D02*
X107650D01*
G01X97017Y1552000D02*
Y1554500D01*
X98058D01*
X98392Y1554375D01*
X98600Y1554208D01*
X98683Y1553875D01*
X98600Y1553542D01*
X98350Y1553333D01*
X98058Y1553208D01*
X97017D01*
G01X98058D02*
X98683Y1552000D01*
G01X100033Y1552375D02*
X100283Y1552167D01*
X100575Y1552042D01*
X100950Y1552000D01*
X101325Y1552083D01*
X101617Y1552250D01*
X101825Y1552542D01*
X101867Y1552875D01*
X101783Y1553208D01*
X101575Y1553417D01*
X101283Y1553583D01*
X100992Y1553625D01*
X100700Y1553583D01*
X100325Y1553417D01*
X100450Y1554500D01*
X101575D01*
G01X104050Y1552000D02*
Y1554500D01*
X103550Y1554000D01*
G01Y1552000D02*
X104550D01*
G01X107150Y1554500D02*
X106817Y1554417D01*
X106567Y1554208D01*
X106400Y1553958D01*
X106275Y1553625D01*
X106233Y1553250D01*
X106275Y1552875D01*
X106400Y1552542D01*
X106567Y1552292D01*
X106817Y1552083D01*
X107150Y1552000D01*
X107483Y1552083D01*
X107733Y1552292D01*
X107900Y1552542D01*
X108025Y1552875D01*
X108067Y1553250D01*
X108025Y1553625D01*
X107900Y1553958D01*
X107733Y1554208D01*
X107483Y1554417D01*
X107150Y1554500D01*
G01X98399Y1516350D02*
Y1513850D01*
G01X97441Y1516350D02*
X99357D01*
G01X100666Y1513850D02*
Y1516350D01*
X101666D01*
X101999Y1516225D01*
X102249Y1515933D01*
X102332Y1515600D01*
X102249Y1515267D01*
X102041Y1515017D01*
X101666Y1514892D01*
X100666D01*
G01X104599Y1513850D02*
Y1516350D01*
X104099Y1515850D01*
G01Y1513850D02*
X105099D01*
G01X114349Y1532716D02*
Y1530216D01*
G01X113391Y1532716D02*
X115307D01*
G01X116616Y1530216D02*
Y1532716D01*
X117616D01*
X117949Y1532591D01*
X118199Y1532299D01*
X118282Y1531966D01*
X118199Y1531633D01*
X117991Y1531383D01*
X117616Y1531258D01*
X116616D01*
G01X119632Y1530716D02*
X119882Y1530424D01*
X120216Y1530258D01*
X120591Y1530216D01*
X120924Y1530258D01*
X121257Y1530466D01*
X121466Y1530716D01*
X121507Y1530966D01*
X121424Y1531258D01*
X121132Y1531466D01*
X120841Y1531549D01*
X120466D01*
G01X120841D02*
X121091Y1531674D01*
X121299Y1531883D01*
X121382Y1532133D01*
X121299Y1532383D01*
X121091Y1532591D01*
X120716Y1532716D01*
X120341Y1532674D01*
X119966Y1532508D01*
G01X123649Y1530216D02*
Y1532716D01*
X123149Y1532216D01*
G01Y1530216D02*
X124149D01*
G01X107955Y1497071D02*
Y1489071D01*
X119905D01*
Y1497071D01*
X107955D01*
G01X119905Y1490921D02*
X117905Y1492921D01*
X119905Y1494921D01*
G01X140667Y1474675D02*
X140875Y1475008D01*
X141000Y1475383D01*
Y1475717D01*
X140875Y1476050D01*
X140667Y1476300D01*
X140375Y1476425D01*
X140083Y1476342D01*
X139833Y1476133D01*
X139667Y1475758D01*
X139583Y1475258D01*
X139417Y1474967D01*
X139125Y1474842D01*
X138833Y1474925D01*
X138625Y1475133D01*
X138500Y1475425D01*
Y1475717D01*
X138583Y1476008D01*
X138792Y1476258D01*
G01X141000Y1477733D02*
X138500D01*
G01Y1479317D02*
X140042Y1477733D01*
G01X141000Y1479567D02*
X139333Y1478442D01*
G01X138500Y1481750D02*
X141000D01*
G01X138500Y1480792D02*
Y1482708D01*
G01X141000Y1484767D02*
X140458Y1484850D01*
X140000Y1484975D01*
X139583Y1485142D01*
X139125Y1485350D01*
X138500Y1485683D01*
Y1484017D01*
G01X174482Y1620050D02*
Y1618258D01*
X174649Y1617883D01*
X174982Y1617633D01*
X175399Y1617550D01*
X175816Y1617633D01*
X176149Y1617883D01*
X176316Y1618258D01*
Y1620050D01*
G01X177582Y1618050D02*
X177832Y1617758D01*
X178166Y1617592D01*
X178541Y1617550D01*
X178874Y1617592D01*
X179207Y1617800D01*
X179416Y1618050D01*
X179457Y1618300D01*
X179374Y1618592D01*
X179082Y1618800D01*
X178791Y1618883D01*
X178416D01*
G01X178791D02*
X179041Y1619008D01*
X179249Y1619217D01*
X179332Y1619467D01*
X179249Y1619717D01*
X179041Y1619925D01*
X178666Y1620050D01*
X178291Y1620008D01*
X177916Y1619842D01*
G01X180807Y1619633D02*
X181057Y1619883D01*
X181349Y1620008D01*
X181682Y1620050D01*
X182099Y1619967D01*
X182391Y1619758D01*
X182474Y1619508D01*
X182432Y1619258D01*
X182266Y1619050D01*
X181432Y1618633D01*
X181057Y1618342D01*
X180807Y1617925D01*
X180724Y1617550D01*
X182474D01*
G01X176499Y1622313D02*
X178499Y1624313D01*
X180499Y1622313D01*
G01X184099D02*
Y1641513D01*
X172899D01*
Y1622313D01*
X184099D01*
G01X95999Y1617900D02*
X98499D01*
G01X95999Y1616942D02*
Y1618858D01*
G01X98499Y1620167D02*
X95999D01*
Y1621167D01*
X96124Y1621500D01*
X96416Y1621750D01*
X96749Y1621833D01*
X97082Y1621750D01*
X97332Y1621542D01*
X97457Y1621167D01*
Y1620167D01*
G01X97999Y1623183D02*
X98291Y1623433D01*
X98457Y1623767D01*
X98499Y1624142D01*
X98457Y1624475D01*
X98249Y1624808D01*
X97999Y1625017D01*
X97749Y1625058D01*
X97457Y1624975D01*
X97249Y1624683D01*
X97166Y1624392D01*
Y1624017D01*
G01Y1624392D02*
X97041Y1624642D01*
X96832Y1624850D01*
X96582Y1624933D01*
X96332Y1624850D01*
X96124Y1624642D01*
X95999Y1624267D01*
X96041Y1623892D01*
X96207Y1623517D01*
G01X98124Y1626283D02*
X98332Y1626533D01*
X98457Y1626825D01*
X98499Y1627200D01*
X98416Y1627575D01*
X98249Y1627867D01*
X97957Y1628075D01*
X97624Y1628117D01*
X97291Y1628033D01*
X97082Y1627825D01*
X96916Y1627533D01*
X96874Y1627242D01*
X96916Y1626950D01*
X97082Y1626575D01*
X95999Y1626700D01*
Y1627825D01*
G01X104666Y1605942D02*
X104416Y1606067D01*
X104124Y1606150D01*
X103791D01*
X103416Y1606025D01*
X103124Y1605817D01*
X102916Y1605567D01*
X102749Y1605150D01*
X102707Y1604775D01*
X102791Y1604400D01*
X102916Y1604150D01*
X103166Y1603900D01*
X103457Y1603733D01*
X103749Y1603650D01*
X104041D01*
X104332Y1603733D01*
X104582Y1603858D01*
X104791Y1604025D01*
G01X105932Y1604150D02*
X106182Y1603858D01*
X106516Y1603692D01*
X106891Y1603650D01*
X107224Y1603692D01*
X107557Y1603900D01*
X107766Y1604150D01*
X107807Y1604400D01*
X107724Y1604692D01*
X107432Y1604900D01*
X107141Y1604983D01*
X106766D01*
G01X107141D02*
X107391Y1605108D01*
X107599Y1605317D01*
X107682Y1605567D01*
X107599Y1605817D01*
X107391Y1606025D01*
X107016Y1606150D01*
X106641Y1606108D01*
X106266Y1605942D01*
G01X109032Y1604025D02*
X109282Y1603817D01*
X109574Y1603692D01*
X109949Y1603650D01*
X110324Y1603733D01*
X110616Y1603900D01*
X110824Y1604192D01*
X110866Y1604525D01*
X110782Y1604858D01*
X110574Y1605067D01*
X110282Y1605233D01*
X109991Y1605275D01*
X109699Y1605233D01*
X109324Y1605067D01*
X109449Y1606150D01*
X110574D01*
G01X113049D02*
X112716Y1606067D01*
X112466Y1605858D01*
X112299Y1605608D01*
X112174Y1605275D01*
X112132Y1604900D01*
X112174Y1604525D01*
X112299Y1604192D01*
X112466Y1603942D01*
X112716Y1603733D01*
X113049Y1603650D01*
X113382Y1603733D01*
X113632Y1603942D01*
X113799Y1604192D01*
X113924Y1604525D01*
X113966Y1604900D01*
X113924Y1605275D01*
X113799Y1605608D01*
X113632Y1605858D01*
X113382Y1606067D01*
X113049Y1606150D01*
G01X109800Y1564000D02*
Y1561500D01*
G01X108842Y1564000D02*
X110758D01*
G01X113817Y1563792D02*
X113567Y1563917D01*
X113275Y1564000D01*
X112942D01*
X112567Y1563875D01*
X112275Y1563667D01*
X112067Y1563417D01*
X111900Y1563000D01*
X111858Y1562625D01*
X111942Y1562250D01*
X112067Y1562000D01*
X112317Y1561750D01*
X112608Y1561583D01*
X112900Y1561500D01*
X113192D01*
X113483Y1561583D01*
X113733Y1561708D01*
X113942Y1561875D01*
G01X116000Y1561500D02*
Y1564000D01*
X115500Y1563500D01*
G01Y1561500D02*
X116500D01*
G01X132100Y1573500D02*
X120900D01*
G01X132100Y1591500D02*
Y1573500D01*
G01X120900Y1591500D02*
X132100D01*
G01X124907Y1622880D02*
X124782Y1622630D01*
X124699Y1622338D01*
Y1622005D01*
X124824Y1621630D01*
X125032Y1621338D01*
X125282Y1621130D01*
X125699Y1620963D01*
X126074Y1620921D01*
X126449Y1621005D01*
X126699Y1621130D01*
X126949Y1621380D01*
X127116Y1621671D01*
X127199Y1621963D01*
Y1622255D01*
X127116Y1622546D01*
X126991Y1622796D01*
X126824Y1623005D01*
G01X125116Y1624271D02*
X124866Y1624521D01*
X124741Y1624813D01*
X124699Y1625146D01*
X124782Y1625563D01*
X124991Y1625855D01*
X125241Y1625938D01*
X125491Y1625896D01*
X125699Y1625730D01*
X126116Y1624896D01*
X126407Y1624521D01*
X126824Y1624271D01*
X127199Y1624188D01*
Y1625938D01*
G01Y1628080D02*
X126657Y1628163D01*
X126199Y1628288D01*
X125782Y1628455D01*
X125324Y1628663D01*
X124699Y1628996D01*
Y1627330D01*
G01X126699Y1630346D02*
X126991Y1630596D01*
X127157Y1630930D01*
X127199Y1631305D01*
X127157Y1631638D01*
X126949Y1631971D01*
X126699Y1632180D01*
X126449Y1632221D01*
X126157Y1632138D01*
X125949Y1631846D01*
X125866Y1631555D01*
Y1631180D01*
G01Y1631555D02*
X125741Y1631805D01*
X125532Y1632013D01*
X125282Y1632096D01*
X125032Y1632013D01*
X124824Y1631805D01*
X124699Y1631430D01*
X124741Y1631055D01*
X124907Y1630680D01*
G01X122199Y1634713D02*
Y1640213D01*
G01X130199Y1634713D02*
X122199D01*
G01X130199Y1640213D02*
Y1634713D01*
G01X116208Y1622867D02*
X116083Y1622617D01*
X116000Y1622325D01*
Y1621992D01*
X116125Y1621617D01*
X116333Y1621325D01*
X116583Y1621117D01*
X117000Y1620950D01*
X117375Y1620908D01*
X117750Y1620992D01*
X118000Y1621117D01*
X118250Y1621367D01*
X118417Y1621658D01*
X118500Y1621950D01*
Y1622242D01*
X118417Y1622533D01*
X118292Y1622783D01*
X118125Y1622992D01*
G01X116417Y1624258D02*
X116167Y1624508D01*
X116042Y1624800D01*
X116000Y1625133D01*
X116083Y1625550D01*
X116292Y1625842D01*
X116542Y1625925D01*
X116792Y1625883D01*
X117000Y1625717D01*
X117417Y1624883D01*
X117708Y1624508D01*
X118125Y1624258D01*
X118500Y1624175D01*
Y1625925D01*
G01Y1628067D02*
X117958Y1628150D01*
X117500Y1628275D01*
X117083Y1628442D01*
X116625Y1628650D01*
X116000Y1628983D01*
Y1627317D01*
G01X118500Y1631750D02*
X116000D01*
X117792Y1630208D01*
Y1632292D01*
G01X113500Y1634700D02*
Y1640200D01*
G01X121500Y1634700D02*
X113500D01*
G01X121500Y1640200D02*
Y1634700D01*
G01X107507Y1622880D02*
X107382Y1622630D01*
X107299Y1622338D01*
Y1622005D01*
X107424Y1621630D01*
X107632Y1621338D01*
X107882Y1621130D01*
X108299Y1620963D01*
X108674Y1620921D01*
X109049Y1621005D01*
X109299Y1621130D01*
X109549Y1621380D01*
X109716Y1621671D01*
X109799Y1621963D01*
Y1622255D01*
X109716Y1622546D01*
X109591Y1622796D01*
X109424Y1623005D01*
G01X107716Y1624271D02*
X107466Y1624521D01*
X107341Y1624813D01*
X107299Y1625146D01*
X107382Y1625563D01*
X107591Y1625855D01*
X107841Y1625938D01*
X108091Y1625896D01*
X108299Y1625730D01*
X108716Y1624896D01*
X109007Y1624521D01*
X109424Y1624271D01*
X109799Y1624188D01*
Y1625938D01*
G01Y1628080D02*
X109257Y1628163D01*
X108799Y1628288D01*
X108382Y1628455D01*
X107924Y1628663D01*
X107299Y1628996D01*
Y1627330D01*
G01X109424Y1630346D02*
X109632Y1630596D01*
X109757Y1630888D01*
X109799Y1631263D01*
X109716Y1631638D01*
X109549Y1631930D01*
X109257Y1632138D01*
X108924Y1632180D01*
X108591Y1632096D01*
X108382Y1631888D01*
X108216Y1631596D01*
X108174Y1631305D01*
X108216Y1631013D01*
X108382Y1630638D01*
X107299Y1630763D01*
Y1631888D01*
G01X104799Y1634713D02*
Y1640213D01*
G01X112799Y1634713D02*
X104799D01*
G01X112799Y1640213D02*
Y1634713D01*
G01X176999Y1656127D02*
Y1644727D01*
G01X190399Y1656127D02*
X176999D01*
G01Y1644727D02*
X190399D01*
G01X169100Y1675400D02*
X180500D01*
G01X169100Y1688800D02*
Y1675400D01*
G01X180500Y1688800D02*
X169100D01*
G01X178900Y1715500D02*
X178567Y1715542D01*
X178275Y1715708D01*
X178025Y1715958D01*
X177858Y1716250D01*
X177775Y1716583D01*
Y1716917D01*
X177858Y1717250D01*
X178025Y1717542D01*
X178275Y1717792D01*
X178567Y1717958D01*
X178900Y1718000D01*
X179233Y1717958D01*
X179525Y1717792D01*
X179775Y1717542D01*
X179942Y1717250D01*
X180025Y1716917D01*
Y1716583D01*
X179942Y1716250D01*
X179775Y1715958D01*
X179525Y1715708D01*
X179233Y1715542D01*
X178900Y1715500D01*
G01X179233Y1716167D02*
X179733Y1715500D01*
G01X181208Y1717583D02*
X181458Y1717833D01*
X181750Y1717958D01*
X182083Y1718000D01*
X182500Y1717917D01*
X182792Y1717708D01*
X182875Y1717458D01*
X182833Y1717208D01*
X182667Y1717000D01*
X181833Y1716583D01*
X181458Y1716292D01*
X181208Y1715875D01*
X181125Y1715500D01*
X182875D01*
G01X185100D02*
Y1718000D01*
X184600Y1717500D01*
G01Y1715500D02*
X185600D01*
G01X154299Y1712113D02*
X156399Y1710313D01*
X154299Y1708113D01*
G01X154199Y1704513D02*
X173399D01*
Y1715713D01*
X154199D01*
Y1704513D01*
X154599D01*
G01X99000Y1682517D02*
X96500D01*
Y1683558D01*
X96625Y1683892D01*
X96792Y1684100D01*
X97125Y1684183D01*
X97458Y1684100D01*
X97667Y1683850D01*
X97792Y1683558D01*
Y1682517D01*
G01Y1683558D02*
X99000Y1684183D01*
G01X96917Y1685658D02*
X96667Y1685908D01*
X96542Y1686200D01*
X96500Y1686533D01*
X96583Y1686950D01*
X96792Y1687242D01*
X97042Y1687325D01*
X97292Y1687283D01*
X97500Y1687117D01*
X97917Y1686283D01*
X98208Y1685908D01*
X98625Y1685658D01*
X99000Y1685575D01*
Y1687325D01*
G01Y1690050D02*
X96500D01*
X98292Y1688508D01*
Y1690592D01*
G01X98625Y1691733D02*
X98833Y1691983D01*
X98958Y1692275D01*
X99000Y1692650D01*
X98917Y1693025D01*
X98750Y1693317D01*
X98458Y1693525D01*
X98125Y1693567D01*
X97792Y1693483D01*
X97583Y1693275D01*
X97417Y1692983D01*
X97375Y1692692D01*
X97417Y1692400D01*
X97583Y1692025D01*
X96500Y1692150D01*
Y1693275D01*
G01X129499Y1686613D02*
Y1699613D01*
G01X103499Y1686613D02*
X129499D01*
G01X103499Y1699613D02*
Y1686613D01*
G01X129499Y1699613D02*
X103499D01*
G01X100499Y1654067D02*
X97999D01*
Y1655108D01*
X98124Y1655442D01*
X98291Y1655650D01*
X98624Y1655733D01*
X98957Y1655650D01*
X99166Y1655400D01*
X99291Y1655108D01*
Y1654067D01*
G01Y1655108D02*
X100499Y1655733D01*
G01X98416Y1657208D02*
X98166Y1657458D01*
X98041Y1657750D01*
X97999Y1658083D01*
X98082Y1658500D01*
X98291Y1658792D01*
X98541Y1658875D01*
X98791Y1658833D01*
X98999Y1658667D01*
X99416Y1657833D01*
X99707Y1657458D01*
X100124Y1657208D01*
X100499Y1657125D01*
Y1658875D01*
G01X100124Y1660183D02*
X100332Y1660433D01*
X100457Y1660725D01*
X100499Y1661100D01*
X100416Y1661475D01*
X100249Y1661767D01*
X99957Y1661975D01*
X99624Y1662017D01*
X99291Y1661933D01*
X99082Y1661725D01*
X98916Y1661433D01*
X98874Y1661142D01*
X98916Y1660850D01*
X99082Y1660475D01*
X97999Y1660600D01*
Y1661725D01*
G01Y1664200D02*
X98082Y1663867D01*
X98291Y1663617D01*
X98541Y1663450D01*
X98874Y1663325D01*
X99249Y1663283D01*
X99624Y1663325D01*
X99957Y1663450D01*
X100207Y1663617D01*
X100416Y1663867D01*
X100499Y1664200D01*
X100416Y1664533D01*
X100207Y1664783D01*
X99957Y1664950D01*
X99624Y1665075D01*
X99249Y1665117D01*
X98874Y1665075D01*
X98541Y1664950D01*
X98291Y1664783D01*
X98082Y1664533D01*
X97999Y1664200D01*
G01X128999Y1653113D02*
Y1666113D01*
G01X102999Y1653113D02*
X128999D01*
G01X102999Y1666113D02*
Y1653113D01*
G01X128999Y1666113D02*
X102999D01*
G01X119449Y1700613D02*
Y1704613D01*
X112049D01*
G01X142299Y1724550D02*
Y1720550D01*
X149699D01*
G01X176499Y1655063D02*
X172499D01*
Y1647663D01*
G01X142299Y1720550D02*
Y1716550D01*
X149699D01*
G01X155517Y1670500D02*
Y1673000D01*
X156558D01*
X156892Y1672875D01*
X157100Y1672708D01*
X157183Y1672375D01*
X157100Y1672042D01*
X156850Y1671833D01*
X156558Y1671708D01*
X155517D01*
G01X156558D02*
X157183Y1670500D01*
G01X158533Y1671000D02*
X158783Y1670708D01*
X159117Y1670542D01*
X159492Y1670500D01*
X159825Y1670542D01*
X160158Y1670750D01*
X160367Y1671000D01*
X160408Y1671250D01*
X160325Y1671542D01*
X160033Y1671750D01*
X159742Y1671833D01*
X159367D01*
G01X159742D02*
X159992Y1671958D01*
X160200Y1672167D01*
X160283Y1672417D01*
X160200Y1672667D01*
X159992Y1672875D01*
X159617Y1673000D01*
X159242Y1672958D01*
X158867Y1672792D01*
G01X161842Y1670792D02*
X162133Y1670583D01*
X162467Y1670500D01*
X162800Y1670583D01*
X163092Y1670833D01*
X163300Y1671208D01*
X163383Y1671583D01*
Y1672042D01*
X163300Y1672417D01*
X163092Y1672750D01*
X162842Y1672917D01*
X162550Y1673000D01*
X162217Y1672917D01*
X161967Y1672750D01*
X161800Y1672500D01*
X161717Y1672167D01*
X161800Y1671875D01*
X162008Y1671583D01*
X162258Y1671417D01*
X162550Y1671375D01*
X162883Y1671458D01*
X163133Y1671667D01*
X163383Y1672042D01*
G01X164858Y1671542D02*
X165150Y1671833D01*
X165400Y1672000D01*
X165733Y1672083D01*
X166025Y1672000D01*
X166233Y1671833D01*
X166400Y1671583D01*
X166442Y1671292D01*
X166400Y1671042D01*
X166233Y1670792D01*
X165983Y1670583D01*
X165692Y1670500D01*
X165358Y1670583D01*
X165067Y1670833D01*
X164900Y1671208D01*
X164858Y1671625D01*
X164942Y1672167D01*
X165067Y1672458D01*
X165275Y1672750D01*
X165567Y1672958D01*
X165858Y1673000D01*
X166150Y1672917D01*
X166358Y1672708D01*
G01X150600Y1679200D02*
X154600D01*
Y1686600D01*
G01X176200Y1689200D02*
Y1693200D01*
X168800D01*
G01X103799Y1718613D02*
Y1714613D01*
X111199D01*
G01X103799Y1722613D02*
Y1718613D01*
X111199D01*
G01X133999Y1701350D02*
X137999D01*
Y1708750D01*
G01X129999Y1701350D02*
X133999D01*
Y1708750D01*
G01X101230Y1695758D02*
X98730D01*
Y1696799D01*
X98855Y1697133D01*
X99022Y1697341D01*
X99355Y1697424D01*
X99688Y1697341D01*
X99897Y1697091D01*
X100022Y1696799D01*
Y1695758D01*
G01Y1696799D02*
X101230Y1697424D01*
G01X99147Y1698899D02*
X98897Y1699149D01*
X98772Y1699441D01*
X98730Y1699774D01*
X98813Y1700191D01*
X99022Y1700483D01*
X99272Y1700566D01*
X99522Y1700524D01*
X99730Y1700358D01*
X100147Y1699524D01*
X100438Y1699149D01*
X100855Y1698899D01*
X101230Y1698816D01*
Y1700566D01*
G01X100855Y1701874D02*
X101063Y1702124D01*
X101188Y1702416D01*
X101230Y1702791D01*
X101147Y1703166D01*
X100980Y1703458D01*
X100688Y1703666D01*
X100355Y1703708D01*
X100022Y1703624D01*
X99813Y1703416D01*
X99647Y1703124D01*
X99605Y1702833D01*
X99647Y1702541D01*
X99813Y1702166D01*
X98730Y1702291D01*
Y1703416D01*
G01X101230Y1705891D02*
X98730D01*
X99230Y1705391D01*
G01X101230D02*
Y1706391D01*
G01X127199Y1712550D02*
X113799D01*
G01X127199Y1722550D02*
Y1712550D01*
G01X113799Y1722550D02*
X127199D01*
G01X113799Y1712550D02*
Y1722550D01*
G01X140499Y1724750D02*
Y1711350D01*
G01X130499D02*
Y1724750D01*
G01X140499Y1711350D02*
X130499D01*
G01X140208Y1671267D02*
X140083Y1671017D01*
X140000Y1670725D01*
Y1670392D01*
X140125Y1670017D01*
X140333Y1669725D01*
X140583Y1669517D01*
X141000Y1669350D01*
X141375Y1669308D01*
X141750Y1669392D01*
X142000Y1669517D01*
X142250Y1669767D01*
X142417Y1670058D01*
X142500Y1670350D01*
Y1670642D01*
X142417Y1670933D01*
X142292Y1671183D01*
X142125Y1671392D01*
G01X140417Y1672658D02*
X140167Y1672908D01*
X140042Y1673200D01*
X140000Y1673533D01*
X140083Y1673950D01*
X140292Y1674242D01*
X140542Y1674325D01*
X140792Y1674283D01*
X141000Y1674117D01*
X141417Y1673283D01*
X141708Y1672908D01*
X142125Y1672658D01*
X142500Y1672575D01*
Y1674325D01*
G01Y1676467D02*
X141958Y1676550D01*
X141500Y1676675D01*
X141083Y1676842D01*
X140625Y1677050D01*
X140000Y1677383D01*
Y1675717D01*
G01X142500Y1679650D02*
X140000D01*
X140500Y1679150D01*
G01X142500D02*
Y1680150D01*
G01X129999Y1656313D02*
Y1661813D01*
G01X137999Y1656313D02*
X129999D01*
G01X137999Y1661813D02*
Y1656313D01*
G01Y1673913D02*
Y1668413D01*
G01X129999Y1673913D02*
X137999D01*
G01X129999Y1668413D02*
Y1673913D01*
G01X130199Y1652313D02*
Y1646813D01*
G01X122199Y1652313D02*
X130199D01*
G01X122199Y1646813D02*
Y1652313D01*
G01X121500Y1652300D02*
Y1646800D01*
G01X113500Y1652300D02*
X121500D01*
G01X113500Y1646800D02*
Y1652300D01*
G01X112799Y1652313D02*
Y1646813D01*
G01X104799Y1652313D02*
X112799D01*
G01X104799Y1646813D02*
Y1652313D01*
G01X98708Y1670767D02*
X98583Y1670517D01*
X98500Y1670225D01*
Y1669892D01*
X98625Y1669517D01*
X98833Y1669225D01*
X99083Y1669017D01*
X99500Y1668850D01*
X99875Y1668808D01*
X100250Y1668892D01*
X100500Y1669017D01*
X100750Y1669267D01*
X100917Y1669558D01*
X101000Y1669850D01*
Y1670142D01*
X100917Y1670433D01*
X100792Y1670683D01*
X100625Y1670892D01*
G01X98917Y1672158D02*
X98667Y1672408D01*
X98542Y1672700D01*
X98500Y1673033D01*
X98583Y1673450D01*
X98792Y1673742D01*
X99042Y1673825D01*
X99292Y1673783D01*
X99500Y1673617D01*
X99917Y1672783D01*
X100208Y1672408D01*
X100625Y1672158D01*
X101000Y1672075D01*
Y1673825D01*
G01X99958Y1675258D02*
X99667Y1675550D01*
X99500Y1675800D01*
X99417Y1676133D01*
X99500Y1676425D01*
X99667Y1676633D01*
X99917Y1676800D01*
X100208Y1676842D01*
X100458Y1676800D01*
X100708Y1676633D01*
X100917Y1676383D01*
X101000Y1676092D01*
X100917Y1675758D01*
X100667Y1675467D01*
X100292Y1675300D01*
X99875Y1675258D01*
X99333Y1675342D01*
X99042Y1675467D01*
X98750Y1675675D01*
X98542Y1675967D01*
X98500Y1676258D01*
X98583Y1676550D01*
X98792Y1676758D01*
G01X101000Y1679067D02*
X100458Y1679150D01*
X100000Y1679275D01*
X99583Y1679442D01*
X99125Y1679650D01*
X98500Y1679983D01*
Y1678317D01*
G01X116499Y1685913D02*
Y1680413D01*
G01X108499Y1685913D02*
X116499D01*
G01X108499Y1680413D02*
Y1685913D01*
G01Y1668313D02*
Y1673813D01*
G01X116499Y1668313D02*
X108499D01*
G01X116499Y1673813D02*
Y1668313D01*
G01X158900Y1674500D02*
X158567Y1674542D01*
X158275Y1674708D01*
X158025Y1674958D01*
X157858Y1675250D01*
X157775Y1675583D01*
Y1675917D01*
X157858Y1676250D01*
X158025Y1676542D01*
X158275Y1676792D01*
X158567Y1676958D01*
X158900Y1677000D01*
X159233Y1676958D01*
X159525Y1676792D01*
X159775Y1676542D01*
X159942Y1676250D01*
X160025Y1675917D01*
Y1675583D01*
X159942Y1675250D01*
X159775Y1674958D01*
X159525Y1674708D01*
X159233Y1674542D01*
X158900Y1674500D01*
G01X159233Y1675167D02*
X159733Y1674500D01*
G01X161208Y1675542D02*
X161500Y1675833D01*
X161750Y1676000D01*
X162083Y1676083D01*
X162375Y1676000D01*
X162583Y1675833D01*
X162750Y1675583D01*
X162792Y1675292D01*
X162750Y1675042D01*
X162583Y1674792D01*
X162333Y1674583D01*
X162042Y1674500D01*
X161708Y1674583D01*
X161417Y1674833D01*
X161250Y1675208D01*
X161208Y1675625D01*
X161292Y1676167D01*
X161417Y1676458D01*
X161625Y1676750D01*
X161917Y1676958D01*
X162208Y1677000D01*
X162500Y1676917D01*
X162708Y1676708D01*
G01X165017Y1674500D02*
X165100Y1675042D01*
X165225Y1675500D01*
X165392Y1675917D01*
X165600Y1676375D01*
X165933Y1677000D01*
X164267D01*
G01X155200Y1692800D02*
Y1678800D01*
G01X168200Y1692800D02*
X155200D01*
G01X168200Y1678800D02*
Y1692800D01*
G01X155200Y1678800D02*
X168200D01*
G01X116999Y1841150D02*
X126999D01*
G01Y1834150D02*
X116999D01*
G01X121999D02*
Y1841150D01*
G01X116999Y1830717D02*
X126999D01*
Y1827383D01*
X126499Y1826050D01*
X125832Y1825050D01*
X124832Y1824217D01*
X123665Y1823550D01*
X121999Y1823383D01*
X120332Y1823550D01*
X119166Y1824217D01*
X118165Y1825050D01*
X117499Y1826050D01*
X116999Y1827383D01*
Y1830717D01*
G01Y1820117D02*
X126999D01*
Y1816783D01*
X126499Y1815450D01*
X125832Y1814450D01*
X124832Y1813617D01*
X123665Y1812950D01*
X121999Y1812783D01*
X120332Y1812950D01*
X119166Y1813617D01*
X118165Y1814450D01*
X117499Y1815450D01*
X116999Y1816783D01*
Y1820117D01*
G01Y1805850D02*
X126999D01*
X124999Y1807850D01*
G01X116999D02*
Y1803850D01*
G01X126999Y1795250D02*
X126666Y1796584D01*
X125832Y1797583D01*
X124832Y1798250D01*
X123499Y1798750D01*
X121999Y1798917D01*
X120499Y1798750D01*
X119166Y1798250D01*
X118165Y1797583D01*
X117332Y1796584D01*
X116999Y1795250D01*
X117332Y1793917D01*
X118165Y1792917D01*
X119166Y1792250D01*
X120499Y1791750D01*
X121999Y1791583D01*
X123499Y1791750D01*
X124832Y1792250D01*
X125832Y1792917D01*
X126666Y1793917D01*
X126999Y1795250D01*
G01X113666Y1789650D02*
Y1779650D01*
G01X126999Y1777383D02*
X116999D01*
Y1770717D01*
G01Y1760117D02*
Y1766783D01*
X126999D01*
Y1760117D01*
G01X122166Y1762783D02*
Y1766783D01*
G01X116999Y1756517D02*
X126999D01*
Y1753183D01*
X126499Y1751850D01*
X125832Y1750850D01*
X124832Y1750017D01*
X123665Y1749350D01*
X121999Y1749183D01*
X120332Y1749350D01*
X119166Y1750017D01*
X118165Y1750850D01*
X117499Y1751850D01*
X116999Y1753183D01*
Y1756517D01*
G01X137708Y1747267D02*
X137583Y1747017D01*
X137500Y1746725D01*
Y1746392D01*
X137625Y1746017D01*
X137833Y1745725D01*
X138083Y1745517D01*
X138500Y1745350D01*
X138875Y1745308D01*
X139250Y1745392D01*
X139500Y1745517D01*
X139750Y1745767D01*
X139917Y1746058D01*
X140000Y1746350D01*
Y1746642D01*
X139917Y1746933D01*
X139792Y1747183D01*
X139625Y1747392D01*
G01X137917Y1748658D02*
X137667Y1748908D01*
X137542Y1749200D01*
X137500Y1749533D01*
X137583Y1749950D01*
X137792Y1750242D01*
X138042Y1750325D01*
X138292Y1750283D01*
X138500Y1750117D01*
X138917Y1749283D01*
X139208Y1748908D01*
X139625Y1748658D01*
X140000Y1748575D01*
Y1750325D01*
G01X138958Y1751758D02*
X138667Y1752050D01*
X138500Y1752300D01*
X138417Y1752633D01*
X138500Y1752925D01*
X138667Y1753133D01*
X138917Y1753300D01*
X139208Y1753342D01*
X139458Y1753300D01*
X139708Y1753133D01*
X139917Y1752883D01*
X140000Y1752592D01*
X139917Y1752258D01*
X139667Y1751967D01*
X139292Y1751800D01*
X138875Y1751758D01*
X138333Y1751842D01*
X138042Y1751967D01*
X137750Y1752175D01*
X137542Y1752467D01*
X137500Y1752758D01*
X137583Y1753050D01*
X137792Y1753258D01*
G01X139708Y1754942D02*
X139917Y1755233D01*
X140000Y1755567D01*
X139917Y1755900D01*
X139667Y1756192D01*
X139292Y1756400D01*
X138917Y1756483D01*
X138458D01*
X138083Y1756400D01*
X137750Y1756192D01*
X137583Y1755942D01*
X137500Y1755650D01*
X137583Y1755317D01*
X137750Y1755067D01*
X138000Y1754900D01*
X138333Y1754817D01*
X138625Y1754900D01*
X138917Y1755108D01*
X139083Y1755358D01*
X139125Y1755650D01*
X139042Y1755983D01*
X138833Y1756233D01*
X138458Y1756483D01*
G01X129208Y1735767D02*
X129083Y1735517D01*
X129000Y1735225D01*
Y1734892D01*
X129125Y1734517D01*
X129333Y1734225D01*
X129583Y1734017D01*
X130000Y1733850D01*
X130375Y1733808D01*
X130750Y1733892D01*
X131000Y1734017D01*
X131250Y1734267D01*
X131417Y1734558D01*
X131500Y1734850D01*
Y1735142D01*
X131417Y1735433D01*
X131292Y1735683D01*
X131125Y1735892D01*
G01X129417Y1737158D02*
X129167Y1737408D01*
X129042Y1737700D01*
X129000Y1738033D01*
X129083Y1738450D01*
X129292Y1738742D01*
X129542Y1738825D01*
X129792Y1738783D01*
X130000Y1738617D01*
X130417Y1737783D01*
X130708Y1737408D01*
X131125Y1737158D01*
X131500Y1737075D01*
Y1738825D01*
G01X130458Y1740258D02*
X130167Y1740550D01*
X130000Y1740800D01*
X129917Y1741133D01*
X130000Y1741425D01*
X130167Y1741633D01*
X130417Y1741800D01*
X130708Y1741842D01*
X130958Y1741800D01*
X131208Y1741633D01*
X131417Y1741383D01*
X131500Y1741092D01*
X131417Y1740758D01*
X131167Y1740467D01*
X130792Y1740300D01*
X130375Y1740258D01*
X129833Y1740342D01*
X129542Y1740467D01*
X129250Y1740675D01*
X129042Y1740967D01*
X129000Y1741258D01*
X129083Y1741550D01*
X129292Y1741758D01*
G01X131500Y1744150D02*
X129000D01*
X129500Y1743650D01*
G01X131500D02*
Y1744650D01*
G01X102766Y1760842D02*
X102516Y1760967D01*
X102224Y1761050D01*
X101891D01*
X101516Y1760925D01*
X101224Y1760717D01*
X101016Y1760467D01*
X100849Y1760050D01*
X100807Y1759675D01*
X100891Y1759300D01*
X101016Y1759050D01*
X101266Y1758800D01*
X101557Y1758633D01*
X101849Y1758550D01*
X102141D01*
X102432Y1758633D01*
X102682Y1758758D01*
X102891Y1758925D01*
G01X104157Y1760633D02*
X104407Y1760883D01*
X104699Y1761008D01*
X105032Y1761050D01*
X105449Y1760967D01*
X105741Y1760758D01*
X105824Y1760508D01*
X105782Y1760258D01*
X105616Y1760050D01*
X104782Y1759633D01*
X104407Y1759342D01*
X104157Y1758925D01*
X104074Y1758550D01*
X105824D01*
G01X107257Y1759592D02*
X107549Y1759883D01*
X107799Y1760050D01*
X108132Y1760133D01*
X108424Y1760050D01*
X108632Y1759883D01*
X108799Y1759633D01*
X108841Y1759342D01*
X108799Y1759092D01*
X108632Y1758842D01*
X108382Y1758633D01*
X108091Y1758550D01*
X107757Y1758633D01*
X107466Y1758883D01*
X107299Y1759258D01*
X107257Y1759675D01*
X107341Y1760217D01*
X107466Y1760508D01*
X107674Y1760800D01*
X107966Y1761008D01*
X108257Y1761050D01*
X108549Y1760967D01*
X108757Y1760758D01*
G01X110357Y1760633D02*
X110607Y1760883D01*
X110899Y1761008D01*
X111232Y1761050D01*
X111649Y1760967D01*
X111941Y1760758D01*
X112024Y1760508D01*
X111982Y1760258D01*
X111816Y1760050D01*
X110982Y1759633D01*
X110607Y1759342D01*
X110357Y1758925D01*
X110274Y1758550D01*
X112024D01*
G01X102266Y1756842D02*
X102016Y1756967D01*
X101724Y1757050D01*
X101391D01*
X101016Y1756925D01*
X100724Y1756717D01*
X100516Y1756467D01*
X100349Y1756050D01*
X100307Y1755675D01*
X100391Y1755300D01*
X100516Y1755050D01*
X100766Y1754800D01*
X101057Y1754633D01*
X101349Y1754550D01*
X101641D01*
X101932Y1754633D01*
X102182Y1754758D01*
X102391Y1754925D01*
G01X103657Y1756633D02*
X103907Y1756883D01*
X104199Y1757008D01*
X104532Y1757050D01*
X104949Y1756967D01*
X105241Y1756758D01*
X105324Y1756508D01*
X105282Y1756258D01*
X105116Y1756050D01*
X104282Y1755633D01*
X103907Y1755342D01*
X103657Y1754925D01*
X103574Y1754550D01*
X105324D01*
G01X106757Y1755592D02*
X107049Y1755883D01*
X107299Y1756050D01*
X107632Y1756133D01*
X107924Y1756050D01*
X108132Y1755883D01*
X108299Y1755633D01*
X108341Y1755342D01*
X108299Y1755092D01*
X108132Y1754842D01*
X107882Y1754633D01*
X107591Y1754550D01*
X107257Y1754633D01*
X106966Y1754883D01*
X106799Y1755258D01*
X106757Y1755675D01*
X106841Y1756217D01*
X106966Y1756508D01*
X107174Y1756800D01*
X107466Y1757008D01*
X107757Y1757050D01*
X108049Y1756967D01*
X108257Y1756758D01*
G01X109732Y1755050D02*
X109982Y1754758D01*
X110316Y1754592D01*
X110691Y1754550D01*
X111024Y1754592D01*
X111357Y1754800D01*
X111566Y1755050D01*
X111607Y1755300D01*
X111524Y1755592D01*
X111232Y1755800D01*
X110941Y1755883D01*
X110566D01*
G01X110941D02*
X111191Y1756008D01*
X111399Y1756217D01*
X111482Y1756467D01*
X111399Y1756717D01*
X111191Y1756925D01*
X110816Y1757050D01*
X110441Y1757008D01*
X110066Y1756842D01*
G01X98766Y1751342D02*
X98516Y1751467D01*
X98224Y1751550D01*
X97891D01*
X97516Y1751425D01*
X97224Y1751217D01*
X97016Y1750967D01*
X96849Y1750550D01*
X96807Y1750175D01*
X96891Y1749800D01*
X97016Y1749550D01*
X97266Y1749300D01*
X97557Y1749133D01*
X97849Y1749050D01*
X98141D01*
X98432Y1749133D01*
X98682Y1749258D01*
X98891Y1749425D01*
G01X100157Y1751133D02*
X100407Y1751383D01*
X100699Y1751508D01*
X101032Y1751550D01*
X101449Y1751467D01*
X101741Y1751258D01*
X101824Y1751008D01*
X101782Y1750758D01*
X101616Y1750550D01*
X100782Y1750133D01*
X100407Y1749842D01*
X100157Y1749425D01*
X100074Y1749050D01*
X101824D01*
G01X103257Y1750092D02*
X103549Y1750383D01*
X103799Y1750550D01*
X104132Y1750633D01*
X104424Y1750550D01*
X104632Y1750383D01*
X104799Y1750133D01*
X104841Y1749842D01*
X104799Y1749592D01*
X104632Y1749342D01*
X104382Y1749133D01*
X104091Y1749050D01*
X103757Y1749133D01*
X103466Y1749383D01*
X103299Y1749758D01*
X103257Y1750175D01*
X103341Y1750717D01*
X103466Y1751008D01*
X103674Y1751300D01*
X103966Y1751508D01*
X104257Y1751550D01*
X104549Y1751467D01*
X104757Y1751258D01*
G01X107649Y1749050D02*
Y1751550D01*
X106107Y1749758D01*
X108191D01*
G01X98766Y1747842D02*
X98516Y1747967D01*
X98224Y1748050D01*
X97891D01*
X97516Y1747925D01*
X97224Y1747717D01*
X97016Y1747467D01*
X96849Y1747050D01*
X96807Y1746675D01*
X96891Y1746300D01*
X97016Y1746050D01*
X97266Y1745800D01*
X97557Y1745633D01*
X97849Y1745550D01*
X98141D01*
X98432Y1745633D01*
X98682Y1745758D01*
X98891Y1745925D01*
G01X100157Y1747633D02*
X100407Y1747883D01*
X100699Y1748008D01*
X101032Y1748050D01*
X101449Y1747967D01*
X101741Y1747758D01*
X101824Y1747508D01*
X101782Y1747258D01*
X101616Y1747050D01*
X100782Y1746633D01*
X100407Y1746342D01*
X100157Y1745925D01*
X100074Y1745550D01*
X101824D01*
G01X103257Y1746592D02*
X103549Y1746883D01*
X103799Y1747050D01*
X104132Y1747133D01*
X104424Y1747050D01*
X104632Y1746883D01*
X104799Y1746633D01*
X104841Y1746342D01*
X104799Y1746092D01*
X104632Y1745842D01*
X104382Y1745633D01*
X104091Y1745550D01*
X103757Y1745633D01*
X103466Y1745883D01*
X103299Y1746258D01*
X103257Y1746675D01*
X103341Y1747217D01*
X103466Y1747508D01*
X103674Y1747800D01*
X103966Y1748008D01*
X104257Y1748050D01*
X104549Y1747967D01*
X104757Y1747758D01*
G01X106232Y1745925D02*
X106482Y1745717D01*
X106774Y1745592D01*
X107149Y1745550D01*
X107524Y1745633D01*
X107816Y1745800D01*
X108024Y1746092D01*
X108066Y1746425D01*
X107982Y1746758D01*
X107774Y1746967D01*
X107482Y1747133D01*
X107191Y1747175D01*
X106899Y1747133D01*
X106524Y1746967D01*
X106649Y1748050D01*
X107774D01*
G01X161741Y1770698D02*
Y1768198D01*
X163407D01*
G01X166507D02*
X164841D01*
Y1770698D01*
X166507D01*
G01X165841Y1769490D02*
X164841D01*
G01X167857Y1768198D02*
Y1770698D01*
X168691D01*
X169024Y1770573D01*
X169274Y1770406D01*
X169482Y1770156D01*
X169649Y1769865D01*
X169691Y1769448D01*
X169649Y1769031D01*
X169482Y1768740D01*
X169274Y1768490D01*
X169024Y1768323D01*
X168691Y1768198D01*
X167857D01*
G01X171082Y1769240D02*
X171374Y1769531D01*
X171624Y1769698D01*
X171957Y1769781D01*
X172249Y1769698D01*
X172457Y1769531D01*
X172624Y1769281D01*
X172666Y1768990D01*
X172624Y1768740D01*
X172457Y1768490D01*
X172207Y1768281D01*
X171916Y1768198D01*
X171582Y1768281D01*
X171291Y1768531D01*
X171124Y1768906D01*
X171082Y1769323D01*
X171166Y1769865D01*
X171291Y1770156D01*
X171499Y1770448D01*
X171791Y1770656D01*
X172082Y1770698D01*
X172374Y1770615D01*
X172582Y1770406D01*
G01X173023Y1787894D02*
Y1780294D01*
X161623D01*
Y1787894D01*
X173023D01*
G01X175364Y1788613D02*
Y1784613D01*
X182764D01*
G01X140488Y1785409D02*
Y1787909D01*
X141529D01*
X141863Y1787784D01*
X142071Y1787617D01*
X142154Y1787284D01*
X142071Y1786951D01*
X141821Y1786742D01*
X141529Y1786617D01*
X140488D01*
G01X141529D02*
X142154Y1785409D01*
G01X144421D02*
Y1787909D01*
X143921Y1787409D01*
G01Y1785409D02*
X144921D01*
G01X147438D02*
X147521Y1785951D01*
X147646Y1786409D01*
X147813Y1786826D01*
X148021Y1787284D01*
X148354Y1787909D01*
X146688D01*
G01X150621Y1785409D02*
Y1787909D01*
X150121Y1787409D01*
G01Y1785409D02*
X151121D01*
G01X152771Y1788909D02*
Y1784909D01*
X160171D01*
G01X175364Y1784613D02*
Y1780613D01*
X182764D01*
G01X140488Y1781409D02*
Y1783909D01*
X141529D01*
X141863Y1783784D01*
X142071Y1783617D01*
X142154Y1783284D01*
X142071Y1782951D01*
X141821Y1782742D01*
X141529Y1782617D01*
X140488D01*
G01X141529D02*
X142154Y1781409D01*
G01X144421D02*
Y1783909D01*
X143921Y1783409D01*
G01Y1781409D02*
X144921D01*
G01X147438D02*
X147521Y1781951D01*
X147646Y1782409D01*
X147813Y1782826D01*
X148021Y1783284D01*
X148354Y1783909D01*
X146688D01*
G01X149704Y1781909D02*
X149954Y1781617D01*
X150288Y1781451D01*
X150663Y1781409D01*
X150996Y1781451D01*
X151329Y1781659D01*
X151538Y1781909D01*
X151579Y1782159D01*
X151496Y1782451D01*
X151204Y1782659D01*
X150913Y1782742D01*
X150538D01*
G01X150913D02*
X151163Y1782867D01*
X151371Y1783076D01*
X151454Y1783326D01*
X151371Y1783576D01*
X151163Y1783784D01*
X150788Y1783909D01*
X150413Y1783867D01*
X150038Y1783701D01*
G01X152771Y1784909D02*
Y1780909D01*
X160171D01*
G01X175364Y1780613D02*
Y1776613D01*
X182764D01*
G01X148513Y1736182D02*
Y1738682D01*
X149554D01*
X149888Y1738557D01*
X150096Y1738390D01*
X150179Y1738057D01*
X150096Y1737724D01*
X149846Y1737515D01*
X149554Y1737390D01*
X148513D01*
G01X149554D02*
X150179Y1736182D01*
G01X151654Y1738265D02*
X151904Y1738515D01*
X152196Y1738640D01*
X152529Y1738682D01*
X152946Y1738599D01*
X153238Y1738390D01*
X153321Y1738140D01*
X153279Y1737890D01*
X153113Y1737682D01*
X152279Y1737265D01*
X151904Y1736974D01*
X151654Y1736557D01*
X151571Y1736182D01*
X153321D01*
G01X156046D02*
Y1738682D01*
X154504Y1736890D01*
X156588D01*
G01X158563Y1736182D02*
X158646Y1736724D01*
X158771Y1737182D01*
X158938Y1737599D01*
X159146Y1738057D01*
X159479Y1738682D01*
X157813D01*
G01X148513Y1732182D02*
Y1734682D01*
X149554D01*
X149888Y1734557D01*
X150096Y1734390D01*
X150179Y1734057D01*
X150096Y1733724D01*
X149846Y1733515D01*
X149554Y1733390D01*
X148513D01*
G01X149554D02*
X150179Y1732182D01*
G01X151654Y1734265D02*
X151904Y1734515D01*
X152196Y1734640D01*
X152529Y1734682D01*
X152946Y1734599D01*
X153238Y1734390D01*
X153321Y1734140D01*
X153279Y1733890D01*
X153113Y1733682D01*
X152279Y1733265D01*
X151904Y1732974D01*
X151654Y1732557D01*
X151571Y1732182D01*
X153321D01*
G01X154629Y1732557D02*
X154879Y1732349D01*
X155171Y1732224D01*
X155546Y1732182D01*
X155921Y1732265D01*
X156213Y1732432D01*
X156421Y1732724D01*
X156463Y1733057D01*
X156379Y1733390D01*
X156171Y1733599D01*
X155879Y1733765D01*
X155588Y1733807D01*
X155296Y1733765D01*
X154921Y1733599D01*
X155046Y1734682D01*
X156171D01*
G01X157729Y1732682D02*
X157979Y1732390D01*
X158313Y1732224D01*
X158688Y1732182D01*
X159021Y1732224D01*
X159354Y1732432D01*
X159563Y1732682D01*
X159604Y1732932D01*
X159521Y1733224D01*
X159229Y1733432D01*
X158938Y1733515D01*
X158563D01*
G01X158938D02*
X159188Y1733640D01*
X159396Y1733849D01*
X159479Y1734099D01*
X159396Y1734349D01*
X159188Y1734557D01*
X158813Y1734682D01*
X158438Y1734640D01*
X158063Y1734474D01*
G01X127517Y1730000D02*
Y1732500D01*
X128558D01*
X128892Y1732375D01*
X129100Y1732208D01*
X129183Y1731875D01*
X129100Y1731542D01*
X128850Y1731333D01*
X128558Y1731208D01*
X127517D01*
G01X128558D02*
X129183Y1730000D01*
G01X131950D02*
Y1732500D01*
X130408Y1730708D01*
X132492D01*
G01X133758Y1731042D02*
X134050Y1731333D01*
X134300Y1731500D01*
X134633Y1731583D01*
X134925Y1731500D01*
X135133Y1731333D01*
X135300Y1731083D01*
X135342Y1730792D01*
X135300Y1730542D01*
X135133Y1730292D01*
X134883Y1730083D01*
X134592Y1730000D01*
X134258Y1730083D01*
X133967Y1730333D01*
X133800Y1730708D01*
X133758Y1731125D01*
X133842Y1731667D01*
X133967Y1731958D01*
X134175Y1732250D01*
X134467Y1732458D01*
X134758Y1732500D01*
X135050Y1732417D01*
X135258Y1732208D01*
G01X136858Y1732083D02*
X137108Y1732333D01*
X137400Y1732458D01*
X137733Y1732500D01*
X138150Y1732417D01*
X138442Y1732208D01*
X138525Y1731958D01*
X138483Y1731708D01*
X138317Y1731500D01*
X137483Y1731083D01*
X137108Y1730792D01*
X136858Y1730375D01*
X136775Y1730000D01*
X138525D01*
G01X127517Y1726500D02*
Y1729000D01*
X128558D01*
X128892Y1728875D01*
X129100Y1728708D01*
X129183Y1728375D01*
X129100Y1728042D01*
X128850Y1727833D01*
X128558Y1727708D01*
X127517D01*
G01X128558D02*
X129183Y1726500D01*
G01X131950D02*
Y1729000D01*
X130408Y1727208D01*
X132492D01*
G01X133758Y1727542D02*
X134050Y1727833D01*
X134300Y1728000D01*
X134633Y1728083D01*
X134925Y1728000D01*
X135133Y1727833D01*
X135300Y1727583D01*
X135342Y1727292D01*
X135300Y1727042D01*
X135133Y1726792D01*
X134883Y1726583D01*
X134592Y1726500D01*
X134258Y1726583D01*
X133967Y1726833D01*
X133800Y1727208D01*
X133758Y1727625D01*
X133842Y1728167D01*
X133967Y1728458D01*
X134175Y1728750D01*
X134467Y1728958D01*
X134758Y1729000D01*
X135050Y1728917D01*
X135258Y1728708D01*
G01X136733Y1727000D02*
X136983Y1726708D01*
X137317Y1726542D01*
X137692Y1726500D01*
X138025Y1726542D01*
X138358Y1726750D01*
X138567Y1727000D01*
X138608Y1727250D01*
X138525Y1727542D01*
X138233Y1727750D01*
X137942Y1727833D01*
X137567D01*
G01X137942D02*
X138192Y1727958D01*
X138400Y1728167D01*
X138483Y1728417D01*
X138400Y1728667D01*
X138192Y1728875D01*
X137817Y1729000D01*
X137442Y1728958D01*
X137067Y1728792D01*
G01X115483Y1728000D02*
Y1726208D01*
X115650Y1725833D01*
X115983Y1725583D01*
X116400Y1725500D01*
X116817Y1725583D01*
X117150Y1725833D01*
X117317Y1726208D01*
Y1728000D01*
G01X118583Y1726000D02*
X118833Y1725708D01*
X119167Y1725542D01*
X119542Y1725500D01*
X119875Y1725542D01*
X120208Y1725750D01*
X120417Y1726000D01*
X120458Y1726250D01*
X120375Y1726542D01*
X120083Y1726750D01*
X119792Y1726833D01*
X119417D01*
G01X119792D02*
X120042Y1726958D01*
X120250Y1727167D01*
X120333Y1727417D01*
X120250Y1727667D01*
X120042Y1727875D01*
X119667Y1728000D01*
X119292Y1727958D01*
X118917Y1727792D01*
G01X122600Y1725500D02*
Y1728000D01*
X122100Y1727500D01*
G01Y1725500D02*
X123100D01*
G01X140983Y1729500D02*
Y1727708D01*
X141150Y1727333D01*
X141483Y1727083D01*
X141900Y1727000D01*
X142317Y1727083D01*
X142650Y1727333D01*
X142817Y1727708D01*
Y1729500D01*
G01X144083Y1727500D02*
X144333Y1727208D01*
X144667Y1727042D01*
X145042Y1727000D01*
X145375Y1727042D01*
X145708Y1727250D01*
X145917Y1727500D01*
X145958Y1727750D01*
X145875Y1728042D01*
X145583Y1728250D01*
X145292Y1728333D01*
X144917D01*
G01X145292D02*
X145542Y1728458D01*
X145750Y1728667D01*
X145833Y1728917D01*
X145750Y1729167D01*
X145542Y1729375D01*
X145167Y1729500D01*
X144792Y1729458D01*
X144417Y1729292D01*
G01X147183Y1727500D02*
X147433Y1727208D01*
X147767Y1727042D01*
X148142Y1727000D01*
X148475Y1727042D01*
X148808Y1727250D01*
X149017Y1727500D01*
X149058Y1727750D01*
X148975Y1728042D01*
X148683Y1728250D01*
X148392Y1728333D01*
X148017D01*
G01X148392D02*
X148642Y1728458D01*
X148850Y1728667D01*
X148933Y1728917D01*
X148850Y1729167D01*
X148642Y1729375D01*
X148267Y1729500D01*
X147892Y1729458D01*
X147517Y1729292D01*
G01X130499Y1724750D02*
X140499D01*
G01X144623Y1807865D02*
Y1969065D01*
X158223D01*
Y1982015D01*
X176423D01*
Y1969065D01*
X205323D01*
Y1958715D01*
X198623D01*
Y1818215D01*
X205323D01*
Y1807865D01*
X176423D01*
Y1794915D01*
X158223D01*
Y1807865D01*
X144623D01*
G01X115859Y1847546D02*
X115609Y1847671D01*
X115317Y1847754D01*
X114984D01*
X114609Y1847629D01*
X114317Y1847421D01*
X114109Y1847171D01*
X113942Y1846754D01*
X113900Y1846379D01*
X113984Y1846004D01*
X114109Y1845754D01*
X114359Y1845504D01*
X114650Y1845337D01*
X114942Y1845254D01*
X115234D01*
X115525Y1845337D01*
X115775Y1845462D01*
X115984Y1845629D01*
G01X118042Y1845254D02*
Y1847754D01*
X117542Y1847254D01*
G01Y1845254D02*
X118542D01*
G01X121142D02*
X121434Y1845296D01*
X121767Y1845421D01*
X121975Y1845629D01*
X122059Y1845921D01*
X121975Y1846212D01*
X121725Y1846462D01*
X121350Y1846587D01*
X120934D01*
X120684Y1846671D01*
X120475Y1846879D01*
X120392Y1847171D01*
X120517Y1847462D01*
X120809Y1847671D01*
X121142Y1847754D01*
X121475Y1847671D01*
X121767Y1847462D01*
X121892Y1847171D01*
X121809Y1846879D01*
X121600Y1846671D01*
X121350Y1846587D01*
X120934D01*
X120559Y1846462D01*
X120309Y1846212D01*
X120225Y1845921D01*
X120309Y1845629D01*
X120517Y1845421D01*
X120850Y1845296D01*
X121142Y1845254D01*
G01X123450Y1847337D02*
X123700Y1847587D01*
X123992Y1847712D01*
X124325Y1847754D01*
X124742Y1847671D01*
X125034Y1847462D01*
X125117Y1847212D01*
X125075Y1846962D01*
X124909Y1846754D01*
X124075Y1846337D01*
X123700Y1846046D01*
X123450Y1845629D01*
X123367Y1845254D01*
X125117D01*
G01X115859Y1851046D02*
X115609Y1851171D01*
X115317Y1851254D01*
X114984D01*
X114609Y1851129D01*
X114317Y1850921D01*
X114109Y1850671D01*
X113942Y1850254D01*
X113900Y1849879D01*
X113984Y1849504D01*
X114109Y1849254D01*
X114359Y1849004D01*
X114650Y1848837D01*
X114942Y1848754D01*
X115234D01*
X115525Y1848837D01*
X115775Y1848962D01*
X115984Y1849129D01*
G01X118042Y1848754D02*
Y1851254D01*
X117542Y1850754D01*
G01Y1848754D02*
X118542D01*
G01X121142D02*
X121434Y1848796D01*
X121767Y1848921D01*
X121975Y1849129D01*
X122059Y1849421D01*
X121975Y1849712D01*
X121725Y1849962D01*
X121350Y1850087D01*
X120934D01*
X120684Y1850171D01*
X120475Y1850379D01*
X120392Y1850671D01*
X120517Y1850962D01*
X120809Y1851171D01*
X121142Y1851254D01*
X121475Y1851171D01*
X121767Y1850962D01*
X121892Y1850671D01*
X121809Y1850379D01*
X121600Y1850171D01*
X121350Y1850087D01*
X120934D01*
X120559Y1849962D01*
X120309Y1849712D01*
X120225Y1849421D01*
X120309Y1849129D01*
X120517Y1848921D01*
X120850Y1848796D01*
X121142Y1848754D01*
G01X123325Y1849254D02*
X123575Y1848962D01*
X123909Y1848796D01*
X124284Y1848754D01*
X124617Y1848796D01*
X124950Y1849004D01*
X125159Y1849254D01*
X125200Y1849504D01*
X125117Y1849796D01*
X124825Y1850004D01*
X124534Y1850087D01*
X124159D01*
G01X124534D02*
X124784Y1850212D01*
X124992Y1850421D01*
X125075Y1850671D01*
X124992Y1850921D01*
X124784Y1851129D01*
X124409Y1851254D01*
X124034Y1851212D01*
X123659Y1851046D01*
G01X127167Y1863192D02*
X126917Y1863317D01*
X126625Y1863400D01*
X126292D01*
X125917Y1863275D01*
X125625Y1863067D01*
X125417Y1862817D01*
X125250Y1862400D01*
X125208Y1862025D01*
X125292Y1861650D01*
X125417Y1861400D01*
X125667Y1861150D01*
X125958Y1860983D01*
X126250Y1860900D01*
X126542D01*
X126833Y1860983D01*
X127083Y1861108D01*
X127292Y1861275D01*
G01X129350Y1860900D02*
Y1863400D01*
X128850Y1862900D01*
G01Y1860900D02*
X129850D01*
G01X132450D02*
X132742Y1860942D01*
X133075Y1861067D01*
X133283Y1861275D01*
X133367Y1861567D01*
X133283Y1861858D01*
X133033Y1862108D01*
X132658Y1862233D01*
X132242D01*
X131992Y1862317D01*
X131783Y1862525D01*
X131700Y1862817D01*
X131825Y1863108D01*
X132117Y1863317D01*
X132450Y1863400D01*
X132783Y1863317D01*
X133075Y1863108D01*
X133200Y1862817D01*
X133117Y1862525D01*
X132908Y1862317D01*
X132658Y1862233D01*
X132242D01*
X131867Y1862108D01*
X131617Y1861858D01*
X131533Y1861567D01*
X131617Y1861275D01*
X131825Y1861067D01*
X132158Y1860942D01*
X132450Y1860900D01*
G01X136050D02*
Y1863400D01*
X134508Y1861608D01*
X136592D01*
G01X127359Y1867546D02*
X127109Y1867671D01*
X126817Y1867754D01*
X126484D01*
X126109Y1867629D01*
X125817Y1867421D01*
X125609Y1867171D01*
X125442Y1866754D01*
X125400Y1866379D01*
X125484Y1866004D01*
X125609Y1865754D01*
X125859Y1865504D01*
X126150Y1865337D01*
X126442Y1865254D01*
X126734D01*
X127025Y1865337D01*
X127275Y1865462D01*
X127484Y1865629D01*
G01X129542Y1865254D02*
Y1867754D01*
X129042Y1867254D01*
G01Y1865254D02*
X130042D01*
G01X132642D02*
X132934Y1865296D01*
X133267Y1865421D01*
X133475Y1865629D01*
X133559Y1865921D01*
X133475Y1866212D01*
X133225Y1866462D01*
X132850Y1866587D01*
X132434D01*
X132184Y1866671D01*
X131975Y1866879D01*
X131892Y1867171D01*
X132017Y1867462D01*
X132309Y1867671D01*
X132642Y1867754D01*
X132975Y1867671D01*
X133267Y1867462D01*
X133392Y1867171D01*
X133309Y1866879D01*
X133100Y1866671D01*
X132850Y1866587D01*
X132434D01*
X132059Y1866462D01*
X131809Y1866212D01*
X131725Y1865921D01*
X131809Y1865629D01*
X132017Y1865421D01*
X132350Y1865296D01*
X132642Y1865254D01*
G01X134825Y1865629D02*
X135075Y1865421D01*
X135367Y1865296D01*
X135742Y1865254D01*
X136117Y1865337D01*
X136409Y1865504D01*
X136617Y1865796D01*
X136659Y1866129D01*
X136575Y1866462D01*
X136367Y1866671D01*
X136075Y1866837D01*
X135784Y1866879D01*
X135492Y1866837D01*
X135117Y1866671D01*
X135242Y1867754D01*
X136367D01*
G01X125817Y1884400D02*
Y1886900D01*
X126817D01*
X127150Y1886775D01*
X127400Y1886483D01*
X127483Y1886150D01*
X127400Y1885817D01*
X127192Y1885567D01*
X126817Y1885442D01*
X125817D01*
G01X129750Y1886900D02*
Y1884400D01*
G01X128792Y1886900D02*
X130708D01*
G01X133767Y1886692D02*
X133517Y1886817D01*
X133225Y1886900D01*
X132892D01*
X132517Y1886775D01*
X132225Y1886567D01*
X132017Y1886317D01*
X131850Y1885900D01*
X131808Y1885525D01*
X131892Y1885150D01*
X132017Y1884900D01*
X132267Y1884650D01*
X132558Y1884483D01*
X132850Y1884400D01*
X133142D01*
X133433Y1884483D01*
X133683Y1884608D01*
X133892Y1884775D01*
G01X135033D02*
X135283Y1884567D01*
X135575Y1884442D01*
X135950Y1884400D01*
X136325Y1884483D01*
X136617Y1884650D01*
X136825Y1884942D01*
X136867Y1885275D01*
X136783Y1885608D01*
X136575Y1885817D01*
X136283Y1885983D01*
X135992Y1886025D01*
X135700Y1885983D01*
X135325Y1885817D01*
X135450Y1886900D01*
X136575D01*
G01X122699Y1881550D02*
X111499D01*
G01X122699Y1899550D02*
Y1881550D01*
G01X125817Y1879100D02*
Y1881600D01*
X126817D01*
X127150Y1881475D01*
X127400Y1881183D01*
X127483Y1880850D01*
X127400Y1880517D01*
X127192Y1880267D01*
X126817Y1880142D01*
X125817D01*
G01X129750Y1881600D02*
Y1879100D01*
G01X128792Y1881600D02*
X130708D01*
G01X133767Y1881392D02*
X133517Y1881517D01*
X133225Y1881600D01*
X132892D01*
X132517Y1881475D01*
X132225Y1881267D01*
X132017Y1881017D01*
X131850Y1880600D01*
X131808Y1880225D01*
X131892Y1879850D01*
X132017Y1879600D01*
X132267Y1879350D01*
X132558Y1879183D01*
X132850Y1879100D01*
X133142D01*
X133433Y1879183D01*
X133683Y1879308D01*
X133892Y1879475D01*
G01X135158Y1880142D02*
X135450Y1880433D01*
X135700Y1880600D01*
X136033Y1880683D01*
X136325Y1880600D01*
X136533Y1880433D01*
X136700Y1880183D01*
X136742Y1879892D01*
X136700Y1879642D01*
X136533Y1879392D01*
X136283Y1879183D01*
X135992Y1879100D01*
X135658Y1879183D01*
X135367Y1879433D01*
X135200Y1879808D01*
X135158Y1880225D01*
X135242Y1880767D01*
X135367Y1881058D01*
X135575Y1881350D01*
X135867Y1881558D01*
X136158Y1881600D01*
X136450Y1881517D01*
X136658Y1881308D01*
G01X122699Y1861050D02*
X111499D01*
G01X122699Y1879050D02*
Y1861050D01*
G01X111499Y1879050D02*
X122699D01*
G01X124799Y1969150D02*
X102199D01*
G01X124799Y1958950D02*
Y1969150D01*
G01X102199Y1958950D02*
X124799D01*
G01X102199Y1969150D02*
Y1958950D01*
G01X124799Y1969150D02*
X102199D01*
G01X124799Y1958950D02*
Y1969150D01*
G01X102199Y1958950D02*
X124799D01*
G01X102199Y1969150D02*
Y1958950D01*
G01X122767Y1925600D02*
Y1928100D01*
X123767D01*
X124100Y1927975D01*
X124350Y1927683D01*
X124433Y1927350D01*
X124350Y1927017D01*
X124142Y1926767D01*
X123767Y1926642D01*
X122767D01*
G01X125867Y1928100D02*
Y1925600D01*
X127533D01*
G01X129008Y1926642D02*
X129300Y1926933D01*
X129550Y1927100D01*
X129883Y1927183D01*
X130175Y1927100D01*
X130383Y1926933D01*
X130550Y1926683D01*
X130592Y1926392D01*
X130550Y1926142D01*
X130383Y1925892D01*
X130133Y1925683D01*
X129842Y1925600D01*
X129508Y1925683D01*
X129217Y1925933D01*
X129050Y1926308D01*
X129008Y1926725D01*
X129092Y1927267D01*
X129217Y1927558D01*
X129425Y1927850D01*
X129717Y1928058D01*
X130008Y1928100D01*
X130300Y1928017D01*
X130508Y1927808D01*
G01X111499Y1899550D02*
X122699D01*
G01X110566Y1972050D02*
Y1974550D01*
X111566D01*
X111899Y1974425D01*
X112149Y1974133D01*
X112232Y1973800D01*
X112149Y1973467D01*
X111941Y1973217D01*
X111566Y1973092D01*
X110566D01*
G01X113666Y1974550D02*
Y1972050D01*
X115332D01*
G01X116682Y1972425D02*
X116932Y1972217D01*
X117224Y1972092D01*
X117599Y1972050D01*
X117974Y1972133D01*
X118266Y1972300D01*
X118474Y1972592D01*
X118516Y1972925D01*
X118432Y1973258D01*
X118224Y1973467D01*
X117932Y1973633D01*
X117641Y1973675D01*
X117349Y1973633D01*
X116974Y1973467D01*
X117099Y1974550D01*
X118224D01*
G01X184800Y41517D02*
X182300D01*
Y42517D01*
X182425Y42850D01*
X182717Y43100D01*
X183050Y43183D01*
X183383Y43100D01*
X183633Y42892D01*
X183758Y42517D01*
Y41517D01*
G01X182508Y46367D02*
X182383Y46117D01*
X182300Y45825D01*
Y45492D01*
X182425Y45117D01*
X182633Y44825D01*
X182883Y44617D01*
X183300Y44450D01*
X183675Y44408D01*
X184050Y44492D01*
X184300Y44617D01*
X184550Y44867D01*
X184717Y45158D01*
X184800Y45450D01*
Y45742D01*
X184717Y46033D01*
X184592Y46283D01*
X184425Y46492D01*
G01X182717Y47758D02*
X182467Y48008D01*
X182342Y48300D01*
X182300Y48633D01*
X182383Y49050D01*
X182592Y49342D01*
X182842Y49425D01*
X183092Y49383D01*
X183300Y49217D01*
X183717Y48383D01*
X184008Y48008D01*
X184425Y47758D01*
X184800Y47675D01*
Y49425D01*
G01X182300Y51650D02*
X182383Y51317D01*
X182592Y51067D01*
X182842Y50900D01*
X183175Y50775D01*
X183550Y50733D01*
X183925Y50775D01*
X184258Y50900D01*
X184508Y51067D01*
X184717Y51317D01*
X184800Y51650D01*
X184717Y51983D01*
X184508Y52233D01*
X184258Y52400D01*
X183925Y52525D01*
X183550Y52567D01*
X183175Y52525D01*
X182842Y52400D01*
X182592Y52233D01*
X182383Y51983D01*
X182300Y51650D01*
G01X209167Y28100D02*
Y30600D01*
X210167D01*
X210500Y30475D01*
X210750Y30183D01*
X210833Y29850D01*
X210750Y29517D01*
X210542Y29267D01*
X210167Y29142D01*
X209167D01*
G01X212267Y30600D02*
Y28100D01*
X213933D01*
G01X215283Y28600D02*
X215533Y28308D01*
X215867Y28142D01*
X216242Y28100D01*
X216575Y28142D01*
X216908Y28350D01*
X217117Y28600D01*
X217158Y28850D01*
X217075Y29142D01*
X216783Y29350D01*
X216492Y29433D01*
X216117D01*
G01X216492D02*
X216742Y29558D01*
X216950Y29767D01*
X217033Y30017D01*
X216950Y30267D01*
X216742Y30475D01*
X216367Y30600D01*
X215992Y30558D01*
X215617Y30392D01*
G01X202699Y34450D02*
X225299D01*
G01X202699Y44650D02*
Y34450D01*
G01X225299Y44650D02*
X202699D01*
G01X225299Y34450D02*
Y44650D01*
G01X202699Y34450D02*
X225299D01*
G01X202699Y44650D02*
Y34450D01*
G01X225299Y44650D02*
X202699D01*
G01X225299Y34450D02*
Y44650D01*
G01X205867Y51200D02*
Y53700D01*
X206867D01*
X207200Y53575D01*
X207450Y53283D01*
X207533Y52950D01*
X207450Y52617D01*
X207242Y52367D01*
X206867Y52242D01*
X205867D01*
G01X208883Y53700D02*
Y51908D01*
X209050Y51533D01*
X209383Y51283D01*
X209800Y51200D01*
X210217Y51283D01*
X210550Y51533D01*
X210717Y51908D01*
Y53700D01*
G01X212108Y53283D02*
X212358Y53533D01*
X212650Y53658D01*
X212983Y53700D01*
X213400Y53617D01*
X213692Y53408D01*
X213775Y53158D01*
X213733Y52908D01*
X213567Y52700D01*
X212733Y52283D01*
X212358Y51992D01*
X212108Y51575D01*
X212025Y51200D01*
X213775D01*
G01X219526Y58528D02*
X224526D01*
Y63528D01*
G01X196826D02*
Y58528D01*
X201826D01*
G01X197833Y64654D02*
X194833D01*
G01X245117Y32600D02*
Y35100D01*
X246117D01*
X246450Y34975D01*
X246700Y34683D01*
X246783Y34350D01*
X246700Y34017D01*
X246492Y33767D01*
X246117Y33642D01*
X245117D01*
G01X249967Y34892D02*
X249717Y35017D01*
X249425Y35100D01*
X249092D01*
X248717Y34975D01*
X248425Y34767D01*
X248217Y34517D01*
X248050Y34100D01*
X248008Y33725D01*
X248092Y33350D01*
X248217Y33100D01*
X248467Y32850D01*
X248758Y32683D01*
X249050Y32600D01*
X249342D01*
X249633Y32683D01*
X249883Y32808D01*
X250092Y32975D01*
G01X252150Y32600D02*
Y35100D01*
X251650Y34600D01*
G01Y32600D02*
X252650D01*
G01X255250D02*
X255542Y32642D01*
X255875Y32767D01*
X256083Y32975D01*
X256167Y33267D01*
X256083Y33558D01*
X255833Y33808D01*
X255458Y33933D01*
X255042D01*
X254792Y34017D01*
X254583Y34225D01*
X254500Y34517D01*
X254625Y34808D01*
X254917Y35017D01*
X255250Y35100D01*
X255583Y35017D01*
X255875Y34808D01*
X256000Y34517D01*
X255917Y34225D01*
X255708Y34017D01*
X255458Y33933D01*
X255042D01*
X254667Y33808D01*
X254417Y33558D01*
X254333Y33267D01*
X254417Y32975D01*
X254625Y32767D01*
X254958Y32642D01*
X255250Y32600D01*
G01X244917Y50800D02*
Y53300D01*
X245917D01*
X246250Y53175D01*
X246500Y52883D01*
X246583Y52550D01*
X246500Y52217D01*
X246292Y51967D01*
X245917Y51842D01*
X244917D01*
G01X249767Y53092D02*
X249517Y53217D01*
X249225Y53300D01*
X248892D01*
X248517Y53175D01*
X248225Y52967D01*
X248017Y52717D01*
X247850Y52300D01*
X247808Y51925D01*
X247892Y51550D01*
X248017Y51300D01*
X248267Y51050D01*
X248558Y50883D01*
X248850Y50800D01*
X249142D01*
X249433Y50883D01*
X249683Y51008D01*
X249892Y51175D01*
G01X251158Y52883D02*
X251408Y53133D01*
X251700Y53258D01*
X252033Y53300D01*
X252450Y53217D01*
X252742Y53008D01*
X252825Y52758D01*
X252783Y52508D01*
X252617Y52300D01*
X251783Y51883D01*
X251408Y51592D01*
X251158Y51175D01*
X251075Y50800D01*
X252825D01*
G01X254258Y52883D02*
X254508Y53133D01*
X254800Y53258D01*
X255133Y53300D01*
X255550Y53217D01*
X255842Y53008D01*
X255925Y52758D01*
X255883Y52508D01*
X255717Y52300D01*
X254883Y51883D01*
X254508Y51592D01*
X254258Y51175D01*
X254175Y50800D01*
X255925D01*
G01X245417Y41700D02*
Y44200D01*
X246417D01*
X246750Y44075D01*
X247000Y43783D01*
X247083Y43450D01*
X247000Y43117D01*
X246792Y42867D01*
X246417Y42742D01*
X245417D01*
G01X250267Y43992D02*
X250017Y44117D01*
X249725Y44200D01*
X249392D01*
X249017Y44075D01*
X248725Y43867D01*
X248517Y43617D01*
X248350Y43200D01*
X248308Y42825D01*
X248392Y42450D01*
X248517Y42200D01*
X248767Y41950D01*
X249058Y41783D01*
X249350Y41700D01*
X249642D01*
X249933Y41783D01*
X250183Y41908D01*
X250392Y42075D01*
G01X251658Y43783D02*
X251908Y44033D01*
X252200Y44158D01*
X252533Y44200D01*
X252950Y44117D01*
X253242Y43908D01*
X253325Y43658D01*
X253283Y43408D01*
X253117Y43200D01*
X252283Y42783D01*
X251908Y42492D01*
X251658Y42075D01*
X251575Y41700D01*
X253325D01*
G01X256050D02*
Y44200D01*
X254508Y42408D01*
X256592D01*
G01X245417Y59500D02*
Y62000D01*
X246417D01*
X246750Y61875D01*
X247000Y61583D01*
X247083Y61250D01*
X247000Y60917D01*
X246792Y60667D01*
X246417Y60542D01*
X245417D01*
G01X250267Y61792D02*
X250017Y61917D01*
X249725Y62000D01*
X249392D01*
X249017Y61875D01*
X248725Y61667D01*
X248517Y61417D01*
X248350Y61000D01*
X248308Y60625D01*
X248392Y60250D01*
X248517Y60000D01*
X248767Y59750D01*
X249058Y59583D01*
X249350Y59500D01*
X249642D01*
X249933Y59583D01*
X250183Y59708D01*
X250392Y59875D01*
G01X252450Y59500D02*
Y62000D01*
X251950Y61500D01*
G01Y59500D02*
X252950D01*
G01X256050D02*
Y62000D01*
X254508Y60208D01*
X256592D01*
G01X201600Y12800D02*
Y17800D01*
X203600D01*
X204200Y17500D01*
X204700Y17000D01*
X204900Y16300D01*
X204700Y15600D01*
X204300Y15100D01*
X203600Y14900D01*
X201600D01*
G01X197600Y12800D02*
X197000Y12900D01*
X196400Y13200D01*
X195900Y13700D01*
X195500Y14300D01*
X195400Y15000D01*
Y15600D01*
X195500Y16300D01*
X195900Y16900D01*
X196400Y17400D01*
X197000Y17700D01*
X197600Y17800D01*
X198300Y17700D01*
X198900Y17400D01*
X199400Y16900D01*
X199700Y16300D01*
X199900Y15600D01*
Y15000D01*
X199700Y14300D01*
X199400Y13700D01*
X198900Y13200D01*
X198300Y12900D01*
X197600Y12800D01*
G01X192000Y17800D02*
Y12800D01*
G01X188700Y11400D02*
Y19200D01*
X206300D01*
Y11400D01*
X188700D01*
G01X190100Y17800D02*
X193900D01*
G01X251400Y80917D02*
X248900D01*
Y81917D01*
X249025Y82250D01*
X249317Y82500D01*
X249650Y82583D01*
X249983Y82500D01*
X250233Y82292D01*
X250358Y81917D01*
Y80917D01*
G01X249108Y85767D02*
X248983Y85517D01*
X248900Y85225D01*
Y84892D01*
X249025Y84517D01*
X249233Y84225D01*
X249483Y84017D01*
X249900Y83850D01*
X250275Y83808D01*
X250650Y83892D01*
X250900Y84017D01*
X251150Y84267D01*
X251317Y84558D01*
X251400Y84850D01*
Y85142D01*
X251317Y85433D01*
X251192Y85683D01*
X251025Y85892D01*
G01X251400Y87950D02*
X248900D01*
X249400Y87450D01*
G01X251400D02*
Y88450D01*
G01Y90967D02*
X250858Y91050D01*
X250400Y91175D01*
X249983Y91342D01*
X249525Y91550D01*
X248900Y91883D01*
Y90217D01*
G01X214500Y105717D02*
X212000D01*
Y106717D01*
X212125Y107050D01*
X212417Y107300D01*
X212750Y107383D01*
X213083Y107300D01*
X213333Y107092D01*
X213458Y106717D01*
Y105717D01*
G01X212208Y110567D02*
X212083Y110317D01*
X212000Y110025D01*
Y109692D01*
X212125Y109317D01*
X212333Y109025D01*
X212583Y108817D01*
X213000Y108650D01*
X213375Y108608D01*
X213750Y108692D01*
X214000Y108817D01*
X214250Y109067D01*
X214417Y109358D01*
X214500Y109650D01*
Y109942D01*
X214417Y110233D01*
X214292Y110483D01*
X214125Y110692D01*
G01X214500Y112750D02*
X212000D01*
X212500Y112250D01*
G01X214500D02*
Y113250D01*
G01X214208Y115142D02*
X214417Y115433D01*
X214500Y115767D01*
X214417Y116100D01*
X214167Y116392D01*
X213792Y116600D01*
X213417Y116683D01*
X212958D01*
X212583Y116600D01*
X212250Y116392D01*
X212083Y116142D01*
X212000Y115850D01*
X212083Y115517D01*
X212250Y115267D01*
X212500Y115100D01*
X212833Y115017D01*
X213125Y115100D01*
X213417Y115308D01*
X213583Y115558D01*
X213625Y115850D01*
X213542Y116183D01*
X213333Y116433D01*
X212958Y116683D01*
G01X226516Y117550D02*
Y120050D01*
X227516D01*
X227849Y119925D01*
X228099Y119633D01*
X228182Y119300D01*
X228099Y118967D01*
X227891Y118717D01*
X227516Y118592D01*
X226516D01*
G01X229616Y117550D02*
Y120050D01*
X230657D01*
X230991Y119925D01*
X231199Y119758D01*
X231282Y119425D01*
X231199Y119092D01*
X230949Y118883D01*
X230657Y118758D01*
X229616D01*
G01X230657D02*
X231282Y117550D01*
G01X233549D02*
Y120050D01*
X233049Y119550D01*
G01Y117550D02*
X234049D01*
G01X236649D02*
X236941Y117592D01*
X237274Y117717D01*
X237482Y117925D01*
X237566Y118217D01*
X237482Y118508D01*
X237232Y118758D01*
X236857Y118883D01*
X236441D01*
X236191Y118967D01*
X235982Y119175D01*
X235899Y119467D01*
X236024Y119758D01*
X236316Y119967D01*
X236649Y120050D01*
X236982Y119967D01*
X237274Y119758D01*
X237399Y119467D01*
X237316Y119175D01*
X237107Y118967D01*
X236857Y118883D01*
X236441D01*
X236066Y118758D01*
X235816Y118508D01*
X235732Y118217D01*
X235816Y117925D01*
X236024Y117717D01*
X236357Y117592D01*
X236649Y117550D01*
G01X228299Y103050D02*
Y99050D01*
X235699D01*
G01X226516Y121550D02*
Y124050D01*
X227516D01*
X227849Y123925D01*
X228099Y123633D01*
X228182Y123300D01*
X228099Y122967D01*
X227891Y122717D01*
X227516Y122592D01*
X226516D01*
G01X229616Y121550D02*
Y124050D01*
X230657D01*
X230991Y123925D01*
X231199Y123758D01*
X231282Y123425D01*
X231199Y123092D01*
X230949Y122883D01*
X230657Y122758D01*
X229616D01*
G01X230657D02*
X231282Y121550D01*
G01X232757Y123633D02*
X233007Y123883D01*
X233299Y124008D01*
X233632Y124050D01*
X234049Y123967D01*
X234341Y123758D01*
X234424Y123508D01*
X234382Y123258D01*
X234216Y123050D01*
X233382Y122633D01*
X233007Y122342D01*
X232757Y121925D01*
X232674Y121550D01*
X234424D01*
G01X235857Y123633D02*
X236107Y123883D01*
X236399Y124008D01*
X236732Y124050D01*
X237149Y123967D01*
X237441Y123758D01*
X237524Y123508D01*
X237482Y123258D01*
X237316Y123050D01*
X236482Y122633D01*
X236107Y122342D01*
X235857Y121925D01*
X235774Y121550D01*
X237524D01*
G01X235699Y103050D02*
Y107050D01*
X228299D01*
G01X206499Y105567D02*
X203999D01*
Y106567D01*
X204124Y106900D01*
X204416Y107150D01*
X204749Y107233D01*
X205082Y107150D01*
X205332Y106942D01*
X205457Y106567D01*
Y105567D01*
G01X206499Y108667D02*
X203999D01*
Y109708D01*
X204124Y110042D01*
X204291Y110250D01*
X204624Y110333D01*
X204957Y110250D01*
X205166Y110000D01*
X205291Y109708D01*
Y108667D01*
G01Y109708D02*
X206499Y110333D01*
G01X204416Y111808D02*
X204166Y112058D01*
X204041Y112350D01*
X203999Y112683D01*
X204082Y113100D01*
X204291Y113392D01*
X204541Y113475D01*
X204791Y113433D01*
X204999Y113267D01*
X205416Y112433D01*
X205707Y112058D01*
X206124Y111808D01*
X206499Y111725D01*
Y113475D01*
G01X206124Y114783D02*
X206332Y115033D01*
X206457Y115325D01*
X206499Y115700D01*
X206416Y116075D01*
X206249Y116367D01*
X205957Y116575D01*
X205624Y116617D01*
X205291Y116533D01*
X205082Y116325D01*
X204916Y116033D01*
X204874Y115742D01*
X204916Y115450D01*
X205082Y115075D01*
X203999Y115200D01*
Y116325D01*
G01X207499Y103250D02*
X203499D01*
Y95850D01*
G01X245016Y94550D02*
Y97050D01*
X246016D01*
X246349Y96925D01*
X246599Y96633D01*
X246682Y96300D01*
X246599Y95967D01*
X246391Y95717D01*
X246016Y95592D01*
X245016D01*
G01X248116Y94550D02*
Y97050D01*
X249157D01*
X249491Y96925D01*
X249699Y96758D01*
X249782Y96425D01*
X249699Y96092D01*
X249449Y95883D01*
X249157Y95758D01*
X248116D01*
G01X249157D02*
X249782Y94550D01*
G01X251257Y96633D02*
X251507Y96883D01*
X251799Y97008D01*
X252132Y97050D01*
X252549Y96967D01*
X252841Y96758D01*
X252924Y96508D01*
X252882Y96258D01*
X252716Y96050D01*
X251882Y95633D01*
X251507Y95342D01*
X251257Y94925D01*
X251174Y94550D01*
X252924D01*
G01X254357Y95592D02*
X254649Y95883D01*
X254899Y96050D01*
X255232Y96133D01*
X255524Y96050D01*
X255732Y95883D01*
X255899Y95633D01*
X255941Y95342D01*
X255899Y95092D01*
X255732Y94842D01*
X255482Y94633D01*
X255191Y94550D01*
X254857Y94633D01*
X254566Y94883D01*
X254399Y95258D01*
X254357Y95675D01*
X254441Y96217D01*
X254566Y96508D01*
X254774Y96800D01*
X255066Y97008D01*
X255357Y97050D01*
X255649Y96967D01*
X255857Y96758D01*
G01X243699Y93550D02*
Y97550D01*
X236299D01*
G01X210499Y105567D02*
X207999D01*
Y106567D01*
X208124Y106900D01*
X208416Y107150D01*
X208749Y107233D01*
X209082Y107150D01*
X209332Y106942D01*
X209457Y106567D01*
Y105567D01*
G01X210499Y108667D02*
X207999D01*
Y109708D01*
X208124Y110042D01*
X208291Y110250D01*
X208624Y110333D01*
X208957Y110250D01*
X209166Y110000D01*
X209291Y109708D01*
Y108667D01*
G01Y109708D02*
X210499Y110333D01*
G01X208416Y111808D02*
X208166Y112058D01*
X208041Y112350D01*
X207999Y112683D01*
X208082Y113100D01*
X208291Y113392D01*
X208541Y113475D01*
X208791Y113433D01*
X208999Y113267D01*
X209416Y112433D01*
X209707Y112058D01*
X210124Y111808D01*
X210499Y111725D01*
Y113475D01*
G01Y115617D02*
X209957Y115700D01*
X209499Y115825D01*
X209082Y115992D01*
X208624Y116200D01*
X207999Y116533D01*
Y114867D01*
G01X207499Y95850D02*
X211499D01*
Y103250D01*
G01X226389Y109072D02*
Y111572D01*
X227389D01*
X227722Y111447D01*
X227972Y111155D01*
X228055Y110822D01*
X227972Y110489D01*
X227764Y110239D01*
X227389Y110114D01*
X226389D01*
G01X229489Y109072D02*
Y111572D01*
X230530D01*
X230864Y111447D01*
X231072Y111280D01*
X231155Y110947D01*
X231072Y110614D01*
X230822Y110405D01*
X230530Y110280D01*
X229489D01*
G01X230530D02*
X231155Y109072D01*
G01X232630Y111155D02*
X232880Y111405D01*
X233172Y111530D01*
X233505Y111572D01*
X233922Y111489D01*
X234214Y111280D01*
X234297Y111030D01*
X234255Y110780D01*
X234089Y110572D01*
X233255Y110155D01*
X232880Y109864D01*
X232630Y109447D01*
X232547Y109072D01*
X234297D01*
G01X236522D02*
X236814Y109114D01*
X237147Y109239D01*
X237355Y109447D01*
X237439Y109739D01*
X237355Y110030D01*
X237105Y110280D01*
X236730Y110405D01*
X236314D01*
X236064Y110489D01*
X235855Y110697D01*
X235772Y110989D01*
X235897Y111280D01*
X236189Y111489D01*
X236522Y111572D01*
X236855Y111489D01*
X237147Y111280D01*
X237272Y110989D01*
X237189Y110697D01*
X236980Y110489D01*
X236730Y110405D01*
X236314D01*
X235939Y110280D01*
X235689Y110030D01*
X235605Y109739D01*
X235689Y109447D01*
X235897Y109239D01*
X236230Y109114D01*
X236522Y109072D01*
G01X235572Y90572D02*
Y94572D01*
X228172D01*
G01X218499Y105567D02*
X215999D01*
Y106567D01*
X216124Y106900D01*
X216416Y107150D01*
X216749Y107233D01*
X217082Y107150D01*
X217332Y106942D01*
X217457Y106567D01*
Y105567D01*
G01X218499Y108667D02*
X215999D01*
Y109708D01*
X216124Y110042D01*
X216291Y110250D01*
X216624Y110333D01*
X216957Y110250D01*
X217166Y110000D01*
X217291Y109708D01*
Y108667D01*
G01Y109708D02*
X218499Y110333D01*
G01X216416Y111808D02*
X216166Y112058D01*
X216041Y112350D01*
X215999Y112683D01*
X216082Y113100D01*
X216291Y113392D01*
X216541Y113475D01*
X216791Y113433D01*
X216999Y113267D01*
X217416Y112433D01*
X217707Y112058D01*
X218124Y111808D01*
X218499Y111725D01*
Y113475D01*
G01X218207Y114992D02*
X218416Y115283D01*
X218499Y115617D01*
X218416Y115950D01*
X218166Y116242D01*
X217791Y116450D01*
X217416Y116533D01*
X216957D01*
X216582Y116450D01*
X216249Y116242D01*
X216082Y115992D01*
X215999Y115700D01*
X216082Y115367D01*
X216249Y115117D01*
X216499Y114950D01*
X216832Y114867D01*
X217124Y114950D01*
X217416Y115158D01*
X217582Y115408D01*
X217624Y115700D01*
X217541Y116033D01*
X217332Y116283D01*
X216957Y116533D01*
G01X215499Y95850D02*
X219499D01*
Y103250D01*
G01X226516Y113550D02*
Y116050D01*
X227516D01*
X227849Y115925D01*
X228099Y115633D01*
X228182Y115300D01*
X228099Y114967D01*
X227891Y114717D01*
X227516Y114592D01*
X226516D01*
G01X229616Y113550D02*
Y116050D01*
X230657D01*
X230991Y115925D01*
X231199Y115758D01*
X231282Y115425D01*
X231199Y115092D01*
X230949Y114883D01*
X230657Y114758D01*
X229616D01*
G01X230657D02*
X231282Y113550D01*
G01X232632Y114050D02*
X232882Y113758D01*
X233216Y113592D01*
X233591Y113550D01*
X233924Y113592D01*
X234257Y113800D01*
X234466Y114050D01*
X234507Y114300D01*
X234424Y114592D01*
X234132Y114800D01*
X233841Y114883D01*
X233466D01*
G01X233841D02*
X234091Y115008D01*
X234299Y115217D01*
X234382Y115467D01*
X234299Y115717D01*
X234091Y115925D01*
X233716Y116050D01*
X233341Y116008D01*
X232966Y115842D01*
G01X236649Y116050D02*
X236316Y115967D01*
X236066Y115758D01*
X235899Y115508D01*
X235774Y115175D01*
X235732Y114800D01*
X235774Y114425D01*
X235899Y114092D01*
X236066Y113842D01*
X236316Y113633D01*
X236649Y113550D01*
X236982Y113633D01*
X237232Y113842D01*
X237399Y114092D01*
X237524Y114425D01*
X237566Y114800D01*
X237524Y115175D01*
X237399Y115508D01*
X237232Y115758D01*
X236982Y115967D01*
X236649Y116050D01*
G01X228299Y99050D02*
Y95050D01*
X235699D01*
G01X180516Y146050D02*
Y148550D01*
X181557D01*
X181891Y148425D01*
X182099Y148258D01*
X182182Y147925D01*
X182099Y147592D01*
X181849Y147383D01*
X181557Y147258D01*
X180516D01*
G01X181557D02*
X182182Y146050D01*
G01X184949D02*
Y148550D01*
X183407Y146758D01*
X185491D01*
G01X186841Y146342D02*
X187132Y146133D01*
X187466Y146050D01*
X187799Y146133D01*
X188091Y146383D01*
X188299Y146758D01*
X188382Y147133D01*
Y147592D01*
X188299Y147967D01*
X188091Y148300D01*
X187841Y148467D01*
X187549Y148550D01*
X187216Y148467D01*
X186966Y148300D01*
X186799Y148050D01*
X186716Y147717D01*
X186799Y147425D01*
X187007Y147133D01*
X187257Y146967D01*
X187549Y146925D01*
X187882Y147008D01*
X188132Y147217D01*
X188382Y147592D01*
G01X189941Y146342D02*
X190232Y146133D01*
X190566Y146050D01*
X190899Y146133D01*
X191191Y146383D01*
X191399Y146758D01*
X191482Y147133D01*
Y147592D01*
X191399Y147967D01*
X191191Y148300D01*
X190941Y148467D01*
X190649Y148550D01*
X190316Y148467D01*
X190066Y148300D01*
X189899Y148050D01*
X189816Y147717D01*
X189899Y147425D01*
X190107Y147133D01*
X190357Y146967D01*
X190649Y146925D01*
X190982Y147008D01*
X191232Y147217D01*
X191482Y147592D01*
G01X202300Y106017D02*
X199800D01*
Y107017D01*
X199925Y107350D01*
X200217Y107600D01*
X200550Y107683D01*
X200883Y107600D01*
X201133Y107392D01*
X201258Y107017D01*
Y106017D01*
G01X202300Y109117D02*
X199800D01*
Y110158D01*
X199925Y110492D01*
X200092Y110700D01*
X200425Y110783D01*
X200758Y110700D01*
X200967Y110450D01*
X201092Y110158D01*
Y109117D01*
G01Y110158D02*
X202300Y110783D01*
G01Y113050D02*
X199800D01*
X200300Y112550D01*
G01X202300D02*
Y113550D01*
G01Y116067D02*
X201758Y116150D01*
X201300Y116275D01*
X200883Y116442D01*
X200425Y116650D01*
X199800Y116983D01*
Y115317D01*
G01X199499Y95850D02*
X203499D01*
Y103250D01*
G01X197700Y106117D02*
X195200D01*
Y107117D01*
X195325Y107450D01*
X195617Y107700D01*
X195950Y107783D01*
X196283Y107700D01*
X196533Y107492D01*
X196658Y107117D01*
Y106117D01*
G01X197700Y109217D02*
X195200D01*
Y110258D01*
X195325Y110592D01*
X195492Y110800D01*
X195825Y110883D01*
X196158Y110800D01*
X196367Y110550D01*
X196492Y110258D01*
Y109217D01*
G01Y110258D02*
X197700Y110883D01*
G01X195617Y112358D02*
X195367Y112608D01*
X195242Y112900D01*
X195200Y113233D01*
X195283Y113650D01*
X195492Y113942D01*
X195742Y114025D01*
X195992Y113983D01*
X196200Y113817D01*
X196617Y112983D01*
X196908Y112608D01*
X197325Y112358D01*
X197700Y112275D01*
Y114025D01*
G01X197200Y115333D02*
X197492Y115583D01*
X197658Y115917D01*
X197700Y116292D01*
X197658Y116625D01*
X197450Y116958D01*
X197200Y117167D01*
X196950Y117208D01*
X196658Y117125D01*
X196450Y116833D01*
X196367Y116542D01*
Y116167D01*
G01Y116542D02*
X196242Y116792D01*
X196033Y117000D01*
X195783Y117083D01*
X195533Y117000D01*
X195325Y116792D01*
X195200Y116417D01*
X195242Y116042D01*
X195408Y115667D01*
G01X199499Y103250D02*
X195499D01*
Y95850D01*
G01X248016Y75050D02*
Y77550D01*
X249016D01*
X249349Y77425D01*
X249599Y77133D01*
X249682Y76800D01*
X249599Y76467D01*
X249391Y76217D01*
X249016Y76092D01*
X248016D01*
G01X251116Y75050D02*
Y77550D01*
X252157D01*
X252491Y77425D01*
X252699Y77258D01*
X252782Y76925D01*
X252699Y76592D01*
X252449Y76383D01*
X252157Y76258D01*
X251116D01*
G01X252157D02*
X252782Y75050D01*
G01X255049D02*
Y77550D01*
X254549Y77050D01*
G01Y75050D02*
X255549D01*
G01X257441Y75342D02*
X257732Y75133D01*
X258066Y75050D01*
X258399Y75133D01*
X258691Y75383D01*
X258899Y75758D01*
X258982Y76133D01*
Y76592D01*
X258899Y76967D01*
X258691Y77300D01*
X258441Y77467D01*
X258149Y77550D01*
X257816Y77467D01*
X257566Y77300D01*
X257399Y77050D01*
X257316Y76717D01*
X257399Y76425D01*
X257607Y76133D01*
X257857Y75967D01*
X258149Y75925D01*
X258482Y76008D01*
X258732Y76217D01*
X258982Y76592D01*
G01X182999Y114750D02*
Y109250D01*
G01Y126850D02*
Y121350D01*
G01X255900Y80617D02*
X253400D01*
Y81617D01*
X253525Y81950D01*
X253817Y82200D01*
X254150Y82283D01*
X254483Y82200D01*
X254733Y81992D01*
X254858Y81617D01*
Y80617D01*
G01X253608Y85467D02*
X253483Y85217D01*
X253400Y84925D01*
Y84592D01*
X253525Y84217D01*
X253733Y83925D01*
X253983Y83717D01*
X254400Y83550D01*
X254775Y83508D01*
X255150Y83592D01*
X255400Y83717D01*
X255650Y83967D01*
X255817Y84258D01*
X255900Y84550D01*
Y84842D01*
X255817Y85133D01*
X255692Y85383D01*
X255525Y85592D01*
G01X253817Y86858D02*
X253567Y87108D01*
X253442Y87400D01*
X253400Y87733D01*
X253483Y88150D01*
X253692Y88442D01*
X253942Y88525D01*
X254192Y88483D01*
X254400Y88317D01*
X254817Y87483D01*
X255108Y87108D01*
X255525Y86858D01*
X255900Y86775D01*
Y88525D01*
G01X255400Y89833D02*
X255692Y90083D01*
X255858Y90417D01*
X255900Y90792D01*
X255858Y91125D01*
X255650Y91458D01*
X255400Y91667D01*
X255150Y91708D01*
X254858Y91625D01*
X254650Y91333D01*
X254567Y91042D01*
Y90667D01*
G01Y91042D02*
X254442Y91292D01*
X254233Y91500D01*
X253983Y91583D01*
X253733Y91500D01*
X253525Y91292D01*
X253400Y90917D01*
X253442Y90542D01*
X253608Y90167D01*
G01X245066Y101050D02*
Y103550D01*
X246066D01*
X246399Y103425D01*
X246649Y103133D01*
X246732Y102800D01*
X246649Y102467D01*
X246441Y102217D01*
X246066Y102092D01*
X245066D01*
G01X249249Y102300D02*
X250082D01*
Y101550D01*
X249832Y101300D01*
X249541Y101133D01*
X249124Y101050D01*
X248707Y101133D01*
X248416Y101300D01*
X248166Y101550D01*
X247999Y101842D01*
X247916Y102175D01*
Y102467D01*
X247999Y102717D01*
X248166Y103008D01*
X248416Y103258D01*
X248666Y103425D01*
X248999Y103550D01*
X249291D01*
X249624Y103467D01*
X249874Y103300D01*
G01X251307Y103133D02*
X251557Y103383D01*
X251849Y103508D01*
X252182Y103550D01*
X252599Y103467D01*
X252891Y103258D01*
X252974Y103008D01*
X252932Y102758D01*
X252766Y102550D01*
X251932Y102133D01*
X251557Y101842D01*
X251307Y101425D01*
X251224Y101050D01*
X252974D01*
G01X192500Y114417D02*
X190000D01*
Y115417D01*
X190125Y115750D01*
X190417Y116000D01*
X190750Y116083D01*
X191083Y116000D01*
X191333Y115792D01*
X191458Y115417D01*
Y114417D01*
G01X192500Y117517D02*
X190000D01*
Y118558D01*
X190125Y118892D01*
X190292Y119100D01*
X190625Y119183D01*
X190958Y119100D01*
X191167Y118850D01*
X191292Y118558D01*
Y117517D01*
G01Y118558D02*
X192500Y119183D01*
G01X190417Y120658D02*
X190167Y120908D01*
X190042Y121200D01*
X190000Y121533D01*
X190083Y121950D01*
X190292Y122242D01*
X190542Y122325D01*
X190792Y122283D01*
X191000Y122117D01*
X191417Y121283D01*
X191708Y120908D01*
X192125Y120658D01*
X192500Y120575D01*
Y122325D01*
G01Y124550D02*
X190000D01*
X190500Y124050D01*
G01X192500D02*
Y125050D01*
G01X183499Y115350D02*
X187499D01*
Y122750D01*
G01X224526Y81528D02*
Y86528D01*
X219526D01*
G01X223519Y78434D02*
X226519D01*
G01X223519Y68591D02*
X225519D01*
G01X197833Y74497D02*
X195833D01*
G01X246217Y68400D02*
Y70900D01*
X247217D01*
X247550Y70775D01*
X247800Y70483D01*
X247883Y70150D01*
X247800Y69817D01*
X247592Y69567D01*
X247217Y69442D01*
X246217D01*
G01X251067Y70692D02*
X250817Y70817D01*
X250525Y70900D01*
X250192D01*
X249817Y70775D01*
X249525Y70567D01*
X249317Y70317D01*
X249150Y69900D01*
X249108Y69525D01*
X249192Y69150D01*
X249317Y68900D01*
X249567Y68650D01*
X249858Y68483D01*
X250150Y68400D01*
X250442D01*
X250733Y68483D01*
X250983Y68608D01*
X251192Y68775D01*
G01X253250Y68400D02*
Y70900D01*
X252750Y70400D01*
G01Y68400D02*
X253750D01*
G01X255558Y69442D02*
X255850Y69733D01*
X256100Y69900D01*
X256433Y69983D01*
X256725Y69900D01*
X256933Y69733D01*
X257100Y69483D01*
X257142Y69192D01*
X257100Y68942D01*
X256933Y68692D01*
X256683Y68483D01*
X256392Y68400D01*
X256058Y68483D01*
X255767Y68733D01*
X255600Y69108D01*
X255558Y69525D01*
X255642Y70067D01*
X255767Y70358D01*
X255975Y70650D01*
X256267Y70858D01*
X256558Y70900D01*
X256850Y70817D01*
X257058Y70608D01*
G01X211965Y242750D02*
X221965D01*
G01Y235750D02*
X211965D01*
G01X216965D02*
Y242750D01*
G01X211965Y232317D02*
X221965D01*
Y228983D01*
X221465Y227650D01*
X220798Y226650D01*
X219798Y225817D01*
X218631Y225150D01*
X216965Y224983D01*
X215298Y225150D01*
X214132Y225817D01*
X213131Y226650D01*
X212465Y227650D01*
X211965Y228983D01*
Y232317D01*
G01Y221717D02*
X221965D01*
Y218383D01*
X221465Y217050D01*
X220798Y216050D01*
X219798Y215217D01*
X218631Y214550D01*
X216965Y214383D01*
X215298Y214550D01*
X214132Y215217D01*
X213131Y216050D01*
X212465Y217050D01*
X211965Y218383D01*
Y221717D01*
G01X213131Y210283D02*
X212298Y209117D01*
X211965Y207783D01*
X212298Y206450D01*
X213298Y205283D01*
X214798Y204450D01*
X216298Y204117D01*
X218132D01*
X219632Y204450D01*
X220965Y205283D01*
X221632Y206283D01*
X221965Y207450D01*
X221632Y208784D01*
X220965Y209783D01*
X219965Y210450D01*
X218631Y210783D01*
X217465Y210450D01*
X216298Y209617D01*
X215631Y208617D01*
X215465Y207450D01*
X215798Y206117D01*
X216632Y205117D01*
X218132Y204117D01*
G01X214999Y156050D02*
Y166050D01*
G01X221999D02*
Y156050D01*
G01Y161050D02*
X214999D01*
G01X225432Y156050D02*
Y166050D01*
X228766D01*
X230099Y165550D01*
X231099Y164883D01*
X231932Y163883D01*
X232599Y162716D01*
X232766Y161050D01*
X232599Y159383D01*
X231932Y158217D01*
X231099Y157216D01*
X230099Y156550D01*
X228766Y156050D01*
X225432D01*
G01X236032D02*
Y166050D01*
X239366D01*
X240699Y165550D01*
X241699Y164883D01*
X242532Y163883D01*
X243199Y162716D01*
X243366Y161050D01*
X243199Y159383D01*
X242532Y158217D01*
X241699Y157216D01*
X240699Y156550D01*
X239366Y156050D01*
X236032D01*
G01X247466Y157216D02*
X248632Y156383D01*
X249966Y156050D01*
X251299Y156383D01*
X252466Y157383D01*
X253299Y158883D01*
X253632Y160383D01*
Y162217D01*
X253299Y163717D01*
X252466Y165050D01*
X251466Y165717D01*
X250299Y166050D01*
X248965Y165717D01*
X247966Y165050D01*
X247299Y164050D01*
X246966Y162716D01*
X247299Y161550D01*
X248132Y160383D01*
X249132Y159716D01*
X250299Y159550D01*
X251632Y159883D01*
X252632Y160717D01*
X253632Y162217D01*
G01X255899Y152717D02*
X265899D01*
G01X268166Y166050D02*
Y156050D01*
X274832D01*
G01X285432D02*
X278766D01*
Y166050D01*
X285432D01*
G01X282766Y161217D02*
X278766D01*
G01X289032Y156050D02*
Y166050D01*
X292366D01*
X293699Y165550D01*
X294699Y164883D01*
X295532Y163883D01*
X296199Y162716D01*
X296366Y161050D01*
X296199Y159383D01*
X295532Y158217D01*
X294699Y157216D01*
X293699Y156550D01*
X292366Y156050D01*
X289032D01*
G01X179016Y178550D02*
Y181050D01*
X180057D01*
X180391Y180925D01*
X180599Y180758D01*
X180682Y180425D01*
X180599Y180092D01*
X180349Y179883D01*
X180057Y179758D01*
X179016D01*
G01X180057D02*
X180682Y178550D01*
G01X182157Y180633D02*
X182407Y180883D01*
X182699Y181008D01*
X183032Y181050D01*
X183449Y180967D01*
X183741Y180758D01*
X183824Y180508D01*
X183782Y180258D01*
X183616Y180050D01*
X182782Y179633D01*
X182407Y179342D01*
X182157Y178925D01*
X182074Y178550D01*
X183824D01*
G01X185257Y180633D02*
X185507Y180883D01*
X185799Y181008D01*
X186132Y181050D01*
X186549Y180967D01*
X186841Y180758D01*
X186924Y180508D01*
X186882Y180258D01*
X186716Y180050D01*
X185882Y179633D01*
X185507Y179342D01*
X185257Y178925D01*
X185174Y178550D01*
X186924D01*
G01X188357Y179592D02*
X188649Y179883D01*
X188899Y180050D01*
X189232Y180133D01*
X189524Y180050D01*
X189732Y179883D01*
X189899Y179633D01*
X189941Y179342D01*
X189899Y179092D01*
X189732Y178842D01*
X189482Y178633D01*
X189191Y178550D01*
X188857Y178633D01*
X188566Y178883D01*
X188399Y179258D01*
X188357Y179675D01*
X188441Y180217D01*
X188566Y180508D01*
X188774Y180800D01*
X189066Y181008D01*
X189357Y181050D01*
X189649Y180967D01*
X189857Y180758D01*
G01X179016Y174550D02*
Y177050D01*
X180057D01*
X180391Y176925D01*
X180599Y176758D01*
X180682Y176425D01*
X180599Y176092D01*
X180349Y175883D01*
X180057Y175758D01*
X179016D01*
G01X180057D02*
X180682Y174550D01*
G01X182157Y176633D02*
X182407Y176883D01*
X182699Y177008D01*
X183032Y177050D01*
X183449Y176967D01*
X183741Y176758D01*
X183824Y176508D01*
X183782Y176258D01*
X183616Y176050D01*
X182782Y175633D01*
X182407Y175342D01*
X182157Y174925D01*
X182074Y174550D01*
X183824D01*
G01X185257Y176633D02*
X185507Y176883D01*
X185799Y177008D01*
X186132Y177050D01*
X186549Y176967D01*
X186841Y176758D01*
X186924Y176508D01*
X186882Y176258D01*
X186716Y176050D01*
X185882Y175633D01*
X185507Y175342D01*
X185257Y174925D01*
X185174Y174550D01*
X186924D01*
G01X189149D02*
X189441Y174592D01*
X189774Y174717D01*
X189982Y174925D01*
X190066Y175217D01*
X189982Y175508D01*
X189732Y175758D01*
X189357Y175883D01*
X188941D01*
X188691Y175967D01*
X188482Y176175D01*
X188399Y176467D01*
X188524Y176758D01*
X188816Y176967D01*
X189149Y177050D01*
X189482Y176967D01*
X189774Y176758D01*
X189899Y176467D01*
X189816Y176175D01*
X189607Y175967D01*
X189357Y175883D01*
X188941D01*
X188566Y175758D01*
X188316Y175508D01*
X188232Y175217D01*
X188316Y174925D01*
X188524Y174717D01*
X188857Y174592D01*
X189149Y174550D01*
G01X179016Y170050D02*
Y172550D01*
X180057D01*
X180391Y172425D01*
X180599Y172258D01*
X180682Y171925D01*
X180599Y171592D01*
X180349Y171383D01*
X180057Y171258D01*
X179016D01*
G01X180057D02*
X180682Y170050D01*
G01X182157Y172133D02*
X182407Y172383D01*
X182699Y172508D01*
X183032Y172550D01*
X183449Y172467D01*
X183741Y172258D01*
X183824Y172008D01*
X183782Y171758D01*
X183616Y171550D01*
X182782Y171133D01*
X182407Y170842D01*
X182157Y170425D01*
X182074Y170050D01*
X183824D01*
G01X185132Y170550D02*
X185382Y170258D01*
X185716Y170092D01*
X186091Y170050D01*
X186424Y170092D01*
X186757Y170300D01*
X186966Y170550D01*
X187007Y170800D01*
X186924Y171092D01*
X186632Y171300D01*
X186341Y171383D01*
X185966D01*
G01X186341D02*
X186591Y171508D01*
X186799Y171717D01*
X186882Y171967D01*
X186799Y172217D01*
X186591Y172425D01*
X186216Y172550D01*
X185841Y172508D01*
X185466Y172342D01*
G01X189149Y172550D02*
X188816Y172467D01*
X188566Y172258D01*
X188399Y172008D01*
X188274Y171675D01*
X188232Y171300D01*
X188274Y170925D01*
X188399Y170592D01*
X188566Y170342D01*
X188816Y170133D01*
X189149Y170050D01*
X189482Y170133D01*
X189732Y170342D01*
X189899Y170592D01*
X190024Y170925D01*
X190066Y171300D01*
X190024Y171675D01*
X189899Y172008D01*
X189732Y172258D01*
X189482Y172467D01*
X189149Y172550D01*
G01X188599Y150000D02*
Y154000D01*
X181199D01*
G01X206499Y158450D02*
X206457Y158117D01*
X206291Y157825D01*
X206041Y157575D01*
X205749Y157408D01*
X205416Y157325D01*
X205082D01*
X204749Y157408D01*
X204457Y157575D01*
X204207Y157825D01*
X204041Y158117D01*
X203999Y158450D01*
X204041Y158783D01*
X204207Y159075D01*
X204457Y159325D01*
X204749Y159492D01*
X205082Y159575D01*
X205416D01*
X205749Y159492D01*
X206041Y159325D01*
X206291Y159075D01*
X206457Y158783D01*
X206499Y158450D01*
G01X205832Y158783D02*
X206499Y159283D01*
G01Y162050D02*
X203999D01*
X205791Y160508D01*
Y162592D01*
G01X205999Y163733D02*
X206291Y163983D01*
X206457Y164317D01*
X206499Y164692D01*
X206457Y165025D01*
X206249Y165358D01*
X205999Y165567D01*
X205749Y165608D01*
X205457Y165525D01*
X205249Y165233D01*
X205166Y164942D01*
Y164567D01*
G01Y164942D02*
X205041Y165192D01*
X204832Y165400D01*
X204582Y165483D01*
X204332Y165400D01*
X204124Y165192D01*
X203999Y164817D01*
X204041Y164442D01*
X204207Y164067D01*
G01X182799Y154700D02*
X196799D01*
G01X182799Y167700D02*
Y154700D01*
G01X196799Y167700D02*
X182799D01*
G01X196799Y154700D02*
Y167700D01*
G01X209708Y273767D02*
X209583Y273517D01*
X209500Y273225D01*
Y272892D01*
X209625Y272517D01*
X209833Y272225D01*
X210083Y272017D01*
X210500Y271850D01*
X210875Y271808D01*
X211250Y271892D01*
X211500Y272017D01*
X211750Y272267D01*
X211917Y272558D01*
X212000Y272850D01*
Y273142D01*
X211917Y273433D01*
X211792Y273683D01*
X211625Y273892D01*
G01X209917Y275158D02*
X209667Y275408D01*
X209542Y275700D01*
X209500Y276033D01*
X209583Y276450D01*
X209792Y276742D01*
X210042Y276825D01*
X210292Y276783D01*
X210500Y276617D01*
X210917Y275783D01*
X211208Y275408D01*
X211625Y275158D01*
X212000Y275075D01*
Y276825D01*
G01X211625Y278133D02*
X211833Y278383D01*
X211958Y278675D01*
X212000Y279050D01*
X211917Y279425D01*
X211750Y279717D01*
X211458Y279925D01*
X211125Y279967D01*
X210792Y279883D01*
X210583Y279675D01*
X210417Y279383D01*
X210375Y279092D01*
X210417Y278800D01*
X210583Y278425D01*
X209500Y278550D01*
Y279675D01*
G01X212000Y282650D02*
X209500D01*
X211292Y281108D01*
Y283192D01*
G01X206708Y312267D02*
X206583Y312017D01*
X206500Y311725D01*
Y311392D01*
X206625Y311017D01*
X206833Y310725D01*
X207083Y310517D01*
X207500Y310350D01*
X207875Y310308D01*
X208250Y310392D01*
X208500Y310517D01*
X208750Y310767D01*
X208917Y311058D01*
X209000Y311350D01*
Y311642D01*
X208917Y311933D01*
X208792Y312183D01*
X208625Y312392D01*
G01X206917Y313658D02*
X206667Y313908D01*
X206542Y314200D01*
X206500Y314533D01*
X206583Y314950D01*
X206792Y315242D01*
X207042Y315325D01*
X207292Y315283D01*
X207500Y315117D01*
X207917Y314283D01*
X208208Y313908D01*
X208625Y313658D01*
X209000Y313575D01*
Y315325D01*
G01X208625Y316633D02*
X208833Y316883D01*
X208958Y317175D01*
X209000Y317550D01*
X208917Y317925D01*
X208750Y318217D01*
X208458Y318425D01*
X208125Y318467D01*
X207792Y318383D01*
X207583Y318175D01*
X207417Y317883D01*
X207375Y317592D01*
X207417Y317300D01*
X207583Y316925D01*
X206500Y317050D01*
Y318175D01*
G01Y320650D02*
X206583Y320317D01*
X206792Y320067D01*
X207042Y319900D01*
X207375Y319775D01*
X207750Y319733D01*
X208125Y319775D01*
X208458Y319900D01*
X208708Y320067D01*
X208917Y320317D01*
X209000Y320650D01*
X208917Y320983D01*
X208708Y321233D01*
X208458Y321400D01*
X208125Y321525D01*
X207750Y321567D01*
X207375Y321525D01*
X207042Y321400D01*
X206792Y321233D01*
X206583Y320983D01*
X206500Y320650D01*
G01X241400Y260500D02*
X241067Y260542D01*
X240775Y260708D01*
X240525Y260958D01*
X240358Y261250D01*
X240275Y261583D01*
Y261917D01*
X240358Y262250D01*
X240525Y262542D01*
X240775Y262792D01*
X241067Y262958D01*
X241400Y263000D01*
X241733Y262958D01*
X242025Y262792D01*
X242275Y262542D01*
X242442Y262250D01*
X242525Y261917D01*
Y261583D01*
X242442Y261250D01*
X242275Y260958D01*
X242025Y260708D01*
X241733Y260542D01*
X241400Y260500D01*
G01X241733Y261167D02*
X242233Y260500D01*
G01X243708Y261542D02*
X244000Y261833D01*
X244250Y262000D01*
X244583Y262083D01*
X244875Y262000D01*
X245083Y261833D01*
X245250Y261583D01*
X245292Y261292D01*
X245250Y261042D01*
X245083Y260792D01*
X244833Y260583D01*
X244542Y260500D01*
X244208Y260583D01*
X243917Y260833D01*
X243750Y261208D01*
X243708Y261625D01*
X243792Y262167D01*
X243917Y262458D01*
X244125Y262750D01*
X244417Y262958D01*
X244708Y263000D01*
X245000Y262917D01*
X245208Y262708D01*
G01X248100Y260500D02*
Y263000D01*
X246558Y261208D01*
X248642D01*
G01X238900Y272100D02*
X250300D01*
G01X238900Y285500D02*
Y272100D01*
G01X250300Y285500D02*
X238900D01*
G01X250300Y272100D02*
Y285500D01*
G01X258398Y313414D02*
Y294214D01*
X269598D01*
Y313414D01*
X258398D01*
Y313014D01*
G01X201517Y299500D02*
Y302000D01*
X202558D01*
X202892Y301875D01*
X203100Y301708D01*
X203183Y301375D01*
X203100Y301042D01*
X202850Y300833D01*
X202558Y300708D01*
X201517D01*
G01X202558D02*
X203183Y299500D01*
G01X204658Y301583D02*
X204908Y301833D01*
X205200Y301958D01*
X205533Y302000D01*
X205950Y301917D01*
X206242Y301708D01*
X206325Y301458D01*
X206283Y301208D01*
X206117Y301000D01*
X205283Y300583D01*
X204908Y300292D01*
X204658Y299875D01*
X204575Y299500D01*
X206325D01*
G01X207633Y300000D02*
X207883Y299708D01*
X208217Y299542D01*
X208592Y299500D01*
X208925Y299542D01*
X209258Y299750D01*
X209467Y300000D01*
X209508Y300250D01*
X209425Y300542D01*
X209133Y300750D01*
X208842Y300833D01*
X208467D01*
G01X208842D02*
X209092Y300958D01*
X209300Y301167D01*
X209383Y301417D01*
X209300Y301667D01*
X209092Y301875D01*
X208717Y302000D01*
X208342Y301958D01*
X207967Y301792D01*
G01X212150Y299500D02*
Y302000D01*
X210608Y300208D01*
X212692D01*
G01X241498Y290114D02*
Y303114D01*
G01X215498Y290114D02*
X241498D01*
G01X215498Y303114D02*
Y290114D01*
G01X241498Y303114D02*
X215498D01*
G01X224517Y257000D02*
Y259500D01*
X225558D01*
X225892Y259375D01*
X226100Y259208D01*
X226183Y258875D01*
X226100Y258542D01*
X225850Y258333D01*
X225558Y258208D01*
X224517D01*
G01X225558D02*
X226183Y257000D01*
G01X227658Y259083D02*
X227908Y259333D01*
X228200Y259458D01*
X228533Y259500D01*
X228950Y259417D01*
X229242Y259208D01*
X229325Y258958D01*
X229283Y258708D01*
X229117Y258500D01*
X228283Y258083D01*
X227908Y257792D01*
X227658Y257375D01*
X227575Y257000D01*
X229325D01*
G01X230633Y257500D02*
X230883Y257208D01*
X231217Y257042D01*
X231592Y257000D01*
X231925Y257042D01*
X232258Y257250D01*
X232467Y257500D01*
X232508Y257750D01*
X232425Y258042D01*
X232133Y258250D01*
X231842Y258333D01*
X231467D01*
G01X231842D02*
X232092Y258458D01*
X232300Y258667D01*
X232383Y258917D01*
X232300Y259167D01*
X232092Y259375D01*
X231717Y259500D01*
X231342Y259458D01*
X230967Y259292D01*
G01X233733Y257375D02*
X233983Y257167D01*
X234275Y257042D01*
X234650Y257000D01*
X235025Y257083D01*
X235317Y257250D01*
X235525Y257542D01*
X235567Y257875D01*
X235483Y258208D01*
X235275Y258417D01*
X234983Y258583D01*
X234692Y258625D01*
X234400Y258583D01*
X234025Y258417D01*
X234150Y259500D01*
X235275D01*
G01X231698Y285114D02*
Y289114D01*
X224298D01*
G01X224517Y253000D02*
Y255500D01*
X225558D01*
X225892Y255375D01*
X226100Y255208D01*
X226183Y254875D01*
X226100Y254542D01*
X225850Y254333D01*
X225558Y254208D01*
X224517D01*
G01X225558D02*
X226183Y253000D01*
G01X227533Y253500D02*
X227783Y253208D01*
X228117Y253042D01*
X228492Y253000D01*
X228825Y253042D01*
X229158Y253250D01*
X229367Y253500D01*
X229408Y253750D01*
X229325Y254042D01*
X229033Y254250D01*
X228742Y254333D01*
X228367D01*
G01X228742D02*
X228992Y254458D01*
X229200Y254667D01*
X229283Y254917D01*
X229200Y255167D01*
X228992Y255375D01*
X228617Y255500D01*
X228242Y255458D01*
X227867Y255292D01*
G01X230842Y253292D02*
X231133Y253083D01*
X231467Y253000D01*
X231800Y253083D01*
X232092Y253333D01*
X232300Y253708D01*
X232383Y254083D01*
Y254542D01*
X232300Y254917D01*
X232092Y255250D01*
X231842Y255417D01*
X231550Y255500D01*
X231217Y255417D01*
X230967Y255250D01*
X230800Y255000D01*
X230717Y254667D01*
X230800Y254375D01*
X231008Y254083D01*
X231258Y253917D01*
X231550Y253875D01*
X231883Y253958D01*
X232133Y254167D01*
X232383Y254542D01*
G01X235150Y253000D02*
Y255500D01*
X233608Y253708D01*
X235692D01*
G01X226700Y285000D02*
Y281000D01*
X234100D01*
G01X240517Y255500D02*
Y258000D01*
X241558D01*
X241892Y257875D01*
X242100Y257708D01*
X242183Y257375D01*
X242100Y257042D01*
X241850Y256833D01*
X241558Y256708D01*
X240517D01*
G01X241558D02*
X242183Y255500D01*
G01X243533Y256000D02*
X243783Y255708D01*
X244117Y255542D01*
X244492Y255500D01*
X244825Y255542D01*
X245158Y255750D01*
X245367Y256000D01*
X245408Y256250D01*
X245325Y256542D01*
X245033Y256750D01*
X244742Y256833D01*
X244367D01*
G01X244742D02*
X244992Y256958D01*
X245200Y257167D01*
X245283Y257417D01*
X245200Y257667D01*
X244992Y257875D01*
X244617Y258000D01*
X244242Y257958D01*
X243867Y257792D01*
G01X246842Y255792D02*
X247133Y255583D01*
X247467Y255500D01*
X247800Y255583D01*
X248092Y255833D01*
X248300Y256208D01*
X248383Y256583D01*
Y257042D01*
X248300Y257417D01*
X248092Y257750D01*
X247842Y257917D01*
X247550Y258000D01*
X247217Y257917D01*
X246967Y257750D01*
X246800Y257500D01*
X246717Y257167D01*
X246800Y256875D01*
X247008Y256583D01*
X247258Y256417D01*
X247550Y256375D01*
X247883Y256458D01*
X248133Y256667D01*
X248383Y257042D01*
G01X249733Y255875D02*
X249983Y255667D01*
X250275Y255542D01*
X250650Y255500D01*
X251025Y255583D01*
X251317Y255750D01*
X251525Y256042D01*
X251567Y256375D01*
X251483Y256708D01*
X251275Y256917D01*
X250983Y257083D01*
X250692Y257125D01*
X250400Y257083D01*
X250025Y256917D01*
X250150Y258000D01*
X251275D01*
G01X246000Y267700D02*
Y271700D01*
X238600D01*
G01X218000Y267017D02*
X215500D01*
Y268058D01*
X215625Y268392D01*
X215792Y268600D01*
X216125Y268683D01*
X216458Y268600D01*
X216667Y268350D01*
X216792Y268058D01*
Y267017D01*
G01Y268058D02*
X218000Y268683D01*
G01X215917Y270158D02*
X215667Y270408D01*
X215542Y270700D01*
X215500Y271033D01*
X215583Y271450D01*
X215792Y271742D01*
X216042Y271825D01*
X216292Y271783D01*
X216500Y271617D01*
X216917Y270783D01*
X217208Y270408D01*
X217625Y270158D01*
X218000Y270075D01*
Y271825D01*
G01X217500Y273133D02*
X217792Y273383D01*
X217958Y273717D01*
X218000Y274092D01*
X217958Y274425D01*
X217750Y274758D01*
X217500Y274967D01*
X217250Y275008D01*
X216958Y274925D01*
X216750Y274633D01*
X216667Y274342D01*
Y273967D01*
G01Y274342D02*
X216542Y274592D01*
X216333Y274800D01*
X216083Y274883D01*
X215833Y274800D01*
X215625Y274592D01*
X215500Y274217D01*
X215542Y273842D01*
X215708Y273467D01*
G01X218000Y277067D02*
X217458Y277150D01*
X217000Y277275D01*
X216583Y277442D01*
X216125Y277650D01*
X215500Y277983D01*
Y276317D01*
G01X211208Y312767D02*
X211083Y312517D01*
X211000Y312225D01*
Y311892D01*
X211125Y311517D01*
X211333Y311225D01*
X211583Y311017D01*
X212000Y310850D01*
X212375Y310808D01*
X212750Y310892D01*
X213000Y311017D01*
X213250Y311267D01*
X213417Y311558D01*
X213500Y311850D01*
Y312142D01*
X213417Y312433D01*
X213292Y312683D01*
X213125Y312892D01*
G01X211417Y314158D02*
X211167Y314408D01*
X211042Y314700D01*
X211000Y315033D01*
X211083Y315450D01*
X211292Y315742D01*
X211542Y315825D01*
X211792Y315783D01*
X212000Y315617D01*
X212417Y314783D01*
X212708Y314408D01*
X213125Y314158D01*
X213500Y314075D01*
Y315825D01*
G01X213125Y317133D02*
X213333Y317383D01*
X213458Y317675D01*
X213500Y318050D01*
X213417Y318425D01*
X213250Y318717D01*
X212958Y318925D01*
X212625Y318967D01*
X212292Y318883D01*
X212083Y318675D01*
X211917Y318383D01*
X211875Y318092D01*
X211917Y317800D01*
X212083Y317425D01*
X211000Y317550D01*
Y318675D01*
G01X213500Y321150D02*
X211000D01*
X211500Y320650D01*
G01X213500D02*
Y321650D01*
G01X221900Y304100D02*
Y309600D01*
G01X229900Y304100D02*
X221900D01*
G01X229900Y309600D02*
Y304100D01*
G01X223000Y265900D02*
X222958Y265567D01*
X222792Y265275D01*
X222542Y265025D01*
X222250Y264858D01*
X221917Y264775D01*
X221583D01*
X221250Y264858D01*
X220958Y265025D01*
X220708Y265275D01*
X220542Y265567D01*
X220500Y265900D01*
X220542Y266233D01*
X220708Y266525D01*
X220958Y266775D01*
X221250Y266942D01*
X221583Y267025D01*
X221917D01*
X222250Y266942D01*
X222542Y266775D01*
X222792Y266525D01*
X222958Y266233D01*
X223000Y265900D01*
G01X222333Y266233D02*
X223000Y266733D01*
G01X221958Y268208D02*
X221667Y268500D01*
X221500Y268750D01*
X221417Y269083D01*
X221500Y269375D01*
X221667Y269583D01*
X221917Y269750D01*
X222208Y269792D01*
X222458Y269750D01*
X222708Y269583D01*
X222917Y269333D01*
X223000Y269042D01*
X222917Y268708D01*
X222667Y268417D01*
X222292Y268250D01*
X221875Y268208D01*
X221333Y268292D01*
X221042Y268417D01*
X220750Y268625D01*
X220542Y268917D01*
X220500Y269208D01*
X220583Y269500D01*
X220792Y269708D01*
G01X222625Y271183D02*
X222833Y271433D01*
X222958Y271725D01*
X223000Y272100D01*
X222917Y272475D01*
X222750Y272767D01*
X222458Y272975D01*
X222125Y273017D01*
X221792Y272933D01*
X221583Y272725D01*
X221417Y272433D01*
X221375Y272142D01*
X221417Y271850D01*
X221583Y271475D01*
X220500Y271600D01*
Y272725D01*
G01X238000Y266100D02*
Y280100D01*
G01X225000Y266100D02*
X238000D01*
G01X225000Y280100D02*
Y266100D01*
G01X238000Y280100D02*
X225000D01*
G01X190883Y397300D02*
Y399800D01*
X191717D01*
X192050Y399675D01*
X192300Y399508D01*
X192508Y399258D01*
X192675Y398967D01*
X192717Y398550D01*
X192675Y398133D01*
X192508Y397842D01*
X192300Y397592D01*
X192050Y397425D01*
X191717Y397300D01*
X190883D01*
G01X194108Y399383D02*
X194358Y399633D01*
X194650Y399758D01*
X194983Y399800D01*
X195400Y399717D01*
X195692Y399508D01*
X195775Y399258D01*
X195733Y399008D01*
X195567Y398800D01*
X194733Y398383D01*
X194358Y398092D01*
X194108Y397675D01*
X194025Y397300D01*
X195775D01*
G01X198000D02*
X198292Y397342D01*
X198625Y397467D01*
X198833Y397675D01*
X198917Y397967D01*
X198833Y398258D01*
X198583Y398508D01*
X198208Y398633D01*
X197792D01*
X197542Y398717D01*
X197333Y398925D01*
X197250Y399217D01*
X197375Y399508D01*
X197667Y399717D01*
X198000Y399800D01*
X198333Y399717D01*
X198625Y399508D01*
X198750Y399217D01*
X198667Y398925D01*
X198458Y398717D01*
X198208Y398633D01*
X197792D01*
X197417Y398508D01*
X197167Y398258D01*
X197083Y397967D01*
X197167Y397675D01*
X197375Y397467D01*
X197708Y397342D01*
X198000Y397300D01*
G01X212807Y356817D02*
X212682Y356567D01*
X212599Y356275D01*
Y355942D01*
X212724Y355567D01*
X212932Y355275D01*
X213182Y355067D01*
X213599Y354900D01*
X213974Y354858D01*
X214349Y354942D01*
X214599Y355067D01*
X214849Y355317D01*
X215016Y355608D01*
X215099Y355900D01*
Y356192D01*
X215016Y356483D01*
X214891Y356733D01*
X214724Y356942D01*
G01X213016Y358208D02*
X212766Y358458D01*
X212641Y358750D01*
X212599Y359083D01*
X212682Y359500D01*
X212891Y359792D01*
X213141Y359875D01*
X213391Y359833D01*
X213599Y359667D01*
X214016Y358833D01*
X214307Y358458D01*
X214724Y358208D01*
X215099Y358125D01*
Y359875D01*
G01X214724Y361183D02*
X214932Y361433D01*
X215057Y361725D01*
X215099Y362100D01*
X215016Y362475D01*
X214849Y362767D01*
X214557Y362975D01*
X214224Y363017D01*
X213891Y362933D01*
X213682Y362725D01*
X213516Y362433D01*
X213474Y362142D01*
X213516Y361850D01*
X213682Y361475D01*
X212599Y361600D01*
Y362725D01*
G01X214807Y364492D02*
X215016Y364783D01*
X215099Y365117D01*
X215016Y365450D01*
X214766Y365742D01*
X214391Y365950D01*
X214016Y366033D01*
X213557D01*
X213182Y365950D01*
X212849Y365742D01*
X212682Y365492D01*
X212599Y365200D01*
X212682Y364867D01*
X212849Y364617D01*
X213099Y364450D01*
X213432Y364367D01*
X213724Y364450D01*
X214016Y364658D01*
X214182Y364908D01*
X214224Y365200D01*
X214141Y365533D01*
X213932Y365783D01*
X213557Y366033D01*
G01X203195Y331051D02*
Y333551D01*
X204236D01*
X204570Y333426D01*
X204778Y333259D01*
X204861Y332926D01*
X204778Y332593D01*
X204528Y332384D01*
X204236Y332259D01*
X203195D01*
G01X204236D02*
X204861Y331051D01*
G01X206336Y333134D02*
X206586Y333384D01*
X206878Y333509D01*
X207211Y333551D01*
X207628Y333468D01*
X207920Y333259D01*
X208003Y333009D01*
X207961Y332759D01*
X207795Y332551D01*
X206961Y332134D01*
X206586Y331843D01*
X206336Y331426D01*
X206253Y331051D01*
X208003D01*
G01X209311Y331551D02*
X209561Y331259D01*
X209895Y331093D01*
X210270Y331051D01*
X210603Y331093D01*
X210936Y331301D01*
X211145Y331551D01*
X211186Y331801D01*
X211103Y332093D01*
X210811Y332301D01*
X210520Y332384D01*
X210145D01*
G01X210520D02*
X210770Y332509D01*
X210978Y332718D01*
X211061Y332968D01*
X210978Y333218D01*
X210770Y333426D01*
X210395Y333551D01*
X210020Y333509D01*
X209645Y333343D01*
G01X212536Y332093D02*
X212828Y332384D01*
X213078Y332551D01*
X213411Y332634D01*
X213703Y332551D01*
X213911Y332384D01*
X214078Y332134D01*
X214120Y331843D01*
X214078Y331593D01*
X213911Y331343D01*
X213661Y331134D01*
X213370Y331051D01*
X213036Y331134D01*
X212745Y331384D01*
X212578Y331759D01*
X212536Y332176D01*
X212620Y332718D01*
X212745Y333009D01*
X212953Y333301D01*
X213245Y333509D01*
X213536Y333551D01*
X213828Y333468D01*
X214036Y333259D01*
G01X241498Y323114D02*
Y336114D01*
G01X215498Y323114D02*
X241498D01*
G01X215498Y336114D02*
Y323114D01*
G01X241498Y336114D02*
X215498D01*
G01X253708Y322867D02*
X253583Y322617D01*
X253500Y322325D01*
Y321992D01*
X253625Y321617D01*
X253833Y321325D01*
X254083Y321117D01*
X254500Y320950D01*
X254875Y320908D01*
X255250Y320992D01*
X255500Y321117D01*
X255750Y321367D01*
X255917Y321658D01*
X256000Y321950D01*
Y322242D01*
X255917Y322533D01*
X255792Y322783D01*
X255625Y322992D01*
G01X253917Y324258D02*
X253667Y324508D01*
X253542Y324800D01*
X253500Y325133D01*
X253583Y325550D01*
X253792Y325842D01*
X254042Y325925D01*
X254292Y325883D01*
X254500Y325717D01*
X254917Y324883D01*
X255208Y324508D01*
X255625Y324258D01*
X256000Y324175D01*
Y325925D01*
G01X255625Y327233D02*
X255833Y327483D01*
X255958Y327775D01*
X256000Y328150D01*
X255917Y328525D01*
X255750Y328817D01*
X255458Y329025D01*
X255125Y329067D01*
X254792Y328983D01*
X254583Y328775D01*
X254417Y328483D01*
X254375Y328192D01*
X254417Y327900D01*
X254583Y327525D01*
X253500Y327650D01*
Y328775D01*
G01X255625Y330333D02*
X255833Y330583D01*
X255958Y330875D01*
X256000Y331250D01*
X255917Y331625D01*
X255750Y331917D01*
X255458Y332125D01*
X255125Y332167D01*
X254792Y332083D01*
X254583Y331875D01*
X254417Y331583D01*
X254375Y331292D01*
X254417Y331000D01*
X254583Y330625D01*
X253500Y330750D01*
Y331875D01*
G01X250498Y333414D02*
Y327914D01*
G01X242498Y333414D02*
X250498D01*
G01X242498Y327914D02*
Y333414D01*
G01Y315814D02*
Y321314D01*
G01X250498Y315814D02*
X242498D01*
G01X250498Y321314D02*
Y315814D01*
G01X236906Y359281D02*
X236781Y359031D01*
X236698Y358739D01*
Y358406D01*
X236823Y358031D01*
X237031Y357739D01*
X237281Y357531D01*
X237698Y357364D01*
X238073Y357322D01*
X238448Y357406D01*
X238698Y357531D01*
X238948Y357781D01*
X239115Y358072D01*
X239198Y358364D01*
Y358656D01*
X239115Y358947D01*
X238990Y359197D01*
X238823Y359406D01*
G01X237115Y360672D02*
X236865Y360922D01*
X236740Y361214D01*
X236698Y361547D01*
X236781Y361964D01*
X236990Y362256D01*
X237240Y362339D01*
X237490Y362297D01*
X237698Y362131D01*
X238115Y361297D01*
X238406Y360922D01*
X238823Y360672D01*
X239198Y360589D01*
Y362339D01*
G01X238823Y363647D02*
X239031Y363897D01*
X239156Y364189D01*
X239198Y364564D01*
X239115Y364939D01*
X238948Y365231D01*
X238656Y365439D01*
X238323Y365481D01*
X237990Y365397D01*
X237781Y365189D01*
X237615Y364897D01*
X237573Y364606D01*
X237615Y364314D01*
X237781Y363939D01*
X236698Y364064D01*
Y365189D01*
G01X238156Y366872D02*
X237865Y367164D01*
X237698Y367414D01*
X237615Y367747D01*
X237698Y368039D01*
X237865Y368247D01*
X238115Y368414D01*
X238406Y368456D01*
X238656Y368414D01*
X238906Y368247D01*
X239115Y367997D01*
X239198Y367706D01*
X239115Y367372D01*
X238865Y367081D01*
X238490Y366914D01*
X238073Y366872D01*
X237531Y366956D01*
X237240Y367081D01*
X236948Y367289D01*
X236740Y367581D01*
X236698Y367872D01*
X236781Y368164D01*
X236990Y368372D01*
G01X233698Y337314D02*
Y342814D01*
G01X241698Y337314D02*
X233698D01*
G01X241698Y342814D02*
Y337314D01*
G01Y354914D02*
Y349414D01*
G01X233698Y354914D02*
X241698D01*
G01X233698Y349414D02*
Y354914D01*
G01X228206Y359281D02*
X228081Y359031D01*
X227998Y358739D01*
Y358406D01*
X228123Y358031D01*
X228331Y357739D01*
X228581Y357531D01*
X228998Y357364D01*
X229373Y357322D01*
X229748Y357406D01*
X229998Y357531D01*
X230248Y357781D01*
X230415Y358072D01*
X230498Y358364D01*
Y358656D01*
X230415Y358947D01*
X230290Y359197D01*
X230123Y359406D01*
G01X228415Y360672D02*
X228165Y360922D01*
X228040Y361214D01*
X227998Y361547D01*
X228081Y361964D01*
X228290Y362256D01*
X228540Y362339D01*
X228790Y362297D01*
X228998Y362131D01*
X229415Y361297D01*
X229706Y360922D01*
X230123Y360672D01*
X230498Y360589D01*
Y362339D01*
G01X230123Y363647D02*
X230331Y363897D01*
X230456Y364189D01*
X230498Y364564D01*
X230415Y364939D01*
X230248Y365231D01*
X229956Y365439D01*
X229623Y365481D01*
X229290Y365397D01*
X229081Y365189D01*
X228915Y364897D01*
X228873Y364606D01*
X228915Y364314D01*
X229081Y363939D01*
X227998Y364064D01*
Y365189D01*
G01X230498Y367581D02*
X229956Y367664D01*
X229498Y367789D01*
X229081Y367956D01*
X228623Y368164D01*
X227998Y368497D01*
Y366831D01*
G01X224998Y337314D02*
Y342814D01*
G01X232998Y337314D02*
X224998D01*
G01X232998Y342814D02*
Y337314D01*
G01Y354914D02*
Y349414D01*
G01X224998Y354914D02*
X232998D01*
G01X224998Y349414D02*
Y354914D01*
G01X219506Y359281D02*
X219381Y359031D01*
X219298Y358739D01*
Y358406D01*
X219423Y358031D01*
X219631Y357739D01*
X219881Y357531D01*
X220298Y357364D01*
X220673Y357322D01*
X221048Y357406D01*
X221298Y357531D01*
X221548Y357781D01*
X221715Y358072D01*
X221798Y358364D01*
Y358656D01*
X221715Y358947D01*
X221590Y359197D01*
X221423Y359406D01*
G01X219715Y360672D02*
X219465Y360922D01*
X219340Y361214D01*
X219298Y361547D01*
X219381Y361964D01*
X219590Y362256D01*
X219840Y362339D01*
X220090Y362297D01*
X220298Y362131D01*
X220715Y361297D01*
X221006Y360922D01*
X221423Y360672D01*
X221798Y360589D01*
Y362339D01*
G01X221423Y363647D02*
X221631Y363897D01*
X221756Y364189D01*
X221798Y364564D01*
X221715Y364939D01*
X221548Y365231D01*
X221256Y365439D01*
X220923Y365481D01*
X220590Y365397D01*
X220381Y365189D01*
X220215Y364897D01*
X220173Y364606D01*
X220215Y364314D01*
X220381Y363939D01*
X219298Y364064D01*
Y365189D01*
G01X221798Y367664D02*
X221756Y367956D01*
X221631Y368289D01*
X221423Y368497D01*
X221131Y368581D01*
X220840Y368497D01*
X220590Y368247D01*
X220465Y367872D01*
Y367456D01*
X220381Y367206D01*
X220173Y366997D01*
X219881Y366914D01*
X219590Y367039D01*
X219381Y367331D01*
X219298Y367664D01*
X219381Y367997D01*
X219590Y368289D01*
X219881Y368414D01*
X220173Y368331D01*
X220381Y368122D01*
X220465Y367872D01*
Y367456D01*
X220590Y367081D01*
X220840Y366831D01*
X221131Y366747D01*
X221423Y366831D01*
X221631Y367039D01*
X221756Y367372D01*
X221798Y367664D01*
G01X216298Y337314D02*
Y342814D01*
G01X224298Y337314D02*
X216298D01*
G01X224298Y342814D02*
Y337314D01*
G01Y354914D02*
Y349414D01*
G01X216298Y354914D02*
X224298D01*
G01X216298Y349414D02*
Y354914D01*
G01X229900Y321700D02*
Y316200D01*
G01X221900Y321700D02*
X229900D01*
G01X221900Y316200D02*
Y321700D01*
G01X189500Y418000D02*
Y411000D01*
G01X192808Y403767D02*
X192683Y403517D01*
X192600Y403225D01*
Y402892D01*
X192725Y402517D01*
X192933Y402225D01*
X193183Y402017D01*
X193600Y401850D01*
X193975Y401808D01*
X194350Y401892D01*
X194600Y402017D01*
X194850Y402267D01*
X195017Y402558D01*
X195100Y402850D01*
Y403142D01*
X195017Y403433D01*
X194892Y403683D01*
X194725Y403892D01*
G01X194600Y405033D02*
X194892Y405283D01*
X195058Y405617D01*
X195100Y405992D01*
X195058Y406325D01*
X194850Y406658D01*
X194600Y406867D01*
X194350Y406908D01*
X194058Y406825D01*
X193850Y406533D01*
X193767Y406242D01*
Y405867D01*
G01Y406242D02*
X193642Y406492D01*
X193433Y406700D01*
X193183Y406783D01*
X192933Y406700D01*
X192725Y406492D01*
X192600Y406117D01*
X192642Y405742D01*
X192808Y405367D01*
G01X194808Y408342D02*
X195017Y408633D01*
X195100Y408967D01*
X195017Y409300D01*
X194767Y409592D01*
X194392Y409800D01*
X194017Y409883D01*
X193558D01*
X193183Y409800D01*
X192850Y409592D01*
X192683Y409342D01*
X192600Y409050D01*
X192683Y408717D01*
X192850Y408467D01*
X193100Y408300D01*
X193433Y408217D01*
X193725Y408300D01*
X194017Y408508D01*
X194183Y408758D01*
X194225Y409050D01*
X194142Y409383D01*
X193933Y409633D01*
X193558Y409883D01*
G01X193017Y411358D02*
X192767Y411608D01*
X192642Y411900D01*
X192600Y412233D01*
X192683Y412650D01*
X192892Y412942D01*
X193142Y413025D01*
X193392Y412983D01*
X193600Y412817D01*
X194017Y411983D01*
X194308Y411608D01*
X194725Y411358D01*
X195100Y411275D01*
Y413025D01*
G01X199600Y402217D02*
X197100D01*
Y403258D01*
X197225Y403592D01*
X197392Y403800D01*
X197725Y403883D01*
X198058Y403800D01*
X198267Y403550D01*
X198392Y403258D01*
Y402217D01*
G01Y403258D02*
X199600Y403883D01*
G01X199225Y405233D02*
X199433Y405483D01*
X199558Y405775D01*
X199600Y406150D01*
X199517Y406525D01*
X199350Y406817D01*
X199058Y407025D01*
X198725Y407067D01*
X198392Y406983D01*
X198183Y406775D01*
X198017Y406483D01*
X197975Y406192D01*
X198017Y405900D01*
X198183Y405525D01*
X197100Y405650D01*
Y406775D01*
G01X199600Y409167D02*
X199058Y409250D01*
X198600Y409375D01*
X198183Y409542D01*
X197725Y409750D01*
X197100Y410083D01*
Y408417D01*
G01X198558Y411558D02*
X198267Y411850D01*
X198100Y412100D01*
X198017Y412433D01*
X198100Y412725D01*
X198267Y412933D01*
X198517Y413100D01*
X198808Y413142D01*
X199058Y413100D01*
X199308Y412933D01*
X199517Y412683D01*
X199600Y412392D01*
X199517Y412058D01*
X199267Y411767D01*
X198892Y411600D01*
X198475Y411558D01*
X197933Y411642D01*
X197642Y411767D01*
X197350Y411975D01*
X197142Y412267D01*
X197100Y412558D01*
X197183Y412850D01*
X197392Y413058D01*
G01X186000Y418800D02*
X190000D01*
Y426200D01*
G01X179817Y402500D02*
Y405000D01*
X180858D01*
X181192Y404875D01*
X181400Y404708D01*
X181483Y404375D01*
X181400Y404042D01*
X181150Y403833D01*
X180858Y403708D01*
X179817D01*
G01X180858D02*
X181483Y402500D01*
G01X182833Y402875D02*
X183083Y402667D01*
X183375Y402542D01*
X183750Y402500D01*
X184125Y402583D01*
X184417Y402750D01*
X184625Y403042D01*
X184667Y403375D01*
X184583Y403708D01*
X184375Y403917D01*
X184083Y404083D01*
X183792Y404125D01*
X183500Y404083D01*
X183125Y403917D01*
X183250Y405000D01*
X184375D01*
G01X186058Y403542D02*
X186350Y403833D01*
X186600Y404000D01*
X186933Y404083D01*
X187225Y404000D01*
X187433Y403833D01*
X187600Y403583D01*
X187642Y403292D01*
X187600Y403042D01*
X187433Y402792D01*
X187183Y402583D01*
X186892Y402500D01*
X186558Y402583D01*
X186267Y402833D01*
X186100Y403208D01*
X186058Y403625D01*
X186142Y404167D01*
X186267Y404458D01*
X186475Y404750D01*
X186767Y404958D01*
X187058Y405000D01*
X187350Y404917D01*
X187558Y404708D01*
G01X189950Y402500D02*
Y405000D01*
X189450Y404500D01*
G01Y402500D02*
X190450D01*
G01X200499Y433033D02*
X202291D01*
X202666Y433200D01*
X202916Y433533D01*
X202999Y433950D01*
X202916Y434367D01*
X202666Y434700D01*
X202291Y434867D01*
X200499D01*
G01X202999Y437550D02*
X200499D01*
X202291Y436008D01*
Y438092D01*
G01X202999Y440150D02*
X200499D01*
X200999Y439650D01*
G01X202999D02*
Y440650D01*
G01X185999Y448350D02*
X183999Y446350D01*
X181999Y448350D01*
G01X178399D02*
Y429150D01*
X189599D01*
Y448350D01*
X178399D01*
G01X209499Y562550D02*
Y572550D01*
G01X216499D02*
Y562550D01*
G01Y567550D02*
X209499D01*
G01X219932Y562550D02*
Y572550D01*
X223266D01*
X224599Y572050D01*
X225599Y571383D01*
X226432Y570383D01*
X227099Y569216D01*
X227266Y567550D01*
X227099Y565883D01*
X226432Y564717D01*
X225599Y563716D01*
X224599Y563050D01*
X223266Y562550D01*
X219932D01*
G01X230532D02*
Y572550D01*
X233866D01*
X235199Y572050D01*
X236199Y571383D01*
X237032Y570383D01*
X237699Y569216D01*
X237866Y567550D01*
X237699Y565883D01*
X237032Y564717D01*
X236199Y563716D01*
X235199Y563050D01*
X233866Y562550D01*
X230532D01*
G01X244799D02*
X245966Y562717D01*
X247299Y563217D01*
X248132Y564050D01*
X248466Y565217D01*
X248132Y566383D01*
X247132Y567383D01*
X245632Y567883D01*
X243966D01*
X242966Y568217D01*
X242132Y569050D01*
X241799Y570217D01*
X242299Y571383D01*
X243465Y572217D01*
X244799Y572550D01*
X246132Y572217D01*
X247299Y571383D01*
X247799Y570217D01*
X247466Y569050D01*
X246632Y568217D01*
X245632Y567883D01*
X243966D01*
X242466Y567383D01*
X241466Y566383D01*
X241132Y565217D01*
X241466Y564050D01*
X242299Y563217D01*
X243632Y562717D01*
X244799Y562550D01*
G01X250399Y559217D02*
X260399D01*
G01X262666Y572550D02*
Y562550D01*
X269332D01*
G01X279932D02*
X273266D01*
Y572550D01*
X279932D01*
G01X277266Y567717D02*
X273266D01*
G01X283532Y562550D02*
Y572550D01*
X286866D01*
X288199Y572050D01*
X289199Y571383D01*
X290032Y570383D01*
X290699Y569216D01*
X290866Y567550D01*
X290699Y565883D01*
X290032Y564717D01*
X289199Y563716D01*
X288199Y563050D01*
X286866Y562550D01*
X283532D01*
G01X212999Y551550D02*
Y541550D01*
G01X209166Y551550D02*
X216832D01*
G01X226932Y541550D02*
X220266D01*
Y551550D01*
X226932D01*
G01X224266Y546717D02*
X220266D01*
G01X229866Y541550D02*
Y551550D01*
X234199Y543217D01*
X238532Y551550D01*
Y541550D01*
G01X241466D02*
Y551550D01*
X245466D01*
X246799Y551050D01*
X247799Y549883D01*
X248132Y548550D01*
X247799Y547217D01*
X246966Y546217D01*
X245466Y545716D01*
X241466D01*
G01X250399Y538217D02*
X260399D01*
G01X262499Y542883D02*
X263832Y542050D01*
X265332Y541550D01*
X266666D01*
X267999Y542050D01*
X268999Y542883D01*
X269499Y544050D01*
X269166Y545216D01*
X268332Y546217D01*
X266832Y546883D01*
X264832Y547217D01*
X263666Y547883D01*
X263166Y549050D01*
X263499Y550217D01*
X264332Y551050D01*
X265499Y551550D01*
X266666D01*
X267832Y551217D01*
X268832Y550383D01*
G01X279932Y541550D02*
X273266D01*
Y551550D01*
X279932D01*
G01X277266Y546717D02*
X273266D01*
G01X283366Y541550D02*
Y551550D01*
X291032Y541550D01*
Y551550D01*
G01X294299Y542883D02*
X295632Y542050D01*
X297132Y541550D01*
X298466D01*
X299799Y542050D01*
X300799Y542883D01*
X301299Y544050D01*
X300966Y545216D01*
X300132Y546217D01*
X298632Y546883D01*
X296632Y547217D01*
X295466Y547883D01*
X294966Y549050D01*
X295299Y550217D01*
X296132Y551050D01*
X297299Y551550D01*
X298466D01*
X299632Y551217D01*
X300632Y550383D01*
G01X308399Y541550D02*
X307065Y541717D01*
X305899Y542383D01*
X304899Y543383D01*
X304232Y544550D01*
X303899Y545883D01*
Y547217D01*
X304232Y548550D01*
X304899Y549717D01*
X305899Y550717D01*
X307065Y551383D01*
X308399Y551550D01*
X309732Y551383D01*
X310899Y550717D01*
X311899Y549717D01*
X312566Y548550D01*
X312899Y547217D01*
Y545883D01*
X312566Y544550D01*
X311899Y543383D01*
X310899Y542383D01*
X309732Y541717D01*
X308399Y541550D01*
G01X315666D02*
Y551550D01*
X319832D01*
X321166Y551050D01*
X321999Y550383D01*
X322332Y549050D01*
X321999Y547717D01*
X320999Y546883D01*
X319832Y546383D01*
X315666D01*
G01X319832D02*
X322332Y541550D01*
G01X326432Y549883D02*
X327432Y550883D01*
X328599Y551383D01*
X329932Y551550D01*
X331599Y551217D01*
X332766Y550383D01*
X333099Y549383D01*
X332932Y548383D01*
X332266Y547550D01*
X328932Y545883D01*
X327432Y544717D01*
X326432Y543050D01*
X326099Y541550D01*
X333099D01*
G01X238108Y509167D02*
X237983Y508917D01*
X237900Y508625D01*
Y508292D01*
X238025Y507917D01*
X238233Y507625D01*
X238483Y507417D01*
X238900Y507250D01*
X239275Y507208D01*
X239650Y507292D01*
X239900Y507417D01*
X240150Y507667D01*
X240317Y507958D01*
X240400Y508250D01*
Y508542D01*
X240317Y508833D01*
X240192Y509083D01*
X240025Y509292D01*
G01X239900Y510433D02*
X240192Y510683D01*
X240358Y511017D01*
X240400Y511392D01*
X240358Y511725D01*
X240150Y512058D01*
X239900Y512267D01*
X239650Y512308D01*
X239358Y512225D01*
X239150Y511933D01*
X239067Y511642D01*
Y511267D01*
G01Y511642D02*
X238942Y511892D01*
X238733Y512100D01*
X238483Y512183D01*
X238233Y512100D01*
X238025Y511892D01*
X237900Y511517D01*
X237942Y511142D01*
X238108Y510767D01*
G01X240400Y514367D02*
X239858Y514450D01*
X239400Y514575D01*
X238983Y514742D01*
X238525Y514950D01*
X237900Y515283D01*
Y513617D01*
G01X240400Y517467D02*
X239858Y517550D01*
X239400Y517675D01*
X238983Y517842D01*
X238525Y518050D01*
X237900Y518383D01*
Y516717D01*
G01X206708Y495267D02*
X206583Y495017D01*
X206500Y494725D01*
Y494392D01*
X206625Y494017D01*
X206833Y493725D01*
X207083Y493517D01*
X207500Y493350D01*
X207875Y493308D01*
X208250Y493392D01*
X208500Y493517D01*
X208750Y493767D01*
X208917Y494058D01*
X209000Y494350D01*
Y494642D01*
X208917Y494933D01*
X208792Y495183D01*
X208625Y495392D01*
G01X208500Y496533D02*
X208792Y496783D01*
X208958Y497117D01*
X209000Y497492D01*
X208958Y497825D01*
X208750Y498158D01*
X208500Y498367D01*
X208250Y498408D01*
X207958Y498325D01*
X207750Y498033D01*
X207667Y497742D01*
Y497367D01*
G01Y497742D02*
X207542Y497992D01*
X207333Y498200D01*
X207083Y498283D01*
X206833Y498200D01*
X206625Y497992D01*
X206500Y497617D01*
X206542Y497242D01*
X206708Y496867D01*
G01X206500Y500550D02*
X206583Y500217D01*
X206792Y499967D01*
X207042Y499800D01*
X207375Y499675D01*
X207750Y499633D01*
X208125Y499675D01*
X208458Y499800D01*
X208708Y499967D01*
X208917Y500217D01*
X209000Y500550D01*
X208917Y500883D01*
X208708Y501133D01*
X208458Y501300D01*
X208125Y501425D01*
X207750Y501467D01*
X207375Y501425D01*
X207042Y501300D01*
X206792Y501133D01*
X206583Y500883D01*
X206500Y500550D01*
G01X208708Y502942D02*
X208917Y503233D01*
X209000Y503567D01*
X208917Y503900D01*
X208667Y504192D01*
X208292Y504400D01*
X207917Y504483D01*
X207458D01*
X207083Y504400D01*
X206750Y504192D01*
X206583Y503942D01*
X206500Y503650D01*
X206583Y503317D01*
X206750Y503067D01*
X207000Y502900D01*
X207333Y502817D01*
X207625Y502900D01*
X207917Y503108D01*
X208083Y503358D01*
X208125Y503650D01*
X208042Y503983D01*
X207833Y504233D01*
X207458Y504483D01*
G01X226208Y524767D02*
X226083Y524517D01*
X226000Y524225D01*
Y523892D01*
X226125Y523517D01*
X226333Y523225D01*
X226583Y523017D01*
X227000Y522850D01*
X227375Y522808D01*
X227750Y522892D01*
X228000Y523017D01*
X228250Y523267D01*
X228417Y523558D01*
X228500Y523850D01*
Y524142D01*
X228417Y524433D01*
X228292Y524683D01*
X228125Y524892D01*
G01X228000Y526033D02*
X228292Y526283D01*
X228458Y526617D01*
X228500Y526992D01*
X228458Y527325D01*
X228250Y527658D01*
X228000Y527867D01*
X227750Y527908D01*
X227458Y527825D01*
X227250Y527533D01*
X227167Y527242D01*
Y526867D01*
G01Y527242D02*
X227042Y527492D01*
X226833Y527700D01*
X226583Y527783D01*
X226333Y527700D01*
X226125Y527492D01*
X226000Y527117D01*
X226042Y526742D01*
X226208Y526367D01*
G01X228500Y530550D02*
X226000D01*
X227792Y529008D01*
Y531092D01*
G01X228500Y533150D02*
X226000D01*
X226500Y532650D01*
G01X228500D02*
Y533650D01*
G01X235000Y516900D02*
X234958Y516567D01*
X234792Y516275D01*
X234542Y516025D01*
X234250Y515858D01*
X233917Y515775D01*
X233583D01*
X233250Y515858D01*
X232958Y516025D01*
X232708Y516275D01*
X232542Y516567D01*
X232500Y516900D01*
X232542Y517233D01*
X232708Y517525D01*
X232958Y517775D01*
X233250Y517942D01*
X233583Y518025D01*
X233917D01*
X234250Y517942D01*
X234542Y517775D01*
X234792Y517525D01*
X234958Y517233D01*
X235000Y516900D01*
G01X234333Y517233D02*
X235000Y517733D01*
G01X232917Y519208D02*
X232667Y519458D01*
X232542Y519750D01*
X232500Y520083D01*
X232583Y520500D01*
X232792Y520792D01*
X233042Y520875D01*
X233292Y520833D01*
X233500Y520667D01*
X233917Y519833D01*
X234208Y519458D01*
X234625Y519208D01*
X235000Y519125D01*
Y520875D01*
G01Y523017D02*
X234458Y523100D01*
X234000Y523225D01*
X233583Y523392D01*
X233125Y523600D01*
X232500Y523933D01*
Y522267D01*
G01X188299Y526113D02*
X190399Y524313D01*
X188299Y522113D01*
G01X188199Y518513D02*
X207399D01*
Y529713D01*
X188199D01*
Y518513D01*
X188599D01*
G01X222000Y509017D02*
X219500D01*
Y510058D01*
X219625Y510392D01*
X219792Y510600D01*
X220125Y510683D01*
X220458Y510600D01*
X220667Y510350D01*
X220792Y510058D01*
Y509017D01*
G01Y510058D02*
X222000Y510683D01*
G01X221500Y512033D02*
X221792Y512283D01*
X221958Y512617D01*
X222000Y512992D01*
X221958Y513325D01*
X221750Y513658D01*
X221500Y513867D01*
X221250Y513908D01*
X220958Y513825D01*
X220750Y513533D01*
X220667Y513242D01*
Y512867D01*
G01Y513242D02*
X220542Y513492D01*
X220333Y513700D01*
X220083Y513783D01*
X219833Y513700D01*
X219625Y513492D01*
X219500Y513117D01*
X219542Y512742D01*
X219708Y512367D01*
G01X222000Y516050D02*
X219500D01*
X220000Y515550D01*
G01X222000D02*
Y516550D01*
G01X221625Y518233D02*
X221833Y518483D01*
X221958Y518775D01*
X222000Y519150D01*
X221917Y519525D01*
X221750Y519817D01*
X221458Y520025D01*
X221125Y520067D01*
X220792Y519983D01*
X220583Y519775D01*
X220417Y519483D01*
X220375Y519192D01*
X220417Y518900D01*
X220583Y518525D01*
X219500Y518650D01*
Y519775D01*
G01X226000Y509017D02*
X223500D01*
Y510058D01*
X223625Y510392D01*
X223792Y510600D01*
X224125Y510683D01*
X224458Y510600D01*
X224667Y510350D01*
X224792Y510058D01*
Y509017D01*
G01Y510058D02*
X226000Y510683D01*
G01X225500Y512033D02*
X225792Y512283D01*
X225958Y512617D01*
X226000Y512992D01*
X225958Y513325D01*
X225750Y513658D01*
X225500Y513867D01*
X225250Y513908D01*
X224958Y513825D01*
X224750Y513533D01*
X224667Y513242D01*
Y512867D01*
G01Y513242D02*
X224542Y513492D01*
X224333Y513700D01*
X224083Y513783D01*
X223833Y513700D01*
X223625Y513492D01*
X223500Y513117D01*
X223542Y512742D01*
X223708Y512367D01*
G01X226000Y516050D02*
X223500D01*
X224000Y515550D01*
G01X226000D02*
Y516550D01*
G01X224958Y518358D02*
X224667Y518650D01*
X224500Y518900D01*
X224417Y519233D01*
X224500Y519525D01*
X224667Y519733D01*
X224917Y519900D01*
X225208Y519942D01*
X225458Y519900D01*
X225708Y519733D01*
X225917Y519483D01*
X226000Y519192D01*
X225917Y518858D01*
X225667Y518567D01*
X225292Y518400D01*
X224875Y518358D01*
X224333Y518442D01*
X224042Y518567D01*
X223750Y518775D01*
X223542Y519067D01*
X223500Y519358D01*
X223583Y519650D01*
X223792Y519858D01*
G01X230000Y509017D02*
X227500D01*
Y510058D01*
X227625Y510392D01*
X227792Y510600D01*
X228125Y510683D01*
X228458Y510600D01*
X228667Y510350D01*
X228792Y510058D01*
Y509017D01*
G01Y510058D02*
X230000Y510683D01*
G01X229500Y512033D02*
X229792Y512283D01*
X229958Y512617D01*
X230000Y512992D01*
X229958Y513325D01*
X229750Y513658D01*
X229500Y513867D01*
X229250Y513908D01*
X228958Y513825D01*
X228750Y513533D01*
X228667Y513242D01*
Y512867D01*
G01Y513242D02*
X228542Y513492D01*
X228333Y513700D01*
X228083Y513783D01*
X227833Y513700D01*
X227625Y513492D01*
X227500Y513117D01*
X227542Y512742D01*
X227708Y512367D01*
G01X230000Y516050D02*
X227500D01*
X228000Y515550D01*
G01X230000D02*
Y516550D01*
G01Y519067D02*
X229458Y519150D01*
X229000Y519275D01*
X228583Y519442D01*
X228125Y519650D01*
X227500Y519983D01*
Y518317D01*
G01X216500Y523017D02*
X214000D01*
Y524058D01*
X214125Y524392D01*
X214292Y524600D01*
X214625Y524683D01*
X214958Y524600D01*
X215167Y524350D01*
X215292Y524058D01*
Y523017D01*
G01Y524058D02*
X216500Y524683D01*
G01X216000Y526033D02*
X216292Y526283D01*
X216458Y526617D01*
X216500Y526992D01*
X216458Y527325D01*
X216250Y527658D01*
X216000Y527867D01*
X215750Y527908D01*
X215458Y527825D01*
X215250Y527533D01*
X215167Y527242D01*
Y526867D01*
G01Y527242D02*
X215042Y527492D01*
X214833Y527700D01*
X214583Y527783D01*
X214333Y527700D01*
X214125Y527492D01*
X214000Y527117D01*
X214042Y526742D01*
X214208Y526367D01*
G01X214417Y529258D02*
X214167Y529508D01*
X214042Y529800D01*
X214000Y530133D01*
X214083Y530550D01*
X214292Y530842D01*
X214542Y530925D01*
X214792Y530883D01*
X215000Y530717D01*
X215417Y529883D01*
X215708Y529508D01*
X216125Y529258D01*
X216500Y529175D01*
Y530925D01*
G01X216000Y532233D02*
X216292Y532483D01*
X216458Y532817D01*
X216500Y533192D01*
X216458Y533525D01*
X216250Y533858D01*
X216000Y534067D01*
X215750Y534108D01*
X215458Y534025D01*
X215250Y533733D01*
X215167Y533442D01*
Y533067D01*
G01Y533442D02*
X215042Y533692D01*
X214833Y533900D01*
X214583Y533983D01*
X214333Y533900D01*
X214125Y533692D01*
X214000Y533317D01*
X214042Y532942D01*
X214208Y532567D01*
G01X220500Y523017D02*
X218000D01*
Y524058D01*
X218125Y524392D01*
X218292Y524600D01*
X218625Y524683D01*
X218958Y524600D01*
X219167Y524350D01*
X219292Y524058D01*
Y523017D01*
G01Y524058D02*
X220500Y524683D01*
G01X220000Y526033D02*
X220292Y526283D01*
X220458Y526617D01*
X220500Y526992D01*
X220458Y527325D01*
X220250Y527658D01*
X220000Y527867D01*
X219750Y527908D01*
X219458Y527825D01*
X219250Y527533D01*
X219167Y527242D01*
Y526867D01*
G01Y527242D02*
X219042Y527492D01*
X218833Y527700D01*
X218583Y527783D01*
X218333Y527700D01*
X218125Y527492D01*
X218000Y527117D01*
X218042Y526742D01*
X218208Y526367D01*
G01X218417Y529258D02*
X218167Y529508D01*
X218042Y529800D01*
X218000Y530133D01*
X218083Y530550D01*
X218292Y530842D01*
X218542Y530925D01*
X218792Y530883D01*
X219000Y530717D01*
X219417Y529883D01*
X219708Y529508D01*
X220125Y529258D01*
X220500Y529175D01*
Y530925D01*
G01Y533650D02*
X218000D01*
X219792Y532108D01*
Y534192D01*
G01X224500Y523017D02*
X222000D01*
Y524058D01*
X222125Y524392D01*
X222292Y524600D01*
X222625Y524683D01*
X222958Y524600D01*
X223167Y524350D01*
X223292Y524058D01*
Y523017D01*
G01Y524058D02*
X224500Y524683D01*
G01X224000Y526033D02*
X224292Y526283D01*
X224458Y526617D01*
X224500Y526992D01*
X224458Y527325D01*
X224250Y527658D01*
X224000Y527867D01*
X223750Y527908D01*
X223458Y527825D01*
X223250Y527533D01*
X223167Y527242D01*
Y526867D01*
G01Y527242D02*
X223042Y527492D01*
X222833Y527700D01*
X222583Y527783D01*
X222333Y527700D01*
X222125Y527492D01*
X222000Y527117D01*
X222042Y526742D01*
X222208Y526367D01*
G01X222417Y529258D02*
X222167Y529508D01*
X222042Y529800D01*
X222000Y530133D01*
X222083Y530550D01*
X222292Y530842D01*
X222542Y530925D01*
X222792Y530883D01*
X223000Y530717D01*
X223417Y529883D01*
X223708Y529508D01*
X224125Y529258D01*
X224500Y529175D01*
Y530925D01*
G01X224125Y532233D02*
X224333Y532483D01*
X224458Y532775D01*
X224500Y533150D01*
X224417Y533525D01*
X224250Y533817D01*
X223958Y534025D01*
X223625Y534067D01*
X223292Y533983D01*
X223083Y533775D01*
X222917Y533483D01*
X222875Y533192D01*
X222917Y532900D01*
X223083Y532525D01*
X222000Y532650D01*
Y533775D01*
G01X179787Y552115D02*
Y554615D01*
X180828D01*
X181162Y554490D01*
X181370Y554323D01*
X181453Y553990D01*
X181370Y553657D01*
X181120Y553448D01*
X180828Y553323D01*
X179787D01*
G01X180828D02*
X181453Y552115D01*
G01X184220D02*
Y554615D01*
X182678Y552823D01*
X184762D01*
G01X186112Y552407D02*
X186403Y552198D01*
X186737Y552115D01*
X187070Y552198D01*
X187362Y552448D01*
X187570Y552823D01*
X187653Y553198D01*
Y553657D01*
X187570Y554032D01*
X187362Y554365D01*
X187112Y554532D01*
X186820Y554615D01*
X186487Y554532D01*
X186237Y554365D01*
X186070Y554115D01*
X185987Y553782D01*
X186070Y553490D01*
X186278Y553198D01*
X186528Y553032D01*
X186820Y552990D01*
X187153Y553073D01*
X187403Y553282D01*
X187653Y553657D01*
G01X189920Y552115D02*
X190212Y552157D01*
X190545Y552282D01*
X190753Y552490D01*
X190837Y552782D01*
X190753Y553073D01*
X190503Y553323D01*
X190128Y553448D01*
X189712D01*
X189462Y553532D01*
X189253Y553740D01*
X189170Y554032D01*
X189295Y554323D01*
X189587Y554532D01*
X189920Y554615D01*
X190253Y554532D01*
X190545Y554323D01*
X190670Y554032D01*
X190587Y553740D01*
X190378Y553532D01*
X190128Y553448D01*
X189712D01*
X189337Y553323D01*
X189087Y553073D01*
X189003Y552782D01*
X189087Y552490D01*
X189295Y552282D01*
X189628Y552157D01*
X189920Y552115D01*
G01X188599Y557300D02*
Y561300D01*
X181199D01*
G01X204500Y494017D02*
X202000D01*
Y495058D01*
X202125Y495392D01*
X202292Y495600D01*
X202625Y495683D01*
X202958Y495600D01*
X203167Y495350D01*
X203292Y495058D01*
Y494017D01*
G01Y495058D02*
X204500Y495683D01*
G01X204125Y497033D02*
X204333Y497283D01*
X204458Y497575D01*
X204500Y497950D01*
X204417Y498325D01*
X204250Y498617D01*
X203958Y498825D01*
X203625Y498867D01*
X203292Y498783D01*
X203083Y498575D01*
X202917Y498283D01*
X202875Y497992D01*
X202917Y497700D01*
X203083Y497325D01*
X202000Y497450D01*
Y498575D01*
G01Y501050D02*
X202083Y500717D01*
X202292Y500467D01*
X202542Y500300D01*
X202875Y500175D01*
X203250Y500133D01*
X203625Y500175D01*
X203958Y500300D01*
X204208Y500467D01*
X204417Y500717D01*
X204500Y501050D01*
X204417Y501383D01*
X204208Y501633D01*
X203958Y501800D01*
X203625Y501925D01*
X203250Y501967D01*
X202875Y501925D01*
X202542Y501800D01*
X202292Y501633D01*
X202083Y501383D01*
X202000Y501050D01*
G01X203458Y503358D02*
X203167Y503650D01*
X203000Y503900D01*
X202917Y504233D01*
X203000Y504525D01*
X203167Y504733D01*
X203417Y504900D01*
X203708Y504942D01*
X203958Y504900D01*
X204208Y504733D01*
X204417Y504483D01*
X204500Y504192D01*
X204417Y503858D01*
X204167Y503567D01*
X203792Y503400D01*
X203375Y503358D01*
X202833Y503442D01*
X202542Y503567D01*
X202250Y503775D01*
X202042Y504067D01*
X202000Y504358D01*
X202083Y504650D01*
X202292Y504858D01*
G01X187999Y501850D02*
X183999D01*
Y494450D01*
G01X200500Y494017D02*
X198000D01*
Y495058D01*
X198125Y495392D01*
X198292Y495600D01*
X198625Y495683D01*
X198958Y495600D01*
X199167Y495350D01*
X199292Y495058D01*
Y494017D01*
G01Y495058D02*
X200500Y495683D01*
G01X200125Y497033D02*
X200333Y497283D01*
X200458Y497575D01*
X200500Y497950D01*
X200417Y498325D01*
X200250Y498617D01*
X199958Y498825D01*
X199625Y498867D01*
X199292Y498783D01*
X199083Y498575D01*
X198917Y498283D01*
X198875Y497992D01*
X198917Y497700D01*
X199083Y497325D01*
X198000Y497450D01*
Y498575D01*
G01Y501050D02*
X198083Y500717D01*
X198292Y500467D01*
X198542Y500300D01*
X198875Y500175D01*
X199250Y500133D01*
X199625Y500175D01*
X199958Y500300D01*
X200208Y500467D01*
X200417Y500717D01*
X200500Y501050D01*
X200417Y501383D01*
X200208Y501633D01*
X199958Y501800D01*
X199625Y501925D01*
X199250Y501967D01*
X198875Y501925D01*
X198542Y501800D01*
X198292Y501633D01*
X198083Y501383D01*
X198000Y501050D01*
G01X200125Y503233D02*
X200333Y503483D01*
X200458Y503775D01*
X200500Y504150D01*
X200417Y504525D01*
X200250Y504817D01*
X199958Y505025D01*
X199625Y505067D01*
X199292Y504983D01*
X199083Y504775D01*
X198917Y504483D01*
X198875Y504192D01*
X198917Y503900D01*
X199083Y503525D01*
X198000Y503650D01*
Y504775D01*
G01X183899Y501850D02*
X179899D01*
Y494450D01*
G01X189483Y492500D02*
Y490708D01*
X189650Y490333D01*
X189983Y490083D01*
X190400Y490000D01*
X190817Y490083D01*
X191150Y490333D01*
X191317Y490708D01*
Y492500D01*
G01X194000Y490000D02*
Y492500D01*
X192458Y490708D01*
X194542D01*
G01X196600Y492500D02*
X196267Y492417D01*
X196017Y492208D01*
X195850Y491958D01*
X195725Y491625D01*
X195683Y491250D01*
X195725Y490875D01*
X195850Y490542D01*
X196017Y490292D01*
X196267Y490083D01*
X196600Y490000D01*
X196933Y490083D01*
X197183Y490292D01*
X197350Y490542D01*
X197475Y490875D01*
X197517Y491250D01*
X197475Y491625D01*
X197350Y491958D01*
X197183Y492208D01*
X196933Y492417D01*
X196600Y492500D01*
G01X186949Y493353D02*
Y483353D01*
G01X183000Y538046D02*
X184792D01*
X185167Y538213D01*
X185417Y538546D01*
X185500Y538963D01*
X185417Y539380D01*
X185167Y539713D01*
X184792Y539880D01*
X183000D01*
G01X185500Y542563D02*
X183000D01*
X184792Y541021D01*
Y543105D01*
G01X185500Y545080D02*
X184958Y545163D01*
X184500Y545288D01*
X184083Y545455D01*
X183625Y545663D01*
X183000Y545996D01*
Y544330D01*
G01X201494Y553598D02*
X201452Y553265D01*
X201286Y552973D01*
X201036Y552723D01*
X200744Y552556D01*
X200411Y552473D01*
X200077D01*
X199744Y552556D01*
X199452Y552723D01*
X199202Y552973D01*
X199036Y553265D01*
X198994Y553598D01*
X199036Y553931D01*
X199202Y554223D01*
X199452Y554473D01*
X199744Y554640D01*
X200077Y554723D01*
X200411D01*
X200744Y554640D01*
X201036Y554473D01*
X201286Y554223D01*
X201452Y553931D01*
X201494Y553598D01*
G01X200827Y553931D02*
X201494Y554431D01*
G01Y557198D02*
X198994D01*
X200786Y555656D01*
Y557740D01*
G01X199411Y559006D02*
X199161Y559256D01*
X199036Y559548D01*
X198994Y559881D01*
X199077Y560298D01*
X199286Y560590D01*
X199536Y560673D01*
X199786Y560631D01*
X199994Y560465D01*
X200411Y559631D01*
X200702Y559256D01*
X201119Y559006D01*
X201494Y558923D01*
Y560673D01*
G01X182799Y561900D02*
X196799D01*
G01X182799Y574900D02*
Y561900D01*
G01X196799D02*
Y574900D01*
G01X217465Y641850D02*
X227465D01*
G01Y634850D02*
X217465D01*
G01X222465D02*
Y641850D01*
G01X217465Y631417D02*
X227465D01*
Y628083D01*
X226965Y626750D01*
X226298Y625750D01*
X225298Y624917D01*
X224131Y624250D01*
X222465Y624083D01*
X220798Y624250D01*
X219632Y624917D01*
X218631Y625750D01*
X217965Y626750D01*
X217465Y628083D01*
Y631417D01*
G01Y620817D02*
X227465D01*
Y617483D01*
X226965Y616150D01*
X226298Y615150D01*
X225298Y614317D01*
X224131Y613650D01*
X222465Y613483D01*
X220798Y613650D01*
X219632Y614317D01*
X218631Y615150D01*
X217965Y616150D01*
X217465Y617483D01*
Y620817D01*
G01Y606550D02*
X217632Y605383D01*
X218132Y604050D01*
X218965Y603217D01*
X220132Y602883D01*
X221298Y603217D01*
X222298Y604217D01*
X222798Y605717D01*
Y607383D01*
X223132Y608383D01*
X223965Y609217D01*
X225132Y609550D01*
X226298Y609050D01*
X227132Y607884D01*
X227465Y606550D01*
X227132Y605217D01*
X226298Y604050D01*
X225132Y603550D01*
X223965Y603883D01*
X223132Y604717D01*
X222798Y605717D01*
Y607383D01*
X222298Y608883D01*
X221298Y609883D01*
X220132Y610217D01*
X218965Y609883D01*
X218132Y609050D01*
X217632Y607717D01*
X217465Y606550D01*
G01X179516Y585550D02*
Y588050D01*
X180557D01*
X180891Y587925D01*
X181099Y587758D01*
X181182Y587425D01*
X181099Y587092D01*
X180849Y586883D01*
X180557Y586758D01*
X179516D01*
G01X180557D02*
X181182Y585550D01*
G01X182657Y587633D02*
X182907Y587883D01*
X183199Y588008D01*
X183532Y588050D01*
X183949Y587967D01*
X184241Y587758D01*
X184324Y587508D01*
X184282Y587258D01*
X184116Y587050D01*
X183282Y586633D01*
X182907Y586342D01*
X182657Y585925D01*
X182574Y585550D01*
X184324D01*
G01X186549D02*
Y588050D01*
X186049Y587550D01*
G01Y585550D02*
X187049D01*
G01X188857Y587633D02*
X189107Y587883D01*
X189399Y588008D01*
X189732Y588050D01*
X190149Y587967D01*
X190441Y587758D01*
X190524Y587508D01*
X190482Y587258D01*
X190316Y587050D01*
X189482Y586633D01*
X189107Y586342D01*
X188857Y585925D01*
X188774Y585550D01*
X190524D01*
G01X179516Y581550D02*
Y584050D01*
X180557D01*
X180891Y583925D01*
X181099Y583758D01*
X181182Y583425D01*
X181099Y583092D01*
X180849Y582883D01*
X180557Y582758D01*
X179516D01*
G01X180557D02*
X181182Y581550D01*
G01X182657Y583633D02*
X182907Y583883D01*
X183199Y584008D01*
X183532Y584050D01*
X183949Y583967D01*
X184241Y583758D01*
X184324Y583508D01*
X184282Y583258D01*
X184116Y583050D01*
X183282Y582633D01*
X182907Y582342D01*
X182657Y581925D01*
X182574Y581550D01*
X184324D01*
G01X186549D02*
Y584050D01*
X186049Y583550D01*
G01Y581550D02*
X187049D01*
G01X190149D02*
Y584050D01*
X188607Y582258D01*
X190691D01*
G01X179516Y577550D02*
Y580050D01*
X180557D01*
X180891Y579925D01*
X181099Y579758D01*
X181182Y579425D01*
X181099Y579092D01*
X180849Y578883D01*
X180557Y578758D01*
X179516D01*
G01X180557D02*
X181182Y577550D01*
G01X182657Y579633D02*
X182907Y579883D01*
X183199Y580008D01*
X183532Y580050D01*
X183949Y579967D01*
X184241Y579758D01*
X184324Y579508D01*
X184282Y579258D01*
X184116Y579050D01*
X183282Y578633D01*
X182907Y578342D01*
X182657Y577925D01*
X182574Y577550D01*
X184324D01*
G01X186549D02*
Y580050D01*
X186049Y579550D01*
G01Y577550D02*
X187049D01*
G01X188857Y578592D02*
X189149Y578883D01*
X189399Y579050D01*
X189732Y579133D01*
X190024Y579050D01*
X190232Y578883D01*
X190399Y578633D01*
X190441Y578342D01*
X190399Y578092D01*
X190232Y577842D01*
X189982Y577633D01*
X189691Y577550D01*
X189357Y577633D01*
X189066Y577883D01*
X188899Y578258D01*
X188857Y578675D01*
X188941Y579217D01*
X189066Y579508D01*
X189274Y579800D01*
X189566Y580008D01*
X189857Y580050D01*
X190149Y579967D01*
X190357Y579758D01*
G01X196799Y574900D02*
X182799D01*
G01X202307Y682817D02*
X202182Y682567D01*
X202099Y682275D01*
Y681942D01*
X202224Y681567D01*
X202432Y681275D01*
X202682Y681067D01*
X203099Y680900D01*
X203474Y680858D01*
X203849Y680942D01*
X204099Y681067D01*
X204349Y681317D01*
X204516Y681608D01*
X204599Y681900D01*
Y682192D01*
X204516Y682483D01*
X204391Y682733D01*
X204224Y682942D01*
G01X202516Y684208D02*
X202266Y684458D01*
X202141Y684750D01*
X202099Y685083D01*
X202182Y685500D01*
X202391Y685792D01*
X202641Y685875D01*
X202891Y685833D01*
X203099Y685667D01*
X203516Y684833D01*
X203807Y684458D01*
X204224Y684208D01*
X204599Y684125D01*
Y685875D01*
G01X204099Y687183D02*
X204391Y687433D01*
X204557Y687767D01*
X204599Y688142D01*
X204557Y688475D01*
X204349Y688808D01*
X204099Y689017D01*
X203849Y689058D01*
X203557Y688975D01*
X203349Y688683D01*
X203266Y688392D01*
Y688017D01*
G01Y688392D02*
X203141Y688642D01*
X202932Y688850D01*
X202682Y688933D01*
X202432Y688850D01*
X202224Y688642D01*
X202099Y688267D01*
X202141Y687892D01*
X202307Y687517D01*
G01X204599Y691200D02*
X204557Y691492D01*
X204432Y691825D01*
X204224Y692033D01*
X203932Y692117D01*
X203641Y692033D01*
X203391Y691783D01*
X203266Y691408D01*
Y690992D01*
X203182Y690742D01*
X202974Y690533D01*
X202682Y690450D01*
X202391Y690575D01*
X202182Y690867D01*
X202099Y691200D01*
X202182Y691533D01*
X202391Y691825D01*
X202682Y691950D01*
X202974Y691867D01*
X203182Y691658D01*
X203266Y691408D01*
Y690992D01*
X203391Y690617D01*
X203641Y690367D01*
X203932Y690283D01*
X204224Y690367D01*
X204432Y690575D01*
X204557Y690908D01*
X204599Y691200D01*
G01X202507Y718217D02*
X202382Y717967D01*
X202299Y717675D01*
Y717342D01*
X202424Y716967D01*
X202632Y716675D01*
X202882Y716467D01*
X203299Y716300D01*
X203674Y716258D01*
X204049Y716342D01*
X204299Y716467D01*
X204549Y716717D01*
X204716Y717008D01*
X204799Y717300D01*
Y717592D01*
X204716Y717883D01*
X204591Y718133D01*
X204424Y718342D01*
G01X202716Y719608D02*
X202466Y719858D01*
X202341Y720150D01*
X202299Y720483D01*
X202382Y720900D01*
X202591Y721192D01*
X202841Y721275D01*
X203091Y721233D01*
X203299Y721067D01*
X203716Y720233D01*
X204007Y719858D01*
X204424Y719608D01*
X204799Y719525D01*
Y721275D01*
G01X204299Y722583D02*
X204591Y722833D01*
X204757Y723167D01*
X204799Y723542D01*
X204757Y723875D01*
X204549Y724208D01*
X204299Y724417D01*
X204049Y724458D01*
X203757Y724375D01*
X203549Y724083D01*
X203466Y723792D01*
Y723417D01*
G01Y723792D02*
X203341Y724042D01*
X203132Y724250D01*
X202882Y724333D01*
X202632Y724250D01*
X202424Y724042D01*
X202299Y723667D01*
X202341Y723292D01*
X202507Y722917D01*
G01X203757Y725808D02*
X203466Y726100D01*
X203299Y726350D01*
X203216Y726683D01*
X203299Y726975D01*
X203466Y727183D01*
X203716Y727350D01*
X204007Y727392D01*
X204257Y727350D01*
X204507Y727183D01*
X204716Y726933D01*
X204799Y726642D01*
X204716Y726308D01*
X204466Y726017D01*
X204091Y725850D01*
X203674Y725808D01*
X203132Y725892D01*
X202841Y726017D01*
X202549Y726225D01*
X202341Y726517D01*
X202299Y726808D01*
X202382Y727100D01*
X202591Y727308D01*
G01X245700Y667800D02*
X245367Y667842D01*
X245075Y668008D01*
X244825Y668258D01*
X244658Y668550D01*
X244575Y668883D01*
Y669217D01*
X244658Y669550D01*
X244825Y669842D01*
X245075Y670092D01*
X245367Y670258D01*
X245700Y670300D01*
X246033Y670258D01*
X246325Y670092D01*
X246575Y669842D01*
X246742Y669550D01*
X246825Y669217D01*
Y668883D01*
X246742Y668550D01*
X246575Y668258D01*
X246325Y668008D01*
X246033Y667842D01*
X245700Y667800D01*
G01X246033Y668467D02*
X246533Y667800D01*
G01X248008Y668842D02*
X248300Y669133D01*
X248550Y669300D01*
X248883Y669383D01*
X249175Y669300D01*
X249383Y669133D01*
X249550Y668883D01*
X249592Y668592D01*
X249550Y668342D01*
X249383Y668092D01*
X249133Y667883D01*
X248842Y667800D01*
X248508Y667883D01*
X248217Y668133D01*
X248050Y668508D01*
X248008Y668925D01*
X248092Y669467D01*
X248217Y669758D01*
X248425Y670050D01*
X248717Y670258D01*
X249008Y670300D01*
X249300Y670217D01*
X249508Y670008D01*
G01X251108Y669883D02*
X251358Y670133D01*
X251650Y670258D01*
X251983Y670300D01*
X252400Y670217D01*
X252692Y670008D01*
X252775Y669758D01*
X252733Y669508D01*
X252567Y669300D01*
X251733Y668883D01*
X251358Y668592D01*
X251108Y668175D01*
X251025Y667800D01*
X252775D01*
G01X238300Y679500D02*
X249700D01*
G01X238300Y692900D02*
Y679500D01*
G01X249700Y692900D02*
X238300D01*
G01X249700Y679500D02*
Y692900D01*
G01X258899Y719850D02*
Y700650D01*
X270099D01*
Y719850D01*
X258899D01*
Y719450D01*
G01X205000Y697517D02*
X202500D01*
Y698558D01*
X202625Y698892D01*
X202792Y699100D01*
X203125Y699183D01*
X203458Y699100D01*
X203667Y698850D01*
X203792Y698558D01*
Y697517D01*
G01Y698558D02*
X205000Y699183D01*
G01X202917Y700658D02*
X202667Y700908D01*
X202542Y701200D01*
X202500Y701533D01*
X202583Y701950D01*
X202792Y702242D01*
X203042Y702325D01*
X203292Y702283D01*
X203500Y702117D01*
X203917Y701283D01*
X204208Y700908D01*
X204625Y700658D01*
X205000Y700575D01*
Y702325D01*
G01Y704550D02*
X202500D01*
X203000Y704050D01*
G01X205000D02*
Y705050D01*
G01Y707650D02*
X204958Y707942D01*
X204833Y708275D01*
X204625Y708483D01*
X204333Y708567D01*
X204042Y708483D01*
X203792Y708233D01*
X203667Y707858D01*
Y707442D01*
X203583Y707192D01*
X203375Y706983D01*
X203083Y706900D01*
X202792Y707025D01*
X202583Y707317D01*
X202500Y707650D01*
X202583Y707983D01*
X202792Y708275D01*
X203083Y708400D01*
X203375Y708317D01*
X203583Y708108D01*
X203667Y707858D01*
Y707442D01*
X203792Y707067D01*
X204042Y706817D01*
X204333Y706733D01*
X204625Y706817D01*
X204833Y707025D01*
X204958Y707358D01*
X205000Y707650D01*
G01X241999Y696550D02*
Y709550D01*
G01X215999Y696550D02*
X241999D01*
G01X215999Y709550D02*
Y696550D01*
G01X241999Y709550D02*
X215999D01*
G01X211617Y677300D02*
Y679800D01*
X212658D01*
X212992Y679675D01*
X213200Y679508D01*
X213283Y679175D01*
X213200Y678842D01*
X212950Y678633D01*
X212658Y678508D01*
X211617D01*
G01X212658D02*
X213283Y677300D01*
G01X214758Y679383D02*
X215008Y679633D01*
X215300Y679758D01*
X215633Y679800D01*
X216050Y679717D01*
X216342Y679508D01*
X216425Y679258D01*
X216383Y679008D01*
X216217Y678800D01*
X215383Y678383D01*
X215008Y678092D01*
X214758Y677675D01*
X214675Y677300D01*
X216425D01*
G01X218650D02*
Y679800D01*
X218150Y679300D01*
G01Y677300D02*
X219150D01*
G01X221667D02*
X221750Y677842D01*
X221875Y678300D01*
X222042Y678717D01*
X222250Y679175D01*
X222583Y679800D01*
X220917D01*
G01X231699Y691550D02*
Y695550D01*
X224299D01*
G01X211617Y673300D02*
Y675800D01*
X212658D01*
X212992Y675675D01*
X213200Y675508D01*
X213283Y675175D01*
X213200Y674842D01*
X212950Y674633D01*
X212658Y674508D01*
X211617D01*
G01X212658D02*
X213283Y673300D01*
G01X214633Y673800D02*
X214883Y673508D01*
X215217Y673342D01*
X215592Y673300D01*
X215925Y673342D01*
X216258Y673550D01*
X216467Y673800D01*
X216508Y674050D01*
X216425Y674342D01*
X216133Y674550D01*
X215842Y674633D01*
X215467D01*
G01X215842D02*
X216092Y674758D01*
X216300Y674967D01*
X216383Y675217D01*
X216300Y675467D01*
X216092Y675675D01*
X215717Y675800D01*
X215342Y675758D01*
X214967Y675592D01*
G01X217942Y673592D02*
X218233Y673383D01*
X218567Y673300D01*
X218900Y673383D01*
X219192Y673633D01*
X219400Y674008D01*
X219483Y674383D01*
Y674842D01*
X219400Y675217D01*
X219192Y675550D01*
X218942Y675717D01*
X218650Y675800D01*
X218317Y675717D01*
X218067Y675550D01*
X217900Y675300D01*
X217817Y674967D01*
X217900Y674675D01*
X218108Y674383D01*
X218358Y674217D01*
X218650Y674175D01*
X218983Y674258D01*
X219233Y674467D01*
X219483Y674842D01*
G01X220833Y673800D02*
X221083Y673508D01*
X221417Y673342D01*
X221792Y673300D01*
X222125Y673342D01*
X222458Y673550D01*
X222667Y673800D01*
X222708Y674050D01*
X222625Y674342D01*
X222333Y674550D01*
X222042Y674633D01*
X221667D01*
G01X222042D02*
X222292Y674758D01*
X222500Y674967D01*
X222583Y675217D01*
X222500Y675467D01*
X222292Y675675D01*
X221917Y675800D01*
X221542Y675758D01*
X221167Y675592D01*
G01X224300Y691500D02*
Y687500D01*
X231700D01*
G01X238017Y663500D02*
Y666000D01*
X239058D01*
X239392Y665875D01*
X239600Y665708D01*
X239683Y665375D01*
X239600Y665042D01*
X239350Y664833D01*
X239058Y664708D01*
X238017D01*
G01X239058D02*
X239683Y663500D01*
G01X241033Y664000D02*
X241283Y663708D01*
X241617Y663542D01*
X241992Y663500D01*
X242325Y663542D01*
X242658Y663750D01*
X242867Y664000D01*
X242908Y664250D01*
X242825Y664542D01*
X242533Y664750D01*
X242242Y664833D01*
X241867D01*
G01X242242D02*
X242492Y664958D01*
X242700Y665167D01*
X242783Y665417D01*
X242700Y665667D01*
X242492Y665875D01*
X242117Y666000D01*
X241742Y665958D01*
X241367Y665792D01*
G01X245050Y663500D02*
X245342Y663542D01*
X245675Y663667D01*
X245883Y663875D01*
X245967Y664167D01*
X245883Y664458D01*
X245633Y664708D01*
X245258Y664833D01*
X244842D01*
X244592Y664917D01*
X244383Y665125D01*
X244300Y665417D01*
X244425Y665708D01*
X244717Y665917D01*
X245050Y666000D01*
X245383Y665917D01*
X245675Y665708D01*
X245800Y665417D01*
X245717Y665125D01*
X245508Y664917D01*
X245258Y664833D01*
X244842D01*
X244467Y664708D01*
X244217Y664458D01*
X244133Y664167D01*
X244217Y663875D01*
X244425Y663667D01*
X244758Y663542D01*
X245050Y663500D01*
G01X247233Y663875D02*
X247483Y663667D01*
X247775Y663542D01*
X248150Y663500D01*
X248525Y663583D01*
X248817Y663750D01*
X249025Y664042D01*
X249067Y664375D01*
X248983Y664708D01*
X248775Y664917D01*
X248483Y665083D01*
X248192Y665125D01*
X247900Y665083D01*
X247525Y664917D01*
X247650Y666000D01*
X248775D01*
G01X245400Y675100D02*
Y679100D01*
X238000D01*
G01X209099Y679567D02*
X206599D01*
Y680608D01*
X206724Y680942D01*
X206891Y681150D01*
X207224Y681233D01*
X207557Y681150D01*
X207766Y680900D01*
X207891Y680608D01*
Y679567D01*
G01Y680608D02*
X209099Y681233D01*
G01X207016Y682708D02*
X206766Y682958D01*
X206641Y683250D01*
X206599Y683583D01*
X206682Y684000D01*
X206891Y684292D01*
X207141Y684375D01*
X207391Y684333D01*
X207599Y684167D01*
X208016Y683333D01*
X208307Y682958D01*
X208724Y682708D01*
X209099Y682625D01*
Y684375D01*
G01Y686600D02*
X206599D01*
X207099Y686100D01*
G01X209099D02*
Y687100D01*
G01X208807Y688992D02*
X209016Y689283D01*
X209099Y689617D01*
X209016Y689950D01*
X208766Y690242D01*
X208391Y690450D01*
X208016Y690533D01*
X207557D01*
X207182Y690450D01*
X206849Y690242D01*
X206682Y689992D01*
X206599Y689700D01*
X206682Y689367D01*
X206849Y689117D01*
X207099Y688950D01*
X207432Y688867D01*
X207724Y688950D01*
X208016Y689158D01*
X208182Y689408D01*
X208224Y689700D01*
X208141Y690033D01*
X207932Y690283D01*
X207557Y690533D01*
G01X254767Y729792D02*
X254517Y729917D01*
X254225Y730000D01*
X253892D01*
X253517Y729875D01*
X253225Y729667D01*
X253017Y729417D01*
X252850Y729000D01*
X252808Y728625D01*
X252892Y728250D01*
X253017Y728000D01*
X253267Y727750D01*
X253558Y727583D01*
X253850Y727500D01*
X254142D01*
X254433Y727583D01*
X254683Y727708D01*
X254892Y727875D01*
G01X256158Y729583D02*
X256408Y729833D01*
X256700Y729958D01*
X257033Y730000D01*
X257450Y729917D01*
X257742Y729708D01*
X257825Y729458D01*
X257783Y729208D01*
X257617Y729000D01*
X256783Y728583D01*
X256408Y728292D01*
X256158Y727875D01*
X256075Y727500D01*
X257825D01*
G01X259133Y728000D02*
X259383Y727708D01*
X259717Y727542D01*
X260092Y727500D01*
X260425Y727542D01*
X260758Y727750D01*
X260967Y728000D01*
X261008Y728250D01*
X260925Y728542D01*
X260633Y728750D01*
X260342Y728833D01*
X259967D01*
G01X260342D02*
X260592Y728958D01*
X260800Y729167D01*
X260883Y729417D01*
X260800Y729667D01*
X260592Y729875D01*
X260217Y730000D01*
X259842Y729958D01*
X259467Y729792D01*
G01X262442Y727792D02*
X262733Y727583D01*
X263067Y727500D01*
X263400Y727583D01*
X263692Y727833D01*
X263900Y728208D01*
X263983Y728583D01*
Y729042D01*
X263900Y729417D01*
X263692Y729750D01*
X263442Y729917D01*
X263150Y730000D01*
X262817Y729917D01*
X262567Y729750D01*
X262400Y729500D01*
X262317Y729167D01*
X262400Y728875D01*
X262608Y728583D01*
X262858Y728417D01*
X263150Y728375D01*
X263483Y728458D01*
X263733Y728667D01*
X263983Y729042D01*
G01X242499Y722750D02*
Y728250D01*
G01X250499Y722750D02*
X242499D01*
G01X250499Y728250D02*
Y722750D01*
G01X206508Y718167D02*
X206383Y717917D01*
X206300Y717625D01*
Y717292D01*
X206425Y716917D01*
X206633Y716625D01*
X206883Y716417D01*
X207300Y716250D01*
X207675Y716208D01*
X208050Y716292D01*
X208300Y716417D01*
X208550Y716667D01*
X208717Y716958D01*
X208800Y717250D01*
Y717542D01*
X208717Y717833D01*
X208592Y718083D01*
X208425Y718292D01*
G01X206717Y719558D02*
X206467Y719808D01*
X206342Y720100D01*
X206300Y720433D01*
X206383Y720850D01*
X206592Y721142D01*
X206842Y721225D01*
X207092Y721183D01*
X207300Y721017D01*
X207717Y720183D01*
X208008Y719808D01*
X208425Y719558D01*
X208800Y719475D01*
Y721225D01*
G01X208300Y722533D02*
X208592Y722783D01*
X208758Y723117D01*
X208800Y723492D01*
X208758Y723825D01*
X208550Y724158D01*
X208300Y724367D01*
X208050Y724408D01*
X207758Y724325D01*
X207550Y724033D01*
X207467Y723742D01*
Y723367D01*
G01Y723742D02*
X207342Y723992D01*
X207133Y724200D01*
X206883Y724283D01*
X206633Y724200D01*
X206425Y723992D01*
X206300Y723617D01*
X206342Y723242D01*
X206508Y722867D01*
G01X208800Y726467D02*
X208258Y726550D01*
X207800Y726675D01*
X207383Y726842D01*
X206925Y727050D01*
X206300Y727383D01*
Y725717D01*
G01X221499Y711750D02*
Y717250D01*
G01X229499Y711750D02*
X221499D01*
G01X229499Y717250D02*
Y711750D01*
G01Y729350D02*
Y723850D01*
G01X221499D02*
Y729350D01*
G01X227400Y668500D02*
X227067Y668542D01*
X226775Y668708D01*
X226525Y668958D01*
X226358Y669250D01*
X226275Y669583D01*
Y669917D01*
X226358Y670250D01*
X226525Y670542D01*
X226775Y670792D01*
X227067Y670958D01*
X227400Y671000D01*
X227733Y670958D01*
X228025Y670792D01*
X228275Y670542D01*
X228442Y670250D01*
X228525Y669917D01*
Y669583D01*
X228442Y669250D01*
X228275Y668958D01*
X228025Y668708D01*
X227733Y668542D01*
X227400Y668500D01*
G01X227733Y669167D02*
X228233Y668500D01*
G01X229708Y669542D02*
X230000Y669833D01*
X230250Y670000D01*
X230583Y670083D01*
X230875Y670000D01*
X231083Y669833D01*
X231250Y669583D01*
X231292Y669292D01*
X231250Y669042D01*
X231083Y668792D01*
X230833Y668583D01*
X230542Y668500D01*
X230208Y668583D01*
X229917Y668833D01*
X229750Y669208D01*
X229708Y669625D01*
X229792Y670167D01*
X229917Y670458D01*
X230125Y670750D01*
X230417Y670958D01*
X230708Y671000D01*
X231000Y670917D01*
X231208Y670708D01*
G01X232683Y669000D02*
X232933Y668708D01*
X233267Y668542D01*
X233642Y668500D01*
X233975Y668542D01*
X234308Y668750D01*
X234517Y669000D01*
X234558Y669250D01*
X234475Y669542D01*
X234183Y669750D01*
X233892Y669833D01*
X233517D01*
G01X233892D02*
X234142Y669958D01*
X234350Y670167D01*
X234433Y670417D01*
X234350Y670667D01*
X234142Y670875D01*
X233767Y671000D01*
X233392Y670958D01*
X233017Y670792D01*
G01X237400Y673000D02*
Y687000D01*
G01X224400Y673000D02*
X237400D01*
G01X224400Y687000D02*
Y673000D01*
G01X237400Y687000D02*
X224400D01*
G01X206467Y648875D02*
X206675Y649208D01*
X206800Y649583D01*
Y649917D01*
X206675Y650250D01*
X206467Y650500D01*
X206175Y650625D01*
X205883Y650542D01*
X205633Y650333D01*
X205467Y649958D01*
X205383Y649458D01*
X205217Y649167D01*
X204925Y649042D01*
X204633Y649125D01*
X204425Y649333D01*
X204300Y649625D01*
Y649917D01*
X204383Y650208D01*
X204592Y650458D01*
G01X206800Y651933D02*
X204300D01*
G01Y653517D02*
X205842Y651933D01*
G01X206800Y653767D02*
X205133Y652642D01*
G01X204300Y655950D02*
X206800D01*
G01X204300Y654992D02*
Y656908D01*
G01X206508Y658342D02*
X206717Y658633D01*
X206800Y658967D01*
X206717Y659300D01*
X206467Y659592D01*
X206092Y659800D01*
X205717Y659883D01*
X205258D01*
X204883Y659800D01*
X204550Y659592D01*
X204383Y659342D01*
X204300Y659050D01*
X204383Y658717D01*
X204550Y658467D01*
X204800Y658300D01*
X205133Y658217D01*
X205425Y658300D01*
X205717Y658508D01*
X205883Y658758D01*
X205925Y659050D01*
X205842Y659383D01*
X205633Y659633D01*
X205258Y659883D01*
G01X204483Y804000D02*
Y806500D01*
X205317D01*
X205650Y806375D01*
X205900Y806208D01*
X206108Y805958D01*
X206275Y805667D01*
X206317Y805250D01*
X206275Y804833D01*
X206108Y804542D01*
X205900Y804292D01*
X205650Y804125D01*
X205317Y804000D01*
X204483D01*
G01X207708Y806083D02*
X207958Y806333D01*
X208250Y806458D01*
X208583Y806500D01*
X209000Y806417D01*
X209292Y806208D01*
X209375Y805958D01*
X209333Y805708D01*
X209167Y805500D01*
X208333Y805083D01*
X207958Y804792D01*
X207708Y804375D01*
X207625Y804000D01*
X209375D01*
G01X211517D02*
X211600Y804542D01*
X211725Y805000D01*
X211892Y805417D01*
X212100Y805875D01*
X212433Y806500D01*
X210767D01*
G01X216500Y809000D02*
X200400D01*
G01X216500Y816000D02*
Y809000D01*
G01X200400D02*
Y816000D01*
G01X231308Y813767D02*
X231183Y813517D01*
X231100Y813225D01*
Y812892D01*
X231225Y812517D01*
X231433Y812225D01*
X231683Y812017D01*
X232100Y811850D01*
X232475Y811808D01*
X232850Y811892D01*
X233100Y812017D01*
X233350Y812267D01*
X233517Y812558D01*
X233600Y812850D01*
Y813142D01*
X233517Y813433D01*
X233392Y813683D01*
X233225Y813892D01*
G01X233100Y815033D02*
X233392Y815283D01*
X233558Y815617D01*
X233600Y815992D01*
X233558Y816325D01*
X233350Y816658D01*
X233100Y816867D01*
X232850Y816908D01*
X232558Y816825D01*
X232350Y816533D01*
X232267Y816242D01*
Y815867D01*
G01Y816242D02*
X232142Y816492D01*
X231933Y816700D01*
X231683Y816783D01*
X231433Y816700D01*
X231225Y816492D01*
X231100Y816117D01*
X231142Y815742D01*
X231308Y815367D01*
G01X233308Y818342D02*
X233517Y818633D01*
X233600Y818967D01*
X233517Y819300D01*
X233267Y819592D01*
X232892Y819800D01*
X232517Y819883D01*
X232058D01*
X231683Y819800D01*
X231350Y819592D01*
X231183Y819342D01*
X231100Y819050D01*
X231183Y818717D01*
X231350Y818467D01*
X231600Y818300D01*
X231933Y818217D01*
X232225Y818300D01*
X232517Y818508D01*
X232683Y818758D01*
X232725Y819050D01*
X232642Y819383D01*
X232433Y819633D01*
X232058Y819883D01*
G01X233600Y822150D02*
X231100D01*
X231600Y821650D01*
G01X233600D02*
Y822650D01*
G01X213208Y763767D02*
X213083Y763517D01*
X213000Y763225D01*
Y762892D01*
X213125Y762517D01*
X213333Y762225D01*
X213583Y762017D01*
X214000Y761850D01*
X214375Y761808D01*
X214750Y761892D01*
X215000Y762017D01*
X215250Y762267D01*
X215417Y762558D01*
X215500Y762850D01*
Y763142D01*
X215417Y763433D01*
X215292Y763683D01*
X215125Y763892D01*
G01X213417Y765158D02*
X213167Y765408D01*
X213042Y765700D01*
X213000Y766033D01*
X213083Y766450D01*
X213292Y766742D01*
X213542Y766825D01*
X213792Y766783D01*
X214000Y766617D01*
X214417Y765783D01*
X214708Y765408D01*
X215125Y765158D01*
X215500Y765075D01*
Y766825D01*
G01Y769550D02*
X213000D01*
X214792Y768008D01*
Y770092D01*
G01X215000Y771233D02*
X215292Y771483D01*
X215458Y771817D01*
X215500Y772192D01*
X215458Y772525D01*
X215250Y772858D01*
X215000Y773067D01*
X214750Y773108D01*
X214458Y773025D01*
X214250Y772733D01*
X214167Y772442D01*
Y772067D01*
G01Y772442D02*
X214042Y772692D01*
X213833Y772900D01*
X213583Y772983D01*
X213333Y772900D01*
X213125Y772692D01*
X213000Y772317D01*
X213042Y771942D01*
X213208Y771567D01*
G01X185100Y804800D02*
X184767Y804842D01*
X184475Y805008D01*
X184225Y805258D01*
X184058Y805550D01*
X183975Y805883D01*
Y806217D01*
X184058Y806550D01*
X184225Y806842D01*
X184475Y807092D01*
X184767Y807258D01*
X185100Y807300D01*
X185433Y807258D01*
X185725Y807092D01*
X185975Y806842D01*
X186142Y806550D01*
X186225Y806217D01*
Y805883D01*
X186142Y805550D01*
X185975Y805258D01*
X185725Y805008D01*
X185433Y804842D01*
X185100Y804800D01*
G01X185433Y805467D02*
X185933Y804800D01*
G01X187408Y806883D02*
X187658Y807133D01*
X187950Y807258D01*
X188283Y807300D01*
X188700Y807217D01*
X188992Y807008D01*
X189075Y806758D01*
X189033Y806508D01*
X188867Y806300D01*
X188033Y805883D01*
X187658Y805592D01*
X187408Y805175D01*
X187325Y804800D01*
X189075D01*
G01X190508Y805842D02*
X190800Y806133D01*
X191050Y806300D01*
X191383Y806383D01*
X191675Y806300D01*
X191883Y806133D01*
X192050Y805883D01*
X192092Y805592D01*
X192050Y805342D01*
X191883Y805092D01*
X191633Y804883D01*
X191342Y804800D01*
X191008Y804883D01*
X190717Y805133D01*
X190550Y805508D01*
X190508Y805925D01*
X190592Y806467D01*
X190717Y806758D01*
X190925Y807050D01*
X191217Y807258D01*
X191508Y807300D01*
X191800Y807217D01*
X192008Y807008D01*
G01X202131Y730789D02*
Y733289D01*
X203172D01*
X203506Y733164D01*
X203714Y732997D01*
X203797Y732664D01*
X203714Y732331D01*
X203464Y732122D01*
X203172Y731997D01*
X202131D01*
G01X203172D02*
X203797Y730789D01*
G01X205272Y732872D02*
X205522Y733122D01*
X205814Y733247D01*
X206147Y733289D01*
X206564Y733206D01*
X206856Y732997D01*
X206939Y732747D01*
X206897Y732497D01*
X206731Y732289D01*
X205897Y731872D01*
X205522Y731581D01*
X205272Y731164D01*
X205189Y730789D01*
X206939D01*
G01X208372Y732872D02*
X208622Y733122D01*
X208914Y733247D01*
X209247Y733289D01*
X209664Y733206D01*
X209956Y732997D01*
X210039Y732747D01*
X209997Y732497D01*
X209831Y732289D01*
X208997Y731872D01*
X208622Y731581D01*
X208372Y731164D01*
X208289Y730789D01*
X210039D01*
G01X211347Y731289D02*
X211597Y730997D01*
X211931Y730831D01*
X212306Y730789D01*
X212639Y730831D01*
X212972Y731039D01*
X213181Y731289D01*
X213222Y731539D01*
X213139Y731831D01*
X212847Y732039D01*
X212556Y732122D01*
X212181D01*
G01X212556D02*
X212806Y732247D01*
X213014Y732456D01*
X213097Y732706D01*
X213014Y732956D01*
X212806Y733164D01*
X212431Y733289D01*
X212056Y733247D01*
X211681Y733081D01*
G01X241499Y730550D02*
Y743550D01*
G01X215499Y730550D02*
X241499D01*
G01X215499Y743550D02*
Y730550D01*
G01X241499Y743550D02*
X215499D01*
G01X237600Y812017D02*
X235100D01*
Y813058D01*
X235225Y813392D01*
X235392Y813600D01*
X235725Y813683D01*
X236058Y813600D01*
X236267Y813350D01*
X236392Y813058D01*
Y812017D01*
G01Y813058D02*
X237600Y813683D01*
G01X237225Y815033D02*
X237433Y815283D01*
X237558Y815575D01*
X237600Y815950D01*
X237517Y816325D01*
X237350Y816617D01*
X237058Y816825D01*
X236725Y816867D01*
X236392Y816783D01*
X236183Y816575D01*
X236017Y816283D01*
X235975Y815992D01*
X236017Y815700D01*
X236183Y815325D01*
X235100Y815450D01*
Y816575D01*
G01X237600Y818967D02*
X237058Y819050D01*
X236600Y819175D01*
X236183Y819342D01*
X235725Y819550D01*
X235100Y819883D01*
Y818217D01*
G01X237225Y821233D02*
X237433Y821483D01*
X237558Y821775D01*
X237600Y822150D01*
X237517Y822525D01*
X237350Y822817D01*
X237058Y823025D01*
X236725Y823067D01*
X236392Y822983D01*
X236183Y822775D01*
X236017Y822483D01*
X235975Y822192D01*
X236017Y821900D01*
X236183Y821525D01*
X235100Y821650D01*
Y822775D01*
G01X229600Y812017D02*
X227100D01*
Y813058D01*
X227225Y813392D01*
X227392Y813600D01*
X227725Y813683D01*
X228058Y813600D01*
X228267Y813350D01*
X228392Y813058D01*
Y812017D01*
G01Y813058D02*
X229600Y813683D01*
G01X229225Y815033D02*
X229433Y815283D01*
X229558Y815575D01*
X229600Y815950D01*
X229517Y816325D01*
X229350Y816617D01*
X229058Y816825D01*
X228725Y816867D01*
X228392Y816783D01*
X228183Y816575D01*
X228017Y816283D01*
X227975Y815992D01*
X228017Y815700D01*
X228183Y815325D01*
X227100Y815450D01*
Y816575D01*
G01X228558Y818258D02*
X228267Y818550D01*
X228100Y818800D01*
X228017Y819133D01*
X228100Y819425D01*
X228267Y819633D01*
X228517Y819800D01*
X228808Y819842D01*
X229058Y819800D01*
X229308Y819633D01*
X229517Y819383D01*
X229600Y819092D01*
X229517Y818758D01*
X229267Y818467D01*
X228892Y818300D01*
X228475Y818258D01*
X227933Y818342D01*
X227642Y818467D01*
X227350Y818675D01*
X227142Y818967D01*
X227100Y819258D01*
X227183Y819550D01*
X227392Y819758D01*
G01X227100Y822150D02*
X227183Y821817D01*
X227392Y821567D01*
X227642Y821400D01*
X227975Y821275D01*
X228350Y821233D01*
X228725Y821275D01*
X229058Y821400D01*
X229308Y821567D01*
X229517Y821817D01*
X229600Y822150D01*
X229517Y822483D01*
X229308Y822733D01*
X229058Y822900D01*
X228725Y823025D01*
X228350Y823067D01*
X227975Y823025D01*
X227642Y822900D01*
X227392Y822733D01*
X227183Y822483D01*
X227100Y822150D01*
G01X186699Y809930D02*
X184199D01*
Y810971D01*
X184324Y811305D01*
X184491Y811513D01*
X184824Y811596D01*
X185157Y811513D01*
X185366Y811263D01*
X185491Y810971D01*
Y809930D01*
G01Y810971D02*
X186699Y811596D01*
G01X184616Y813071D02*
X184366Y813321D01*
X184241Y813613D01*
X184199Y813946D01*
X184282Y814363D01*
X184491Y814655D01*
X184741Y814738D01*
X184991Y814696D01*
X185199Y814530D01*
X185616Y813696D01*
X185907Y813321D01*
X186324Y813071D01*
X186699Y812988D01*
Y814738D01*
G01Y816880D02*
X186157Y816963D01*
X185699Y817088D01*
X185282Y817255D01*
X184824Y817463D01*
X184199Y817796D01*
Y816130D01*
G01X186324Y819146D02*
X186532Y819396D01*
X186657Y819688D01*
X186699Y820063D01*
X186616Y820438D01*
X186449Y820730D01*
X186157Y820938D01*
X185824Y820980D01*
X185491Y820896D01*
X185282Y820688D01*
X185116Y820396D01*
X185074Y820105D01*
X185116Y819813D01*
X185282Y819438D01*
X184199Y819563D01*
Y820688D01*
G01X191199Y809930D02*
X188699D01*
Y810971D01*
X188824Y811305D01*
X188991Y811513D01*
X189324Y811596D01*
X189657Y811513D01*
X189866Y811263D01*
X189991Y810971D01*
Y809930D01*
G01Y810971D02*
X191199Y811596D01*
G01X189116Y813071D02*
X188866Y813321D01*
X188741Y813613D01*
X188699Y813946D01*
X188782Y814363D01*
X188991Y814655D01*
X189241Y814738D01*
X189491Y814696D01*
X189699Y814530D01*
X190116Y813696D01*
X190407Y813321D01*
X190824Y813071D01*
X191199Y812988D01*
Y814738D01*
G01Y816880D02*
X190657Y816963D01*
X190199Y817088D01*
X189782Y817255D01*
X189324Y817463D01*
X188699Y817796D01*
Y816130D01*
G01X191199Y820063D02*
X191157Y820355D01*
X191032Y820688D01*
X190824Y820896D01*
X190532Y820980D01*
X190241Y820896D01*
X189991Y820646D01*
X189866Y820271D01*
Y819855D01*
X189782Y819605D01*
X189574Y819396D01*
X189282Y819313D01*
X188991Y819438D01*
X188782Y819730D01*
X188699Y820063D01*
X188782Y820396D01*
X188991Y820688D01*
X189282Y820813D01*
X189574Y820730D01*
X189782Y820521D01*
X189866Y820271D01*
Y819855D01*
X189991Y819480D01*
X190241Y819230D01*
X190532Y819146D01*
X190824Y819230D01*
X191032Y819438D01*
X191157Y819771D01*
X191199Y820063D01*
G01X225600Y812017D02*
X223100D01*
Y813058D01*
X223225Y813392D01*
X223392Y813600D01*
X223725Y813683D01*
X224058Y813600D01*
X224267Y813350D01*
X224392Y813058D01*
Y812017D01*
G01Y813058D02*
X225600Y813683D01*
G01Y816450D02*
X223100D01*
X224892Y814908D01*
Y816992D01*
G01X223517Y818258D02*
X223267Y818508D01*
X223142Y818800D01*
X223100Y819133D01*
X223183Y819550D01*
X223392Y819842D01*
X223642Y819925D01*
X223892Y819883D01*
X224100Y819717D01*
X224517Y818883D01*
X224808Y818508D01*
X225225Y818258D01*
X225600Y818175D01*
Y819925D01*
G01X223100Y822150D02*
X223183Y821817D01*
X223392Y821567D01*
X223642Y821400D01*
X223975Y821275D01*
X224350Y821233D01*
X224725Y821275D01*
X225058Y821400D01*
X225308Y821567D01*
X225517Y821817D01*
X225600Y822150D01*
X225517Y822483D01*
X225308Y822733D01*
X225058Y822900D01*
X224725Y823025D01*
X224350Y823067D01*
X223975Y823025D01*
X223642Y822900D01*
X223392Y822733D01*
X223183Y822483D01*
X223100Y822150D01*
G01X250499Y740350D02*
Y734850D01*
G01X242499Y740350D02*
X250499D01*
G01X242499Y734850D02*
Y740350D01*
G01X237407Y768217D02*
X237282Y767967D01*
X237199Y767675D01*
Y767342D01*
X237324Y766967D01*
X237532Y766675D01*
X237782Y766467D01*
X238199Y766300D01*
X238574Y766258D01*
X238949Y766342D01*
X239199Y766467D01*
X239449Y766717D01*
X239616Y767008D01*
X239699Y767300D01*
Y767592D01*
X239616Y767883D01*
X239491Y768133D01*
X239324Y768342D01*
G01X237616Y769608D02*
X237366Y769858D01*
X237241Y770150D01*
X237199Y770483D01*
X237282Y770900D01*
X237491Y771192D01*
X237741Y771275D01*
X237991Y771233D01*
X238199Y771067D01*
X238616Y770233D01*
X238907Y769858D01*
X239324Y769608D01*
X239699Y769525D01*
Y771275D01*
G01Y774000D02*
X237199D01*
X238991Y772458D01*
Y774542D01*
G01X237199Y776600D02*
X237282Y776267D01*
X237491Y776017D01*
X237741Y775850D01*
X238074Y775725D01*
X238449Y775683D01*
X238824Y775725D01*
X239157Y775850D01*
X239407Y776017D01*
X239616Y776267D01*
X239699Y776600D01*
X239616Y776933D01*
X239407Y777183D01*
X239157Y777350D01*
X238824Y777475D01*
X238449Y777517D01*
X238074Y777475D01*
X237741Y777350D01*
X237491Y777183D01*
X237282Y776933D01*
X237199Y776600D01*
G01X234699Y746250D02*
Y751750D01*
G01X242699Y746250D02*
X234699D01*
G01X242699Y751750D02*
Y746250D01*
G01Y763850D02*
Y758350D01*
G01X234699Y763850D02*
X242699D01*
G01X234699Y758350D02*
Y763850D01*
G01X228707Y768217D02*
X228582Y767967D01*
X228499Y767675D01*
Y767342D01*
X228624Y766967D01*
X228832Y766675D01*
X229082Y766467D01*
X229499Y766300D01*
X229874Y766258D01*
X230249Y766342D01*
X230499Y766467D01*
X230749Y766717D01*
X230916Y767008D01*
X230999Y767300D01*
Y767592D01*
X230916Y767883D01*
X230791Y768133D01*
X230624Y768342D01*
G01X228916Y769608D02*
X228666Y769858D01*
X228541Y770150D01*
X228499Y770483D01*
X228582Y770900D01*
X228791Y771192D01*
X229041Y771275D01*
X229291Y771233D01*
X229499Y771067D01*
X229916Y770233D01*
X230207Y769858D01*
X230624Y769608D01*
X230999Y769525D01*
Y771275D01*
G01Y774000D02*
X228499D01*
X230291Y772458D01*
Y774542D01*
G01X230999Y776600D02*
X228499D01*
X228999Y776100D01*
G01X230999D02*
Y777100D01*
G01X225999Y746250D02*
Y751750D01*
G01X233999Y746250D02*
X225999D01*
G01X233999Y751750D02*
Y746250D01*
G01Y763850D02*
Y758350D01*
G01X225999Y763850D02*
X233999D01*
G01X225999Y758350D02*
Y763850D01*
G01X220007Y768217D02*
X219882Y767967D01*
X219799Y767675D01*
Y767342D01*
X219924Y766967D01*
X220132Y766675D01*
X220382Y766467D01*
X220799Y766300D01*
X221174Y766258D01*
X221549Y766342D01*
X221799Y766467D01*
X222049Y766717D01*
X222216Y767008D01*
X222299Y767300D01*
Y767592D01*
X222216Y767883D01*
X222091Y768133D01*
X221924Y768342D01*
G01X220216Y769608D02*
X219966Y769858D01*
X219841Y770150D01*
X219799Y770483D01*
X219882Y770900D01*
X220091Y771192D01*
X220341Y771275D01*
X220591Y771233D01*
X220799Y771067D01*
X221216Y770233D01*
X221507Y769858D01*
X221924Y769608D01*
X222299Y769525D01*
Y771275D01*
G01Y774000D02*
X219799D01*
X221591Y772458D01*
Y774542D01*
G01X220216Y775808D02*
X219966Y776058D01*
X219841Y776350D01*
X219799Y776683D01*
X219882Y777100D01*
X220091Y777392D01*
X220341Y777475D01*
X220591Y777433D01*
X220799Y777267D01*
X221216Y776433D01*
X221507Y776058D01*
X221924Y775808D01*
X222299Y775725D01*
Y777475D01*
G01X217299Y746250D02*
Y751750D01*
G01X225299Y746250D02*
X217299D01*
G01X225299Y751750D02*
Y746250D01*
G01Y763850D02*
Y758350D01*
G01X217299Y763850D02*
X225299D01*
G01X217299Y758350D02*
Y763850D01*
G01X221499Y729350D02*
X229499D01*
G01X200400Y816000D02*
X216500D01*
G01X228708Y893767D02*
X228583Y893517D01*
X228500Y893225D01*
Y892892D01*
X228625Y892517D01*
X228833Y892225D01*
X229083Y892017D01*
X229500Y891850D01*
X229875Y891808D01*
X230250Y891892D01*
X230500Y892017D01*
X230750Y892267D01*
X230917Y892558D01*
X231000Y892850D01*
Y893142D01*
X230917Y893433D01*
X230792Y893683D01*
X230625Y893892D01*
G01X228917Y895158D02*
X228667Y895408D01*
X228542Y895700D01*
X228500Y896033D01*
X228583Y896450D01*
X228792Y896742D01*
X229042Y896825D01*
X229292Y896783D01*
X229500Y896617D01*
X229917Y895783D01*
X230208Y895408D01*
X230625Y895158D01*
X231000Y895075D01*
Y896825D01*
G01X230708Y898342D02*
X230917Y898633D01*
X231000Y898967D01*
X230917Y899300D01*
X230667Y899592D01*
X230292Y899800D01*
X229917Y899883D01*
X229458D01*
X229083Y899800D01*
X228750Y899592D01*
X228583Y899342D01*
X228500Y899050D01*
X228583Y898717D01*
X228750Y898467D01*
X229000Y898300D01*
X229333Y898217D01*
X229625Y898300D01*
X229917Y898508D01*
X230083Y898758D01*
X230125Y899050D01*
X230042Y899383D01*
X229833Y899633D01*
X229458Y899883D01*
G01X230500Y901233D02*
X230792Y901483D01*
X230958Y901817D01*
X231000Y902192D01*
X230958Y902525D01*
X230750Y902858D01*
X230500Y903067D01*
X230250Y903108D01*
X229958Y903025D01*
X229750Y902733D01*
X229667Y902442D01*
Y902067D01*
G01Y902442D02*
X229542Y902692D01*
X229333Y902900D01*
X229083Y902983D01*
X228833Y902900D01*
X228625Y902692D01*
X228500Y902317D01*
X228542Y901942D01*
X228708Y901567D01*
G01X178799Y839813D02*
Y828413D01*
G01X192199Y839813D02*
X178799D01*
G01X192199Y828413D02*
Y839813D01*
G01X178799Y828413D02*
X192199D01*
G01X186499Y866613D02*
Y879613D01*
G01X209500Y817300D02*
X213500D01*
Y824700D01*
G01X201500Y817300D02*
X205500D01*
Y824700D01*
G01X187999Y847813D02*
X183999D01*
Y840413D01*
G01X192499Y847813D02*
X188499D01*
Y840413D01*
G01X223000Y892017D02*
X220500D01*
Y893058D01*
X220625Y893392D01*
X220792Y893600D01*
X221125Y893683D01*
X221458Y893600D01*
X221667Y893350D01*
X221792Y893058D01*
Y892017D01*
G01Y893058D02*
X223000Y893683D01*
G01Y896450D02*
X220500D01*
X222292Y894908D01*
Y896992D01*
G01X221958Y898258D02*
X221667Y898550D01*
X221500Y898800D01*
X221417Y899133D01*
X221500Y899425D01*
X221667Y899633D01*
X221917Y899800D01*
X222208Y899842D01*
X222458Y899800D01*
X222708Y899633D01*
X222917Y899383D01*
X223000Y899092D01*
X222917Y898758D01*
X222667Y898467D01*
X222292Y898300D01*
X221875Y898258D01*
X221333Y898342D01*
X221042Y898467D01*
X220750Y898675D01*
X220542Y898967D01*
X220500Y899258D01*
X220583Y899550D01*
X220792Y899758D01*
G01X223000Y902150D02*
X222958Y902442D01*
X222833Y902775D01*
X222625Y902983D01*
X222333Y903067D01*
X222042Y902983D01*
X221792Y902733D01*
X221667Y902358D01*
Y901942D01*
X221583Y901692D01*
X221375Y901483D01*
X221083Y901400D01*
X220792Y901525D01*
X220583Y901817D01*
X220500Y902150D01*
X220583Y902483D01*
X220792Y902775D01*
X221083Y902900D01*
X221375Y902817D01*
X221583Y902608D01*
X221667Y902358D01*
Y901942D01*
X221792Y901567D01*
X222042Y901317D01*
X222333Y901233D01*
X222625Y901317D01*
X222833Y901525D01*
X222958Y901858D01*
X223000Y902150D01*
G01X227000Y892017D02*
X224500D01*
Y893058D01*
X224625Y893392D01*
X224792Y893600D01*
X225125Y893683D01*
X225458Y893600D01*
X225667Y893350D01*
X225792Y893058D01*
Y892017D01*
G01Y893058D02*
X227000Y893683D01*
G01Y896450D02*
X224500D01*
X226292Y894908D01*
Y896992D01*
G01X225958Y898258D02*
X225667Y898550D01*
X225500Y898800D01*
X225417Y899133D01*
X225500Y899425D01*
X225667Y899633D01*
X225917Y899800D01*
X226208Y899842D01*
X226458Y899800D01*
X226708Y899633D01*
X226917Y899383D01*
X227000Y899092D01*
X226917Y898758D01*
X226667Y898467D01*
X226292Y898300D01*
X225875Y898258D01*
X225333Y898342D01*
X225042Y898467D01*
X224750Y898675D01*
X224542Y898967D01*
X224500Y899258D01*
X224583Y899550D01*
X224792Y899758D01*
G01X226708Y901442D02*
X226917Y901733D01*
X227000Y902067D01*
X226917Y902400D01*
X226667Y902692D01*
X226292Y902900D01*
X225917Y902983D01*
X225458D01*
X225083Y902900D01*
X224750Y902692D01*
X224583Y902442D01*
X224500Y902150D01*
X224583Y901817D01*
X224750Y901567D01*
X225000Y901400D01*
X225333Y901317D01*
X225625Y901400D01*
X225917Y901608D01*
X226083Y901858D01*
X226125Y902150D01*
X226042Y902483D01*
X225833Y902733D01*
X225458Y902983D01*
G01X193400Y825000D02*
Y821000D01*
X200800D01*
G01X214500Y882983D02*
X216292D01*
X216667Y883150D01*
X216917Y883483D01*
X217000Y883900D01*
X216917Y884317D01*
X216667Y884650D01*
X216292Y884817D01*
X214500D01*
G01X216500Y886083D02*
X216792Y886333D01*
X216958Y886667D01*
X217000Y887042D01*
X216958Y887375D01*
X216750Y887708D01*
X216500Y887917D01*
X216250Y887958D01*
X215958Y887875D01*
X215750Y887583D01*
X215667Y887292D01*
Y886917D01*
G01Y887292D02*
X215542Y887542D01*
X215333Y887750D01*
X215083Y887833D01*
X214833Y887750D01*
X214625Y887542D01*
X214500Y887167D01*
X214542Y886792D01*
X214708Y886417D01*
G01X217000Y890017D02*
X216458Y890100D01*
X216000Y890225D01*
X215583Y890392D01*
X215125Y890600D01*
X214500Y890933D01*
Y889267D01*
G01X200999Y881850D02*
Y895250D01*
G01X210999Y881850D02*
X200999D01*
G01X210999Y895250D02*
Y881850D01*
G01X225983Y842500D02*
Y840708D01*
X226150Y840333D01*
X226483Y840083D01*
X226900Y840000D01*
X227317Y840083D01*
X227650Y840333D01*
X227817Y840708D01*
Y842500D01*
G01X229083Y840500D02*
X229333Y840208D01*
X229667Y840042D01*
X230042Y840000D01*
X230375Y840042D01*
X230708Y840250D01*
X230917Y840500D01*
X230958Y840750D01*
X230875Y841042D01*
X230583Y841250D01*
X230292Y841333D01*
X229917D01*
G01X230292D02*
X230542Y841458D01*
X230750Y841667D01*
X230833Y841917D01*
X230750Y842167D01*
X230542Y842375D01*
X230167Y842500D01*
X229792Y842458D01*
X229417Y842292D01*
G01X233100Y840000D02*
X233392Y840042D01*
X233725Y840167D01*
X233933Y840375D01*
X234017Y840667D01*
X233933Y840958D01*
X233683Y841208D01*
X233308Y841333D01*
X232892D01*
X232642Y841417D01*
X232433Y841625D01*
X232350Y841917D01*
X232475Y842208D01*
X232767Y842417D01*
X233100Y842500D01*
X233433Y842417D01*
X233725Y842208D01*
X233850Y841917D01*
X233767Y841625D01*
X233558Y841417D01*
X233308Y841333D01*
X232892D01*
X232517Y841208D01*
X232267Y840958D01*
X232183Y840667D01*
X232267Y840375D01*
X232475Y840167D01*
X232808Y840042D01*
X233100Y840000D01*
G01X210499Y846913D02*
X208499Y844913D01*
X206499Y846913D01*
G01X202899D02*
Y827713D01*
X214099D01*
Y846913D01*
X202899D01*
G01X197808Y868567D02*
X197683Y868317D01*
X197600Y868025D01*
Y867692D01*
X197725Y867317D01*
X197933Y867025D01*
X198183Y866817D01*
X198600Y866650D01*
X198975Y866608D01*
X199350Y866692D01*
X199600Y866817D01*
X199850Y867067D01*
X200017Y867358D01*
X200100Y867650D01*
Y867942D01*
X200017Y868233D01*
X199892Y868483D01*
X199725Y868692D01*
G01X199600Y869833D02*
X199892Y870083D01*
X200058Y870417D01*
X200100Y870792D01*
X200058Y871125D01*
X199850Y871458D01*
X199600Y871667D01*
X199350Y871708D01*
X199058Y871625D01*
X198850Y871333D01*
X198767Y871042D01*
Y870667D01*
G01Y871042D02*
X198642Y871292D01*
X198433Y871500D01*
X198183Y871583D01*
X197933Y871500D01*
X197725Y871292D01*
X197600Y870917D01*
X197642Y870542D01*
X197808Y870167D01*
G01X197600Y873850D02*
X197683Y873517D01*
X197892Y873267D01*
X198142Y873100D01*
X198475Y872975D01*
X198850Y872933D01*
X199225Y872975D01*
X199558Y873100D01*
X199808Y873267D01*
X200017Y873517D01*
X200100Y873850D01*
X200017Y874183D01*
X199808Y874433D01*
X199558Y874600D01*
X199225Y874725D01*
X198850Y874767D01*
X198475Y874725D01*
X198142Y874600D01*
X197892Y874433D01*
X197683Y874183D01*
X197600Y873850D01*
G01X198017Y876158D02*
X197767Y876408D01*
X197642Y876700D01*
X197600Y877033D01*
X197683Y877450D01*
X197892Y877742D01*
X198142Y877825D01*
X198392Y877783D01*
X198600Y877617D01*
X199017Y876783D01*
X199308Y876408D01*
X199725Y876158D01*
X200100Y876075D01*
Y877825D01*
G01X187499Y869813D02*
Y875313D01*
G01X195499Y869813D02*
X187499D01*
G01X195499Y875313D02*
Y869813D01*
G01Y887413D02*
Y881913D01*
G01X187499Y887413D02*
X195499D01*
G01X187499Y881913D02*
Y887413D01*
G01X191999Y865913D02*
Y860413D01*
G01X183999Y865913D02*
X191999D01*
G01X183999Y860413D02*
Y865913D01*
G01Y848313D02*
Y853813D01*
G01X191999Y848313D02*
X183999D01*
G01X191999Y853813D02*
Y848313D01*
G01X182999Y865913D02*
Y860413D01*
G01Y853813D02*
Y848313D01*
G01X208499Y969050D02*
Y979050D01*
G01X215499D02*
Y969050D01*
G01Y974050D02*
X208499D01*
G01X218932Y969050D02*
Y979050D01*
X222266D01*
X223599Y978550D01*
X224599Y977883D01*
X225432Y976883D01*
X226099Y975716D01*
X226266Y974050D01*
X226099Y972383D01*
X225432Y971217D01*
X224599Y970216D01*
X223599Y969550D01*
X222266Y969050D01*
X218932D01*
G01X229532D02*
Y979050D01*
X232866D01*
X234199Y978550D01*
X235199Y977883D01*
X236032Y976883D01*
X236699Y975716D01*
X236866Y974050D01*
X236699Y972383D01*
X236032Y971217D01*
X235199Y970216D01*
X234199Y969550D01*
X232866Y969050D01*
X229532D01*
G01X243466D02*
X243799Y971217D01*
X244299Y973050D01*
X244966Y974717D01*
X245799Y976550D01*
X247132Y979050D01*
X240466D01*
G01X249399Y965717D02*
X259399D01*
G01X261666Y979050D02*
Y969050D01*
X268332D01*
G01X278932D02*
X272266D01*
Y979050D01*
X278932D01*
G01X276266Y974217D02*
X272266D01*
G01X282532Y969050D02*
Y979050D01*
X285866D01*
X287199Y978550D01*
X288199Y977883D01*
X289032Y976883D01*
X289699Y975716D01*
X289866Y974050D01*
X289699Y972383D01*
X289032Y971217D01*
X288199Y970216D01*
X287199Y969550D01*
X285866Y969050D01*
X282532D01*
G01X241208Y906267D02*
X241083Y906017D01*
X241000Y905725D01*
Y905392D01*
X241125Y905017D01*
X241333Y904725D01*
X241583Y904517D01*
X242000Y904350D01*
X242375Y904308D01*
X242750Y904392D01*
X243000Y904517D01*
X243250Y904767D01*
X243417Y905058D01*
X243500Y905350D01*
Y905642D01*
X243417Y905933D01*
X243292Y906183D01*
X243125Y906392D01*
G01X243000Y907533D02*
X243292Y907783D01*
X243458Y908117D01*
X243500Y908492D01*
X243458Y908825D01*
X243250Y909158D01*
X243000Y909367D01*
X242750Y909408D01*
X242458Y909325D01*
X242250Y909033D01*
X242167Y908742D01*
Y908367D01*
G01Y908742D02*
X242042Y908992D01*
X241833Y909200D01*
X241583Y909283D01*
X241333Y909200D01*
X241125Y908992D01*
X241000Y908617D01*
X241042Y908242D01*
X241208Y907867D01*
G01X243500Y911467D02*
X242958Y911550D01*
X242500Y911675D01*
X242083Y911842D01*
X241625Y912050D01*
X241000Y912383D01*
Y910717D01*
G01X242458Y913858D02*
X242167Y914150D01*
X242000Y914400D01*
X241917Y914733D01*
X242000Y915025D01*
X242167Y915233D01*
X242417Y915400D01*
X242708Y915442D01*
X242958Y915400D01*
X243208Y915233D01*
X243417Y914983D01*
X243500Y914692D01*
X243417Y914358D01*
X243167Y914067D01*
X242792Y913900D01*
X242375Y913858D01*
X241833Y913942D01*
X241542Y914067D01*
X241250Y914275D01*
X241042Y914567D01*
X241000Y914858D01*
X241083Y915150D01*
X241292Y915358D01*
G01X192900Y940500D02*
X192567Y940542D01*
X192275Y940708D01*
X192025Y940958D01*
X191858Y941250D01*
X191775Y941583D01*
Y941917D01*
X191858Y942250D01*
X192025Y942542D01*
X192275Y942792D01*
X192567Y942958D01*
X192900Y943000D01*
X193233Y942958D01*
X193525Y942792D01*
X193775Y942542D01*
X193942Y942250D01*
X194025Y941917D01*
Y941583D01*
X193942Y941250D01*
X193775Y940958D01*
X193525Y940708D01*
X193233Y940542D01*
X192900Y940500D01*
G01X193233Y941167D02*
X193733Y940500D01*
G01X195917D02*
X196000Y941042D01*
X196125Y941500D01*
X196292Y941917D01*
X196500Y942375D01*
X196833Y943000D01*
X195167D01*
G01X199100D02*
X198767Y942917D01*
X198517Y942708D01*
X198350Y942458D01*
X198225Y942125D01*
X198183Y941750D01*
X198225Y941375D01*
X198350Y941042D01*
X198517Y940792D01*
X198767Y940583D01*
X199100Y940500D01*
X199433Y940583D01*
X199683Y940792D01*
X199850Y941042D01*
X199975Y941375D01*
X200017Y941750D01*
X199975Y942125D01*
X199850Y942458D01*
X199683Y942708D01*
X199433Y942917D01*
X199100Y943000D01*
G01X178200Y934100D02*
X189600D01*
G01X178200Y947500D02*
Y934100D01*
G01X189600Y947500D02*
X178200D01*
G01X189600Y934100D02*
Y947500D01*
G01X238999Y920450D02*
X238957Y920117D01*
X238791Y919825D01*
X238541Y919575D01*
X238249Y919408D01*
X237916Y919325D01*
X237582D01*
X237249Y919408D01*
X236957Y919575D01*
X236707Y919825D01*
X236541Y920117D01*
X236499Y920450D01*
X236541Y920783D01*
X236707Y921075D01*
X236957Y921325D01*
X237249Y921492D01*
X237582Y921575D01*
X237916D01*
X238249Y921492D01*
X238541Y921325D01*
X238791Y921075D01*
X238957Y920783D01*
X238999Y920450D01*
G01X238332Y920783D02*
X238999Y921283D01*
G01X236916Y922758D02*
X236666Y923008D01*
X236541Y923300D01*
X236499Y923633D01*
X236582Y924050D01*
X236791Y924342D01*
X237041Y924425D01*
X237291Y924383D01*
X237499Y924217D01*
X237916Y923383D01*
X238207Y923008D01*
X238624Y922758D01*
X238999Y922675D01*
Y924425D01*
G01X238624Y925733D02*
X238832Y925983D01*
X238957Y926275D01*
X238999Y926650D01*
X238916Y927025D01*
X238749Y927317D01*
X238457Y927525D01*
X238124Y927567D01*
X237791Y927483D01*
X237582Y927275D01*
X237416Y926983D01*
X237374Y926692D01*
X237416Y926400D01*
X237582Y926025D01*
X236499Y926150D01*
Y927275D01*
G01X211799Y924613D02*
X213899Y922813D01*
X211799Y920613D01*
G01X211699Y917013D02*
X230899D01*
Y928213D01*
X211699D01*
Y917013D01*
X212099D01*
G01X186499Y900113D02*
Y913113D01*
G01X190017Y930000D02*
Y932500D01*
X191058D01*
X191392Y932375D01*
X191600Y932208D01*
X191683Y931875D01*
X191600Y931542D01*
X191350Y931333D01*
X191058Y931208D01*
X190017D01*
G01X191058D02*
X191683Y930000D01*
G01X194450D02*
Y932500D01*
X192908Y930708D01*
X194992D01*
G01X197050Y932500D02*
X196717Y932417D01*
X196467Y932208D01*
X196300Y931958D01*
X196175Y931625D01*
X196133Y931250D01*
X196175Y930875D01*
X196300Y930542D01*
X196467Y930292D01*
X196717Y930083D01*
X197050Y930000D01*
X197383Y930083D01*
X197633Y930292D01*
X197800Y930542D01*
X197925Y930875D01*
X197967Y931250D01*
X197925Y931625D01*
X197800Y931958D01*
X197633Y932208D01*
X197383Y932417D01*
X197050Y932500D01*
G01X200150Y930000D02*
Y932500D01*
X199650Y932000D01*
G01Y930000D02*
X200650D01*
G01X178400Y933600D02*
Y929600D01*
X185800D01*
G01X207999Y903713D02*
X203999D01*
Y896313D01*
G01X211999Y903713D02*
X207999D01*
Y896313D01*
G01X187016Y956550D02*
Y959050D01*
X188057D01*
X188391Y958925D01*
X188599Y958758D01*
X188682Y958425D01*
X188599Y958092D01*
X188349Y957883D01*
X188057Y957758D01*
X187016D01*
G01X188057D02*
X188682Y956550D01*
G01X191449D02*
Y959050D01*
X189907Y957258D01*
X191991D01*
G01X193341Y956842D02*
X193632Y956633D01*
X193966Y956550D01*
X194299Y956633D01*
X194591Y956883D01*
X194799Y957258D01*
X194882Y957633D01*
Y958092D01*
X194799Y958467D01*
X194591Y958800D01*
X194341Y958967D01*
X194049Y959050D01*
X193716Y958967D01*
X193466Y958800D01*
X193299Y958550D01*
X193216Y958217D01*
X193299Y957925D01*
X193507Y957633D01*
X193757Y957467D01*
X194049Y957425D01*
X194382Y957508D01*
X194632Y957717D01*
X194882Y958092D01*
G01X197066Y956550D02*
X197149Y957092D01*
X197274Y957550D01*
X197441Y957967D01*
X197649Y958425D01*
X197982Y959050D01*
X196316D01*
G01X189099Y961100D02*
Y965100D01*
X181699D01*
G01X200999Y895250D02*
X210999D01*
G01X200896Y977183D02*
X200854Y976850D01*
X200688Y976558D01*
X200438Y976308D01*
X200146Y976141D01*
X199813Y976058D01*
X199479D01*
X199146Y976141D01*
X198854Y976308D01*
X198604Y976558D01*
X198438Y976850D01*
X198396Y977183D01*
X198438Y977516D01*
X198604Y977808D01*
X198854Y978058D01*
X199146Y978225D01*
X199479Y978308D01*
X199813D01*
X200146Y978225D01*
X200438Y978058D01*
X200688Y977808D01*
X200854Y977516D01*
X200896Y977183D01*
G01X200229Y977516D02*
X200896Y978016D01*
G01Y980783D02*
X198396D01*
X200188Y979241D01*
Y981325D01*
G01X200896Y983383D02*
X198396D01*
X198896Y982883D01*
G01X200896D02*
Y983883D01*
G01X182799Y965600D02*
X196799D01*
G01X182799Y978600D02*
Y965600D01*
G01X196799D02*
Y978600D01*
G01X190400Y915000D02*
Y929000D01*
G01X219500Y1022000D02*
X229500D01*
G01Y1015000D02*
X219500D01*
G01X224500D02*
Y1022000D01*
G01X219500Y1011567D02*
X229500D01*
Y1008233D01*
X229000Y1006900D01*
X228333Y1005900D01*
X227333Y1005067D01*
X226166Y1004400D01*
X224500Y1004233D01*
X222833Y1004400D01*
X221667Y1005067D01*
X220666Y1005900D01*
X220000Y1006900D01*
X219500Y1008233D01*
Y1011567D01*
G01Y1000967D02*
X229500D01*
Y997633D01*
X229000Y996300D01*
X228333Y995300D01*
X227333Y994467D01*
X226166Y993800D01*
X224500Y993633D01*
X222833Y993800D01*
X221667Y994467D01*
X220666Y995300D01*
X220000Y996300D01*
X219500Y997633D01*
Y1000967D01*
G01Y987033D02*
X221667Y986700D01*
X223500Y986200D01*
X225167Y985533D01*
X227000Y984700D01*
X229500Y983367D01*
Y990033D01*
G01X232400Y1061000D02*
X232067Y1061042D01*
X231775Y1061208D01*
X231525Y1061458D01*
X231358Y1061750D01*
X231275Y1062083D01*
Y1062417D01*
X231358Y1062750D01*
X231525Y1063042D01*
X231775Y1063292D01*
X232067Y1063458D01*
X232400Y1063500D01*
X232733Y1063458D01*
X233025Y1063292D01*
X233275Y1063042D01*
X233442Y1062750D01*
X233525Y1062417D01*
Y1062083D01*
X233442Y1061750D01*
X233275Y1061458D01*
X233025Y1061208D01*
X232733Y1061042D01*
X232400Y1061000D01*
G01X232733Y1061667D02*
X233233Y1061000D01*
G01X234708Y1062042D02*
X235000Y1062333D01*
X235250Y1062500D01*
X235583Y1062583D01*
X235875Y1062500D01*
X236083Y1062333D01*
X236250Y1062083D01*
X236292Y1061792D01*
X236250Y1061542D01*
X236083Y1061292D01*
X235833Y1061083D01*
X235542Y1061000D01*
X235208Y1061083D01*
X234917Y1061333D01*
X234750Y1061708D01*
X234708Y1062125D01*
X234792Y1062667D01*
X234917Y1062958D01*
X235125Y1063250D01*
X235417Y1063458D01*
X235708Y1063500D01*
X236000Y1063417D01*
X236208Y1063208D01*
G01X238600Y1063500D02*
X238267Y1063417D01*
X238017Y1063208D01*
X237850Y1062958D01*
X237725Y1062625D01*
X237683Y1062250D01*
X237725Y1061875D01*
X237850Y1061542D01*
X238017Y1061292D01*
X238267Y1061083D01*
X238600Y1061000D01*
X238933Y1061083D01*
X239183Y1061292D01*
X239350Y1061542D01*
X239475Y1061875D01*
X239517Y1062250D01*
X239475Y1062625D01*
X239350Y1062958D01*
X239183Y1063208D01*
X238933Y1063417D01*
X238600Y1063500D01*
G01X196799Y978600D02*
X182799D01*
G01X205267Y1047775D02*
X205475Y1048108D01*
X205600Y1048483D01*
Y1048817D01*
X205475Y1049150D01*
X205267Y1049400D01*
X204975Y1049525D01*
X204683Y1049442D01*
X204433Y1049233D01*
X204267Y1048858D01*
X204183Y1048358D01*
X204017Y1048067D01*
X203725Y1047942D01*
X203433Y1048025D01*
X203225Y1048233D01*
X203100Y1048525D01*
Y1048817D01*
X203183Y1049108D01*
X203392Y1049358D01*
G01X205600Y1050833D02*
X203100D01*
G01Y1052417D02*
X204642Y1050833D01*
G01X205600Y1052667D02*
X203933Y1051542D01*
G01X203100Y1054850D02*
X205600D01*
G01X203100Y1053892D02*
Y1055808D01*
G01X205600Y1057950D02*
X205558Y1058242D01*
X205433Y1058575D01*
X205225Y1058783D01*
X204933Y1058867D01*
X204642Y1058783D01*
X204392Y1058533D01*
X204267Y1058158D01*
Y1057742D01*
X204183Y1057492D01*
X203975Y1057283D01*
X203683Y1057200D01*
X203392Y1057325D01*
X203183Y1057617D01*
X203100Y1057950D01*
X203183Y1058283D01*
X203392Y1058575D01*
X203683Y1058700D01*
X203975Y1058617D01*
X204183Y1058408D01*
X204267Y1058158D01*
Y1057742D01*
X204392Y1057367D01*
X204642Y1057117D01*
X204933Y1057033D01*
X205225Y1057117D01*
X205433Y1057325D01*
X205558Y1057658D01*
X205600Y1057950D01*
G01X208708Y1069267D02*
X208583Y1069017D01*
X208500Y1068725D01*
Y1068392D01*
X208625Y1068017D01*
X208833Y1067725D01*
X209083Y1067517D01*
X209500Y1067350D01*
X209875Y1067308D01*
X210250Y1067392D01*
X210500Y1067517D01*
X210750Y1067767D01*
X210917Y1068058D01*
X211000Y1068350D01*
Y1068642D01*
X210917Y1068933D01*
X210792Y1069183D01*
X210625Y1069392D01*
G01X208917Y1070658D02*
X208667Y1070908D01*
X208542Y1071200D01*
X208500Y1071533D01*
X208583Y1071950D01*
X208792Y1072242D01*
X209042Y1072325D01*
X209292Y1072283D01*
X209500Y1072117D01*
X209917Y1071283D01*
X210208Y1070908D01*
X210625Y1070658D01*
X211000Y1070575D01*
Y1072325D01*
G01X208917Y1073758D02*
X208667Y1074008D01*
X208542Y1074300D01*
X208500Y1074633D01*
X208583Y1075050D01*
X208792Y1075342D01*
X209042Y1075425D01*
X209292Y1075383D01*
X209500Y1075217D01*
X209917Y1074383D01*
X210208Y1074008D01*
X210625Y1073758D01*
X211000Y1073675D01*
Y1075425D01*
G01X208917Y1076858D02*
X208667Y1077108D01*
X208542Y1077400D01*
X208500Y1077733D01*
X208583Y1078150D01*
X208792Y1078442D01*
X209042Y1078525D01*
X209292Y1078483D01*
X209500Y1078317D01*
X209917Y1077483D01*
X210208Y1077108D01*
X210625Y1076858D01*
X211000Y1076775D01*
Y1078525D01*
G01X255708Y1118267D02*
X255583Y1118017D01*
X255500Y1117725D01*
Y1117392D01*
X255625Y1117017D01*
X255833Y1116725D01*
X256083Y1116517D01*
X256500Y1116350D01*
X256875Y1116308D01*
X257250Y1116392D01*
X257500Y1116517D01*
X257750Y1116767D01*
X257917Y1117058D01*
X258000Y1117350D01*
Y1117642D01*
X257917Y1117933D01*
X257792Y1118183D01*
X257625Y1118392D01*
G01X255917Y1119658D02*
X255667Y1119908D01*
X255542Y1120200D01*
X255500Y1120533D01*
X255583Y1120950D01*
X255792Y1121242D01*
X256042Y1121325D01*
X256292Y1121283D01*
X256500Y1121117D01*
X256917Y1120283D01*
X257208Y1119908D01*
X257625Y1119658D01*
X258000Y1119575D01*
Y1121325D01*
G01X255917Y1122758D02*
X255667Y1123008D01*
X255542Y1123300D01*
X255500Y1123633D01*
X255583Y1124050D01*
X255792Y1124342D01*
X256042Y1124425D01*
X256292Y1124383D01*
X256500Y1124217D01*
X256917Y1123383D01*
X257208Y1123008D01*
X257625Y1122758D01*
X258000Y1122675D01*
Y1124425D01*
G01X255500Y1126650D02*
X255583Y1126317D01*
X255792Y1126067D01*
X256042Y1125900D01*
X256375Y1125775D01*
X256750Y1125733D01*
X257125Y1125775D01*
X257458Y1125900D01*
X257708Y1126067D01*
X257917Y1126317D01*
X258000Y1126650D01*
X257917Y1126983D01*
X257708Y1127233D01*
X257458Y1127400D01*
X257125Y1127525D01*
X256750Y1127567D01*
X256375Y1127525D01*
X256042Y1127400D01*
X255792Y1127233D01*
X255583Y1126983D01*
X255500Y1126650D01*
G01X245000Y1065860D02*
Y1077260D01*
G01X231600Y1065860D02*
X245000D01*
G01X231600Y1077260D02*
Y1065860D01*
G01X245000Y1077260D02*
X231600D01*
G01X228999Y1141050D02*
X248199D01*
Y1152250D01*
X228999D01*
Y1141050D01*
X229399D01*
G01X243017Y1103000D02*
Y1105500D01*
X244058D01*
X244392Y1105375D01*
X244600Y1105208D01*
X244683Y1104875D01*
X244600Y1104542D01*
X244350Y1104333D01*
X244058Y1104208D01*
X243017D01*
G01X244058D02*
X244683Y1103000D01*
G01X246158Y1105083D02*
X246408Y1105333D01*
X246700Y1105458D01*
X247033Y1105500D01*
X247450Y1105417D01*
X247742Y1105208D01*
X247825Y1104958D01*
X247783Y1104708D01*
X247617Y1104500D01*
X246783Y1104083D01*
X246408Y1103792D01*
X246158Y1103375D01*
X246075Y1103000D01*
X247825D01*
G01X250050Y1105500D02*
X249717Y1105417D01*
X249467Y1105208D01*
X249300Y1104958D01*
X249175Y1104625D01*
X249133Y1104250D01*
X249175Y1103875D01*
X249300Y1103542D01*
X249467Y1103292D01*
X249717Y1103083D01*
X250050Y1103000D01*
X250383Y1103083D01*
X250633Y1103292D01*
X250800Y1103542D01*
X250925Y1103875D01*
X250967Y1104250D01*
X250925Y1104625D01*
X250800Y1104958D01*
X250633Y1105208D01*
X250383Y1105417D01*
X250050Y1105500D01*
G01X252233Y1103375D02*
X252483Y1103167D01*
X252775Y1103042D01*
X253150Y1103000D01*
X253525Y1103083D01*
X253817Y1103250D01*
X254025Y1103542D01*
X254067Y1103875D01*
X253983Y1104208D01*
X253775Y1104417D01*
X253483Y1104583D01*
X253192Y1104625D01*
X252900Y1104583D01*
X252525Y1104417D01*
X252650Y1105500D01*
X253775D01*
G01X241500Y1096600D02*
Y1109600D01*
G01X215500Y1096600D02*
X241500D01*
G01X215500Y1109600D02*
Y1096600D01*
G01X241500Y1109600D02*
X215500D01*
G01X219000Y1067517D02*
X216500D01*
Y1068558D01*
X216625Y1068892D01*
X216792Y1069100D01*
X217125Y1069183D01*
X217458Y1069100D01*
X217667Y1068850D01*
X217792Y1068558D01*
Y1067517D01*
G01Y1068558D02*
X219000Y1069183D01*
G01X216917Y1070658D02*
X216667Y1070908D01*
X216542Y1071200D01*
X216500Y1071533D01*
X216583Y1071950D01*
X216792Y1072242D01*
X217042Y1072325D01*
X217292Y1072283D01*
X217500Y1072117D01*
X217917Y1071283D01*
X218208Y1070908D01*
X218625Y1070658D01*
X219000Y1070575D01*
Y1072325D01*
G01X216500Y1074550D02*
X216583Y1074217D01*
X216792Y1073967D01*
X217042Y1073800D01*
X217375Y1073675D01*
X217750Y1073633D01*
X218125Y1073675D01*
X218458Y1073800D01*
X218708Y1073967D01*
X218917Y1074217D01*
X219000Y1074550D01*
X218917Y1074883D01*
X218708Y1075133D01*
X218458Y1075300D01*
X218125Y1075425D01*
X217750Y1075467D01*
X217375Y1075425D01*
X217042Y1075300D01*
X216792Y1075133D01*
X216583Y1074883D01*
X216500Y1074550D01*
G01X218500Y1076733D02*
X218792Y1076983D01*
X218958Y1077317D01*
X219000Y1077692D01*
X218958Y1078025D01*
X218750Y1078358D01*
X218500Y1078567D01*
X218250Y1078608D01*
X217958Y1078525D01*
X217750Y1078233D01*
X217667Y1077942D01*
Y1077567D01*
G01Y1077942D02*
X217542Y1078192D01*
X217333Y1078400D01*
X217083Y1078483D01*
X216833Y1078400D01*
X216625Y1078192D01*
X216500Y1077817D01*
X216542Y1077442D01*
X216708Y1077067D01*
G01X228800Y1092000D02*
X224800D01*
Y1084600D01*
G01X215000Y1067517D02*
X212500D01*
Y1068558D01*
X212625Y1068892D01*
X212792Y1069100D01*
X213125Y1069183D01*
X213458Y1069100D01*
X213667Y1068850D01*
X213792Y1068558D01*
Y1067517D01*
G01Y1068558D02*
X215000Y1069183D01*
G01X214500Y1070533D02*
X214792Y1070783D01*
X214958Y1071117D01*
X215000Y1071492D01*
X214958Y1071825D01*
X214750Y1072158D01*
X214500Y1072367D01*
X214250Y1072408D01*
X213958Y1072325D01*
X213750Y1072033D01*
X213667Y1071742D01*
Y1071367D01*
G01Y1071742D02*
X213542Y1071992D01*
X213333Y1072200D01*
X213083Y1072283D01*
X212833Y1072200D01*
X212625Y1071992D01*
X212500Y1071617D01*
X212542Y1071242D01*
X212708Y1070867D01*
G01X215000Y1074550D02*
X214958Y1074842D01*
X214833Y1075175D01*
X214625Y1075383D01*
X214333Y1075467D01*
X214042Y1075383D01*
X213792Y1075133D01*
X213667Y1074758D01*
Y1074342D01*
X213583Y1074092D01*
X213375Y1073883D01*
X213083Y1073800D01*
X212792Y1073925D01*
X212583Y1074217D01*
X212500Y1074550D01*
X212583Y1074883D01*
X212792Y1075175D01*
X213083Y1075300D01*
X213375Y1075217D01*
X213583Y1075008D01*
X213667Y1074758D01*
Y1074342D01*
X213792Y1073967D01*
X214042Y1073717D01*
X214333Y1073633D01*
X214625Y1073717D01*
X214833Y1073925D01*
X214958Y1074258D01*
X215000Y1074550D01*
G01Y1078150D02*
X212500D01*
X214292Y1076608D01*
Y1078692D01*
G01X222550Y1084500D02*
Y1080500D01*
X229950D01*
G01X250000Y1062017D02*
X247500D01*
Y1063058D01*
X247625Y1063392D01*
X247792Y1063600D01*
X248125Y1063683D01*
X248458Y1063600D01*
X248667Y1063350D01*
X248792Y1063058D01*
Y1062017D01*
G01Y1063058D02*
X250000Y1063683D01*
G01X249500Y1065033D02*
X249792Y1065283D01*
X249958Y1065617D01*
X250000Y1065992D01*
X249958Y1066325D01*
X249750Y1066658D01*
X249500Y1066867D01*
X249250Y1066908D01*
X248958Y1066825D01*
X248750Y1066533D01*
X248667Y1066242D01*
Y1065867D01*
G01Y1066242D02*
X248542Y1066492D01*
X248333Y1066700D01*
X248083Y1066783D01*
X247833Y1066700D01*
X247625Y1066492D01*
X247500Y1066117D01*
X247542Y1065742D01*
X247708Y1065367D01*
G01X250000Y1069050D02*
X249958Y1069342D01*
X249833Y1069675D01*
X249625Y1069883D01*
X249333Y1069967D01*
X249042Y1069883D01*
X248792Y1069633D01*
X248667Y1069258D01*
Y1068842D01*
X248583Y1068592D01*
X248375Y1068383D01*
X248083Y1068300D01*
X247792Y1068425D01*
X247583Y1068717D01*
X247500Y1069050D01*
X247583Y1069383D01*
X247792Y1069675D01*
X248083Y1069800D01*
X248375Y1069717D01*
X248583Y1069508D01*
X248667Y1069258D01*
Y1068842D01*
X248792Y1068467D01*
X249042Y1068217D01*
X249333Y1068133D01*
X249625Y1068217D01*
X249833Y1068425D01*
X249958Y1068758D01*
X250000Y1069050D01*
G01X249500Y1071233D02*
X249792Y1071483D01*
X249958Y1071817D01*
X250000Y1072192D01*
X249958Y1072525D01*
X249750Y1072858D01*
X249500Y1073067D01*
X249250Y1073108D01*
X248958Y1073025D01*
X248750Y1072733D01*
X248667Y1072442D01*
Y1072067D01*
G01Y1072442D02*
X248542Y1072692D01*
X248333Y1072900D01*
X248083Y1072983D01*
X247833Y1072900D01*
X247625Y1072692D01*
X247500Y1072317D01*
X247542Y1071942D01*
X247708Y1071567D01*
G01X249500Y1083950D02*
X245500D01*
Y1076550D01*
G01X207000Y1067517D02*
X204500D01*
Y1068558D01*
X204625Y1068892D01*
X204792Y1069100D01*
X205125Y1069183D01*
X205458Y1069100D01*
X205667Y1068850D01*
X205792Y1068558D01*
Y1067517D01*
G01Y1068558D02*
X207000Y1069183D01*
G01X204917Y1070658D02*
X204667Y1070908D01*
X204542Y1071200D01*
X204500Y1071533D01*
X204583Y1071950D01*
X204792Y1072242D01*
X205042Y1072325D01*
X205292Y1072283D01*
X205500Y1072117D01*
X205917Y1071283D01*
X206208Y1070908D01*
X206625Y1070658D01*
X207000Y1070575D01*
Y1072325D01*
G01X204500Y1074550D02*
X204583Y1074217D01*
X204792Y1073967D01*
X205042Y1073800D01*
X205375Y1073675D01*
X205750Y1073633D01*
X206125Y1073675D01*
X206458Y1073800D01*
X206708Y1073967D01*
X206917Y1074217D01*
X207000Y1074550D01*
X206917Y1074883D01*
X206708Y1075133D01*
X206458Y1075300D01*
X206125Y1075425D01*
X205750Y1075467D01*
X205375Y1075425D01*
X205042Y1075300D01*
X204792Y1075133D01*
X204583Y1074883D01*
X204500Y1074550D01*
G01X207000Y1077650D02*
X206958Y1077942D01*
X206833Y1078275D01*
X206625Y1078483D01*
X206333Y1078567D01*
X206042Y1078483D01*
X205792Y1078233D01*
X205667Y1077858D01*
Y1077442D01*
X205583Y1077192D01*
X205375Y1076983D01*
X205083Y1076900D01*
X204792Y1077025D01*
X204583Y1077317D01*
X204500Y1077650D01*
X204583Y1077983D01*
X204792Y1078275D01*
X205083Y1078400D01*
X205375Y1078317D01*
X205583Y1078108D01*
X205667Y1077858D01*
Y1077442D01*
X205792Y1077067D01*
X206042Y1076817D01*
X206333Y1076733D01*
X206625Y1076817D01*
X206833Y1077025D01*
X206958Y1077358D01*
X207000Y1077650D01*
G01X260708Y1118467D02*
X260583Y1118217D01*
X260500Y1117925D01*
Y1117592D01*
X260625Y1117217D01*
X260833Y1116925D01*
X261083Y1116717D01*
X261500Y1116550D01*
X261875Y1116508D01*
X262250Y1116592D01*
X262500Y1116717D01*
X262750Y1116967D01*
X262917Y1117258D01*
X263000Y1117550D01*
Y1117842D01*
X262917Y1118133D01*
X262792Y1118383D01*
X262625Y1118592D01*
G01X260917Y1119858D02*
X260667Y1120108D01*
X260542Y1120400D01*
X260500Y1120733D01*
X260583Y1121150D01*
X260792Y1121442D01*
X261042Y1121525D01*
X261292Y1121483D01*
X261500Y1121317D01*
X261917Y1120483D01*
X262208Y1120108D01*
X262625Y1119858D01*
X263000Y1119775D01*
Y1121525D01*
G01X260917Y1122958D02*
X260667Y1123208D01*
X260542Y1123500D01*
X260500Y1123833D01*
X260583Y1124250D01*
X260792Y1124542D01*
X261042Y1124625D01*
X261292Y1124583D01*
X261500Y1124417D01*
X261917Y1123583D01*
X262208Y1123208D01*
X262625Y1122958D01*
X263000Y1122875D01*
Y1124625D01*
G01Y1126850D02*
X260500D01*
X261000Y1126350D01*
G01X263000D02*
Y1127350D01*
G01X220300Y1115900D02*
Y1121400D01*
G01X228300Y1115900D02*
X220300D01*
G01X228300Y1121400D02*
Y1115900D01*
G01Y1133500D02*
Y1128000D01*
G01X220300Y1133500D02*
X228300D01*
G01X220300Y1128000D02*
Y1133500D01*
G01X249000Y1087400D02*
X248958Y1087067D01*
X248792Y1086775D01*
X248542Y1086525D01*
X248250Y1086358D01*
X247917Y1086275D01*
X247583D01*
X247250Y1086358D01*
X246958Y1086525D01*
X246708Y1086775D01*
X246542Y1087067D01*
X246500Y1087400D01*
X246542Y1087733D01*
X246708Y1088025D01*
X246958Y1088275D01*
X247250Y1088442D01*
X247583Y1088525D01*
X247917D01*
X248250Y1088442D01*
X248542Y1088275D01*
X248792Y1088025D01*
X248958Y1087733D01*
X249000Y1087400D01*
G01X248333Y1087733D02*
X249000Y1088233D01*
G01X247958Y1089708D02*
X247667Y1090000D01*
X247500Y1090250D01*
X247417Y1090583D01*
X247500Y1090875D01*
X247667Y1091083D01*
X247917Y1091250D01*
X248208Y1091292D01*
X248458Y1091250D01*
X248708Y1091083D01*
X248917Y1090833D01*
X249000Y1090542D01*
X248917Y1090208D01*
X248667Y1089917D01*
X248292Y1089750D01*
X247875Y1089708D01*
X247333Y1089792D01*
X247042Y1089917D01*
X246750Y1090125D01*
X246542Y1090417D01*
X246500Y1090708D01*
X246583Y1091000D01*
X246792Y1091208D01*
G01X249000Y1093600D02*
X246500D01*
X247000Y1093100D01*
G01X249000D02*
Y1094100D01*
G01X244750Y1092125D02*
X230750D01*
G01X244750Y1079125D02*
Y1092125D01*
G01X230750Y1079125D02*
X244750D01*
G01X230750Y1092125D02*
Y1079125D01*
G01X255799Y1144550D02*
X255757Y1144217D01*
X255591Y1143925D01*
X255341Y1143675D01*
X255049Y1143508D01*
X254716Y1143425D01*
X254382D01*
X254049Y1143508D01*
X253757Y1143675D01*
X253507Y1143925D01*
X253341Y1144217D01*
X253299Y1144550D01*
X253341Y1144883D01*
X253507Y1145175D01*
X253757Y1145425D01*
X254049Y1145592D01*
X254382Y1145675D01*
X254716D01*
X255049Y1145592D01*
X255341Y1145425D01*
X255591Y1145175D01*
X255757Y1144883D01*
X255799Y1144550D01*
G01X255132Y1144883D02*
X255799Y1145383D01*
G01Y1147650D02*
X253299D01*
X253799Y1147150D01*
G01X255799D02*
Y1148150D01*
G01X255424Y1149833D02*
X255632Y1150083D01*
X255757Y1150375D01*
X255799Y1150750D01*
X255716Y1151125D01*
X255549Y1151417D01*
X255257Y1151625D01*
X254924Y1151667D01*
X254591Y1151583D01*
X254382Y1151375D01*
X254216Y1151083D01*
X254174Y1150792D01*
X254216Y1150500D01*
X254382Y1150125D01*
X253299Y1150250D01*
Y1151375D01*
G01X229099Y1148650D02*
X231199Y1146850D01*
X229099Y1144650D01*
G01X182508Y1271267D02*
X182383Y1271017D01*
X182300Y1270725D01*
Y1270392D01*
X182425Y1270017D01*
X182633Y1269725D01*
X182883Y1269517D01*
X183300Y1269350D01*
X183675Y1269308D01*
X184050Y1269392D01*
X184300Y1269517D01*
X184550Y1269767D01*
X184717Y1270058D01*
X184800Y1270350D01*
Y1270642D01*
X184717Y1270933D01*
X184592Y1271183D01*
X184425Y1271392D01*
G01X184300Y1272533D02*
X184592Y1272783D01*
X184758Y1273117D01*
X184800Y1273492D01*
X184758Y1273825D01*
X184550Y1274158D01*
X184300Y1274367D01*
X184050Y1274408D01*
X183758Y1274325D01*
X183550Y1274033D01*
X183467Y1273742D01*
Y1273367D01*
G01Y1273742D02*
X183342Y1273992D01*
X183133Y1274200D01*
X182883Y1274283D01*
X182633Y1274200D01*
X182425Y1273992D01*
X182300Y1273617D01*
X182342Y1273242D01*
X182508Y1272867D01*
G01X184800Y1276467D02*
X184258Y1276550D01*
X183800Y1276675D01*
X183383Y1276842D01*
X182925Y1277050D01*
X182300Y1277383D01*
Y1275717D01*
G01X184425Y1278733D02*
X184633Y1278983D01*
X184758Y1279275D01*
X184800Y1279650D01*
X184717Y1280025D01*
X184550Y1280317D01*
X184258Y1280525D01*
X183925Y1280567D01*
X183592Y1280483D01*
X183383Y1280275D01*
X183217Y1279983D01*
X183175Y1279692D01*
X183217Y1279400D01*
X183383Y1279025D01*
X182300Y1279150D01*
Y1280275D01*
G01X227999Y1369050D02*
Y1379050D01*
G01X234999D02*
Y1369050D01*
G01Y1374050D02*
X227999D01*
G01X238432Y1369050D02*
Y1379050D01*
X241766D01*
X243099Y1378550D01*
X244099Y1377883D01*
X244932Y1376883D01*
X245599Y1375716D01*
X245766Y1374050D01*
X245599Y1372383D01*
X244932Y1371217D01*
X244099Y1370216D01*
X243099Y1369550D01*
X241766Y1369050D01*
X238432D01*
G01X249032D02*
Y1379050D01*
X252366D01*
X253699Y1378550D01*
X254699Y1377883D01*
X255532Y1376883D01*
X256199Y1375716D01*
X256366Y1374050D01*
X256199Y1372383D01*
X255532Y1371217D01*
X254699Y1370216D01*
X253699Y1369550D01*
X252366Y1369050D01*
X249032D01*
G01X260132Y1373216D02*
X261299Y1374383D01*
X262299Y1375050D01*
X263632Y1375383D01*
X264799Y1375050D01*
X265632Y1374383D01*
X266299Y1373383D01*
X266466Y1372217D01*
X266299Y1371217D01*
X265632Y1370216D01*
X264632Y1369383D01*
X263466Y1369050D01*
X262132Y1369383D01*
X260966Y1370383D01*
X260299Y1371883D01*
X260132Y1373550D01*
X260466Y1375716D01*
X260966Y1376883D01*
X261799Y1378050D01*
X262966Y1378883D01*
X264132Y1379050D01*
X265299Y1378717D01*
X266132Y1377883D01*
G01X268899Y1365717D02*
X278899D01*
G01X281166Y1379050D02*
Y1369050D01*
X287832D01*
G01X298432D02*
X291766D01*
Y1379050D01*
X298432D01*
G01X295766Y1374217D02*
X291766D01*
G01X302032Y1369050D02*
Y1379050D01*
X305366D01*
X306699Y1378550D01*
X307699Y1377883D01*
X308532Y1376883D01*
X309199Y1375716D01*
X309366Y1374050D01*
X309199Y1372383D01*
X308532Y1371217D01*
X307699Y1370216D01*
X306699Y1369550D01*
X305366Y1369050D01*
X302032D01*
G01X189299Y1383050D02*
Y1379050D01*
X196699D01*
G01X186500Y1355897D02*
X184000D01*
Y1356938D01*
X184125Y1357272D01*
X184292Y1357480D01*
X184625Y1357563D01*
X184958Y1357480D01*
X185167Y1357230D01*
X185292Y1356938D01*
Y1355897D01*
G01Y1356938D02*
X186500Y1357563D01*
G01Y1359830D02*
X184000D01*
X184500Y1359330D01*
G01X186500D02*
Y1360330D01*
G01Y1362930D02*
X186458Y1363222D01*
X186333Y1363555D01*
X186125Y1363763D01*
X185833Y1363847D01*
X185542Y1363763D01*
X185292Y1363513D01*
X185167Y1363138D01*
Y1362722D01*
X185083Y1362472D01*
X184875Y1362263D01*
X184583Y1362180D01*
X184292Y1362305D01*
X184083Y1362597D01*
X184000Y1362930D01*
X184083Y1363263D01*
X184292Y1363555D01*
X184583Y1363680D01*
X184875Y1363597D01*
X185083Y1363388D01*
X185167Y1363138D01*
Y1362722D01*
X185292Y1362347D01*
X185542Y1362097D01*
X185833Y1362013D01*
X186125Y1362097D01*
X186333Y1362305D01*
X186458Y1362638D01*
X186500Y1362930D01*
G01X186125Y1365113D02*
X186333Y1365363D01*
X186458Y1365655D01*
X186500Y1366030D01*
X186417Y1366405D01*
X186250Y1366697D01*
X185958Y1366905D01*
X185625Y1366947D01*
X185292Y1366863D01*
X185083Y1366655D01*
X184917Y1366363D01*
X184875Y1366072D01*
X184917Y1365780D01*
X185083Y1365405D01*
X184000Y1365530D01*
Y1366655D01*
G01X182600Y1371100D02*
X186600D01*
Y1378500D01*
G01X187129Y1390630D02*
Y1393130D01*
X188170D01*
X188504Y1393005D01*
X188712Y1392838D01*
X188795Y1392505D01*
X188712Y1392172D01*
X188462Y1391963D01*
X188170Y1391838D01*
X187129D01*
G01X188170D02*
X188795Y1390630D01*
G01X191062D02*
Y1393130D01*
X190562Y1392630D01*
G01Y1390630D02*
X191562D01*
G01X194162D02*
X194454Y1390672D01*
X194787Y1390797D01*
X194995Y1391005D01*
X195079Y1391297D01*
X194995Y1391588D01*
X194745Y1391838D01*
X194370Y1391963D01*
X193954D01*
X193704Y1392047D01*
X193495Y1392255D01*
X193412Y1392547D01*
X193537Y1392838D01*
X193829Y1393047D01*
X194162Y1393130D01*
X194495Y1393047D01*
X194787Y1392838D01*
X194912Y1392547D01*
X194829Y1392255D01*
X194620Y1392047D01*
X194370Y1391963D01*
X193954D01*
X193579Y1391838D01*
X193329Y1391588D01*
X193245Y1391297D01*
X193329Y1391005D01*
X193537Y1390797D01*
X193870Y1390672D01*
X194162Y1390630D01*
G01X196470Y1391672D02*
X196762Y1391963D01*
X197012Y1392130D01*
X197345Y1392213D01*
X197637Y1392130D01*
X197845Y1391963D01*
X198012Y1391713D01*
X198054Y1391422D01*
X198012Y1391172D01*
X197845Y1390922D01*
X197595Y1390713D01*
X197304Y1390630D01*
X196970Y1390713D01*
X196679Y1390963D01*
X196512Y1391338D01*
X196470Y1391755D01*
X196554Y1392297D01*
X196679Y1392588D01*
X196887Y1392880D01*
X197179Y1393088D01*
X197470Y1393130D01*
X197762Y1393047D01*
X197970Y1392838D01*
G01X189299Y1379050D02*
Y1375050D01*
X196699D01*
G01X182400Y1355897D02*
X179900D01*
Y1356938D01*
X180025Y1357272D01*
X180192Y1357480D01*
X180525Y1357563D01*
X180858Y1357480D01*
X181067Y1357230D01*
X181192Y1356938D01*
Y1355897D01*
G01Y1356938D02*
X182400Y1357563D01*
G01Y1359830D02*
X179900D01*
X180400Y1359330D01*
G01X182400D02*
Y1360330D01*
G01Y1362930D02*
X182358Y1363222D01*
X182233Y1363555D01*
X182025Y1363763D01*
X181733Y1363847D01*
X181442Y1363763D01*
X181192Y1363513D01*
X181067Y1363138D01*
Y1362722D01*
X180983Y1362472D01*
X180775Y1362263D01*
X180483Y1362180D01*
X180192Y1362305D01*
X179983Y1362597D01*
X179900Y1362930D01*
X179983Y1363263D01*
X180192Y1363555D01*
X180483Y1363680D01*
X180775Y1363597D01*
X180983Y1363388D01*
X181067Y1363138D01*
Y1362722D01*
X181192Y1362347D01*
X181442Y1362097D01*
X181733Y1362013D01*
X182025Y1362097D01*
X182233Y1362305D01*
X182358Y1362638D01*
X182400Y1362930D01*
G01Y1365947D02*
X181858Y1366030D01*
X181400Y1366155D01*
X180983Y1366322D01*
X180525Y1366530D01*
X179900Y1366863D01*
Y1365197D01*
G01X178500Y1371100D02*
X182500D01*
Y1378500D01*
G01X187129Y1386630D02*
Y1389130D01*
X188170D01*
X188504Y1389005D01*
X188712Y1388838D01*
X188795Y1388505D01*
X188712Y1388172D01*
X188462Y1387963D01*
X188170Y1387838D01*
X187129D01*
G01X188170D02*
X188795Y1386630D01*
G01X191062D02*
Y1389130D01*
X190562Y1388630D01*
G01Y1386630D02*
X191562D01*
G01X194162D02*
X194454Y1386672D01*
X194787Y1386797D01*
X194995Y1387005D01*
X195079Y1387297D01*
X194995Y1387588D01*
X194745Y1387838D01*
X194370Y1387963D01*
X193954D01*
X193704Y1388047D01*
X193495Y1388255D01*
X193412Y1388547D01*
X193537Y1388838D01*
X193829Y1389047D01*
X194162Y1389130D01*
X194495Y1389047D01*
X194787Y1388838D01*
X194912Y1388547D01*
X194829Y1388255D01*
X194620Y1388047D01*
X194370Y1387963D01*
X193954D01*
X193579Y1387838D01*
X193329Y1387588D01*
X193245Y1387297D01*
X193329Y1387005D01*
X193537Y1386797D01*
X193870Y1386672D01*
X194162Y1386630D01*
G01X197262D02*
X197554Y1386672D01*
X197887Y1386797D01*
X198095Y1387005D01*
X198179Y1387297D01*
X198095Y1387588D01*
X197845Y1387838D01*
X197470Y1387963D01*
X197054D01*
X196804Y1388047D01*
X196595Y1388255D01*
X196512Y1388547D01*
X196637Y1388838D01*
X196929Y1389047D01*
X197262Y1389130D01*
X197595Y1389047D01*
X197887Y1388838D01*
X198012Y1388547D01*
X197929Y1388255D01*
X197720Y1388047D01*
X197470Y1387963D01*
X197054D01*
X196679Y1387838D01*
X196429Y1387588D01*
X196345Y1387297D01*
X196429Y1387005D01*
X196637Y1386797D01*
X196970Y1386672D01*
X197262Y1386630D01*
G01X189299Y1375050D02*
Y1371050D01*
X196699D01*
G01X194504Y1361361D02*
Y1363861D01*
X195545D01*
X195879Y1363736D01*
X196087Y1363569D01*
X196170Y1363236D01*
X196087Y1362903D01*
X195837Y1362694D01*
X195545Y1362569D01*
X194504D01*
G01X195545D02*
X196170Y1361361D01*
G01X198937D02*
Y1363861D01*
X197395Y1362069D01*
X199479D01*
G01X200829Y1361653D02*
X201120Y1361444D01*
X201454Y1361361D01*
X201787Y1361444D01*
X202079Y1361694D01*
X202287Y1362069D01*
X202370Y1362444D01*
Y1362903D01*
X202287Y1363278D01*
X202079Y1363611D01*
X201829Y1363778D01*
X201537Y1363861D01*
X201204Y1363778D01*
X200954Y1363611D01*
X200787Y1363361D01*
X200704Y1363028D01*
X200787Y1362736D01*
X200995Y1362444D01*
X201245Y1362278D01*
X201537Y1362236D01*
X201870Y1362319D01*
X202120Y1362528D01*
X202370Y1362903D01*
G01X203845Y1362403D02*
X204137Y1362694D01*
X204387Y1362861D01*
X204720Y1362944D01*
X205012Y1362861D01*
X205220Y1362694D01*
X205387Y1362444D01*
X205429Y1362153D01*
X205387Y1361903D01*
X205220Y1361653D01*
X204970Y1361444D01*
X204679Y1361361D01*
X204345Y1361444D01*
X204054Y1361694D01*
X203887Y1362069D01*
X203845Y1362486D01*
X203929Y1363028D01*
X204054Y1363319D01*
X204262Y1363611D01*
X204554Y1363819D01*
X204845Y1363861D01*
X205137Y1363778D01*
X205345Y1363569D01*
G01X204599Y1365400D02*
Y1369400D01*
X197199D01*
G01X215696Y1368632D02*
X215363Y1368674D01*
X215071Y1368840D01*
X214821Y1369090D01*
X214654Y1369382D01*
X214571Y1369715D01*
Y1370049D01*
X214654Y1370382D01*
X214821Y1370674D01*
X215071Y1370924D01*
X215363Y1371090D01*
X215696Y1371132D01*
X216029Y1371090D01*
X216321Y1370924D01*
X216571Y1370674D01*
X216738Y1370382D01*
X216821Y1370049D01*
Y1369715D01*
X216738Y1369382D01*
X216571Y1369090D01*
X216321Y1368840D01*
X216029Y1368674D01*
X215696Y1368632D01*
G01X216029Y1369299D02*
X216529Y1368632D01*
G01X219296D02*
Y1371132D01*
X217754Y1369340D01*
X219838D01*
G01X221896Y1371132D02*
X221563Y1371049D01*
X221313Y1370840D01*
X221146Y1370590D01*
X221021Y1370257D01*
X220979Y1369882D01*
X221021Y1369507D01*
X221146Y1369174D01*
X221313Y1368924D01*
X221563Y1368715D01*
X221896Y1368632D01*
X222229Y1368715D01*
X222479Y1368924D01*
X222646Y1369174D01*
X222771Y1369507D01*
X222813Y1369882D01*
X222771Y1370257D01*
X222646Y1370590D01*
X222479Y1370840D01*
X222229Y1371049D01*
X221896Y1371132D01*
G01X197299Y1370300D02*
X211299D01*
G01X197299Y1383300D02*
Y1370300D01*
G01X211299Y1383300D02*
X197299D01*
G01X211299Y1370300D02*
Y1383300D01*
G01X208765Y1467950D02*
X218765D01*
G01Y1460950D02*
X208765D01*
G01X213765D02*
Y1467950D01*
G01X208765Y1457517D02*
X218765D01*
Y1454183D01*
X218265Y1452850D01*
X217598Y1451850D01*
X216598Y1451017D01*
X215431Y1450350D01*
X213765Y1450183D01*
X212098Y1450350D01*
X210932Y1451017D01*
X209931Y1451850D01*
X209265Y1452850D01*
X208765Y1454183D01*
Y1457517D01*
G01Y1446917D02*
X218765D01*
Y1443583D01*
X218265Y1442250D01*
X217598Y1441250D01*
X216598Y1440417D01*
X215431Y1439750D01*
X213765Y1439583D01*
X212098Y1439750D01*
X210932Y1440417D01*
X209931Y1441250D01*
X209265Y1442250D01*
X208765Y1443583D01*
Y1446917D01*
G01X212931Y1435817D02*
X214098Y1434650D01*
X214765Y1433650D01*
X215098Y1432317D01*
X214765Y1431150D01*
X214098Y1430317D01*
X213098Y1429650D01*
X211932Y1429483D01*
X210932Y1429650D01*
X209931Y1430317D01*
X209098Y1431317D01*
X208765Y1432483D01*
X209098Y1433817D01*
X210098Y1434983D01*
X211598Y1435650D01*
X213265Y1435817D01*
X215431Y1435483D01*
X216598Y1434983D01*
X217765Y1434150D01*
X218598Y1432983D01*
X218765Y1431817D01*
X218432Y1430650D01*
X217598Y1429817D01*
G01X233900Y1465500D02*
X233567Y1465542D01*
X233275Y1465708D01*
X233025Y1465958D01*
X232858Y1466250D01*
X232775Y1466583D01*
Y1466917D01*
X232858Y1467250D01*
X233025Y1467542D01*
X233275Y1467792D01*
X233567Y1467958D01*
X233900Y1468000D01*
X234233Y1467958D01*
X234525Y1467792D01*
X234775Y1467542D01*
X234942Y1467250D01*
X235025Y1466917D01*
Y1466583D01*
X234942Y1466250D01*
X234775Y1465958D01*
X234525Y1465708D01*
X234233Y1465542D01*
X233900Y1465500D01*
G01X234233Y1466167D02*
X234733Y1465500D01*
G01X236083Y1465875D02*
X236333Y1465667D01*
X236625Y1465542D01*
X237000Y1465500D01*
X237375Y1465583D01*
X237667Y1465750D01*
X237875Y1466042D01*
X237917Y1466375D01*
X237833Y1466708D01*
X237625Y1466917D01*
X237333Y1467083D01*
X237042Y1467125D01*
X236750Y1467083D01*
X236375Y1466917D01*
X236500Y1468000D01*
X237625D01*
G01X240100Y1465500D02*
X240392Y1465542D01*
X240725Y1465667D01*
X240933Y1465875D01*
X241017Y1466167D01*
X240933Y1466458D01*
X240683Y1466708D01*
X240308Y1466833D01*
X239892D01*
X239642Y1466917D01*
X239433Y1467125D01*
X239350Y1467417D01*
X239475Y1467708D01*
X239767Y1467917D01*
X240100Y1468000D01*
X240433Y1467917D01*
X240725Y1467708D01*
X240850Y1467417D01*
X240767Y1467125D01*
X240558Y1466917D01*
X240308Y1466833D01*
X239892D01*
X239517Y1466708D01*
X239267Y1466458D01*
X239183Y1466167D01*
X239267Y1465875D01*
X239475Y1465667D01*
X239808Y1465542D01*
X240100Y1465500D01*
G01X230600Y1481500D02*
Y1470100D01*
G01X244000D02*
Y1481500D01*
G01X230600Y1470100D02*
X244000D01*
G01X187129Y1394630D02*
Y1397130D01*
X188170D01*
X188504Y1397005D01*
X188712Y1396838D01*
X188795Y1396505D01*
X188712Y1396172D01*
X188462Y1395963D01*
X188170Y1395838D01*
X187129D01*
G01X188170D02*
X188795Y1394630D01*
G01X191062D02*
Y1397130D01*
X190562Y1396630D01*
G01Y1394630D02*
X191562D01*
G01X194162D02*
X194454Y1394672D01*
X194787Y1394797D01*
X194995Y1395005D01*
X195079Y1395297D01*
X194995Y1395588D01*
X194745Y1395838D01*
X194370Y1395963D01*
X193954D01*
X193704Y1396047D01*
X193495Y1396255D01*
X193412Y1396547D01*
X193537Y1396838D01*
X193829Y1397047D01*
X194162Y1397130D01*
X194495Y1397047D01*
X194787Y1396838D01*
X194912Y1396547D01*
X194829Y1396255D01*
X194620Y1396047D01*
X194370Y1395963D01*
X193954D01*
X193579Y1395838D01*
X193329Y1395588D01*
X193245Y1395297D01*
X193329Y1395005D01*
X193537Y1394797D01*
X193870Y1394672D01*
X194162Y1394630D01*
G01X197762D02*
Y1397130D01*
X196220Y1395338D01*
X198304D01*
G01X215517Y1473500D02*
Y1476000D01*
X216558D01*
X216892Y1475875D01*
X217100Y1475708D01*
X217183Y1475375D01*
X217100Y1475042D01*
X216850Y1474833D01*
X216558Y1474708D01*
X215517D01*
G01X216558D02*
X217183Y1473500D01*
G01X218533Y1474000D02*
X218783Y1473708D01*
X219117Y1473542D01*
X219492Y1473500D01*
X219825Y1473542D01*
X220158Y1473750D01*
X220367Y1474000D01*
X220408Y1474250D01*
X220325Y1474542D01*
X220033Y1474750D01*
X219742Y1474833D01*
X219367D01*
G01X219742D02*
X219992Y1474958D01*
X220200Y1475167D01*
X220283Y1475417D01*
X220200Y1475667D01*
X219992Y1475875D01*
X219617Y1476000D01*
X219242Y1475958D01*
X218867Y1475792D01*
G01X222467Y1473500D02*
X222550Y1474042D01*
X222675Y1474500D01*
X222842Y1474917D01*
X223050Y1475375D01*
X223383Y1476000D01*
X221717D01*
G01X225567Y1473500D02*
X225650Y1474042D01*
X225775Y1474500D01*
X225942Y1474917D01*
X226150Y1475375D01*
X226483Y1476000D01*
X224817D01*
G01X212707Y1486317D02*
X212582Y1486067D01*
X212499Y1485775D01*
Y1485442D01*
X212624Y1485067D01*
X212832Y1484775D01*
X213082Y1484567D01*
X213499Y1484400D01*
X213874Y1484358D01*
X214249Y1484442D01*
X214499Y1484567D01*
X214749Y1484817D01*
X214916Y1485108D01*
X214999Y1485400D01*
Y1485692D01*
X214916Y1485983D01*
X214791Y1486233D01*
X214624Y1486442D01*
G01X212916Y1487708D02*
X212666Y1487958D01*
X212541Y1488250D01*
X212499Y1488583D01*
X212582Y1489000D01*
X212791Y1489292D01*
X213041Y1489375D01*
X213291Y1489333D01*
X213499Y1489167D01*
X213916Y1488333D01*
X214207Y1487958D01*
X214624Y1487708D01*
X214999Y1487625D01*
Y1489375D01*
G01X212499Y1491600D02*
X212582Y1491267D01*
X212791Y1491017D01*
X213041Y1490850D01*
X213374Y1490725D01*
X213749Y1490683D01*
X214124Y1490725D01*
X214457Y1490850D01*
X214707Y1491017D01*
X214916Y1491267D01*
X214999Y1491600D01*
X214916Y1491933D01*
X214707Y1492183D01*
X214457Y1492350D01*
X214124Y1492475D01*
X213749Y1492517D01*
X213374Y1492475D01*
X213041Y1492350D01*
X212791Y1492183D01*
X212582Y1491933D01*
X212499Y1491600D01*
G01X214999Y1495200D02*
X212499D01*
X214291Y1493658D01*
Y1495742D01*
G01X206707Y1526317D02*
X206582Y1526067D01*
X206499Y1525775D01*
Y1525442D01*
X206624Y1525067D01*
X206832Y1524775D01*
X207082Y1524567D01*
X207499Y1524400D01*
X207874Y1524358D01*
X208249Y1524442D01*
X208499Y1524567D01*
X208749Y1524817D01*
X208916Y1525108D01*
X208999Y1525400D01*
Y1525692D01*
X208916Y1525983D01*
X208791Y1526233D01*
X208624Y1526442D01*
G01X206916Y1527708D02*
X206666Y1527958D01*
X206541Y1528250D01*
X206499Y1528583D01*
X206582Y1529000D01*
X206791Y1529292D01*
X207041Y1529375D01*
X207291Y1529333D01*
X207499Y1529167D01*
X207916Y1528333D01*
X208207Y1527958D01*
X208624Y1527708D01*
X208999Y1527625D01*
Y1529375D01*
G01X206499Y1531600D02*
X206582Y1531267D01*
X206791Y1531017D01*
X207041Y1530850D01*
X207374Y1530725D01*
X207749Y1530683D01*
X208124Y1530725D01*
X208457Y1530850D01*
X208707Y1531017D01*
X208916Y1531267D01*
X208999Y1531600D01*
X208916Y1531933D01*
X208707Y1532183D01*
X208457Y1532350D01*
X208124Y1532475D01*
X207749Y1532517D01*
X207374Y1532475D01*
X207041Y1532350D01*
X206791Y1532183D01*
X206582Y1531933D01*
X206499Y1531600D01*
G01X208624Y1533783D02*
X208832Y1534033D01*
X208957Y1534325D01*
X208999Y1534700D01*
X208916Y1535075D01*
X208749Y1535367D01*
X208457Y1535575D01*
X208124Y1535617D01*
X207791Y1535533D01*
X207582Y1535325D01*
X207416Y1535033D01*
X207374Y1534742D01*
X207416Y1534450D01*
X207582Y1534075D01*
X206499Y1534200D01*
Y1535325D01*
G01X244000Y1481500D02*
X230600D01*
G01X257399Y1531350D02*
Y1512150D01*
X268599D01*
Y1531350D01*
X257399D01*
Y1530950D01*
G01X201517Y1516500D02*
Y1519000D01*
X202558D01*
X202892Y1518875D01*
X203100Y1518708D01*
X203183Y1518375D01*
X203100Y1518042D01*
X202850Y1517833D01*
X202558Y1517708D01*
X201517D01*
G01X202558D02*
X203183Y1516500D01*
G01X205450D02*
Y1519000D01*
X204950Y1518500D01*
G01Y1516500D02*
X205950D01*
G01X207842Y1516792D02*
X208133Y1516583D01*
X208467Y1516500D01*
X208800Y1516583D01*
X209092Y1516833D01*
X209300Y1517208D01*
X209383Y1517583D01*
Y1518042D01*
X209300Y1518417D01*
X209092Y1518750D01*
X208842Y1518917D01*
X208550Y1519000D01*
X208217Y1518917D01*
X207967Y1518750D01*
X207800Y1518500D01*
X207717Y1518167D01*
X207800Y1517875D01*
X208008Y1517583D01*
X208258Y1517417D01*
X208550Y1517375D01*
X208883Y1517458D01*
X209133Y1517667D01*
X209383Y1518042D01*
G01X211650Y1519000D02*
X211317Y1518917D01*
X211067Y1518708D01*
X210900Y1518458D01*
X210775Y1518125D01*
X210733Y1517750D01*
X210775Y1517375D01*
X210900Y1517042D01*
X211067Y1516792D01*
X211317Y1516583D01*
X211650Y1516500D01*
X211983Y1516583D01*
X212233Y1516792D01*
X212400Y1517042D01*
X212525Y1517375D01*
X212567Y1517750D01*
X212525Y1518125D01*
X212400Y1518458D01*
X212233Y1518708D01*
X211983Y1518917D01*
X211650Y1519000D01*
G01X240300Y1506900D02*
Y1519900D01*
G01X214300Y1506900D02*
X240300D01*
G01X214300Y1519900D02*
Y1506900D01*
G01X240300Y1519900D02*
X214300D01*
G01X202051Y1539176D02*
Y1541676D01*
X203092D01*
X203426Y1541551D01*
X203634Y1541384D01*
X203717Y1541051D01*
X203634Y1540718D01*
X203384Y1540509D01*
X203092Y1540384D01*
X202051D01*
G01X203092D02*
X203717Y1539176D01*
G01X205984D02*
Y1541676D01*
X205484Y1541176D01*
G01Y1539176D02*
X206484D01*
G01X208376Y1539468D02*
X208667Y1539259D01*
X209001Y1539176D01*
X209334Y1539259D01*
X209626Y1539509D01*
X209834Y1539884D01*
X209917Y1540259D01*
Y1540718D01*
X209834Y1541093D01*
X209626Y1541426D01*
X209376Y1541593D01*
X209084Y1541676D01*
X208751Y1541593D01*
X208501Y1541426D01*
X208334Y1541176D01*
X208251Y1540843D01*
X208334Y1540551D01*
X208542Y1540259D01*
X208792Y1540093D01*
X209084Y1540051D01*
X209417Y1540134D01*
X209667Y1540343D01*
X209917Y1540718D01*
G01X211267Y1539551D02*
X211517Y1539343D01*
X211809Y1539218D01*
X212184Y1539176D01*
X212559Y1539259D01*
X212851Y1539426D01*
X213059Y1539718D01*
X213101Y1540051D01*
X213017Y1540384D01*
X212809Y1540593D01*
X212517Y1540759D01*
X212226Y1540801D01*
X211934Y1540759D01*
X211559Y1540593D01*
X211684Y1541676D01*
X212809D01*
G01X241499Y1539550D02*
Y1552550D01*
G01X215499Y1539550D02*
X241499D01*
G01X215499Y1552550D02*
Y1539550D01*
G01X241499Y1552550D02*
X215499D01*
G01X228517Y1502500D02*
Y1505000D01*
X229558D01*
X229892Y1504875D01*
X230100Y1504708D01*
X230183Y1504375D01*
X230100Y1504042D01*
X229850Y1503833D01*
X229558Y1503708D01*
X228517D01*
G01X229558D02*
X230183Y1502500D01*
G01X232450D02*
Y1505000D01*
X231950Y1504500D01*
G01Y1502500D02*
X232950D01*
G01X235550D02*
X235842Y1502542D01*
X236175Y1502667D01*
X236383Y1502875D01*
X236467Y1503167D01*
X236383Y1503458D01*
X236133Y1503708D01*
X235758Y1503833D01*
X235342D01*
X235092Y1503917D01*
X234883Y1504125D01*
X234800Y1504417D01*
X234925Y1504708D01*
X235217Y1504917D01*
X235550Y1505000D01*
X235883Y1504917D01*
X236175Y1504708D01*
X236300Y1504417D01*
X236217Y1504125D01*
X236008Y1503917D01*
X235758Y1503833D01*
X235342D01*
X234967Y1503708D01*
X234717Y1503458D01*
X234633Y1503167D01*
X234717Y1502875D01*
X234925Y1502667D01*
X235258Y1502542D01*
X235550Y1502500D01*
G01X237942Y1502792D02*
X238233Y1502583D01*
X238567Y1502500D01*
X238900Y1502583D01*
X239192Y1502833D01*
X239400Y1503208D01*
X239483Y1503583D01*
Y1504042D01*
X239400Y1504417D01*
X239192Y1504750D01*
X238942Y1504917D01*
X238650Y1505000D01*
X238317Y1504917D01*
X238067Y1504750D01*
X237900Y1504500D01*
X237817Y1504167D01*
X237900Y1503875D01*
X238108Y1503583D01*
X238358Y1503417D01*
X238650Y1503375D01*
X238983Y1503458D01*
X239233Y1503667D01*
X239483Y1504042D01*
G01X227499Y1504750D02*
X223499D01*
Y1497350D01*
G01X222800Y1482100D02*
Y1478100D01*
X230200D01*
G01X246517Y1500500D02*
Y1503000D01*
X247558D01*
X247892Y1502875D01*
X248100Y1502708D01*
X248183Y1502375D01*
X248100Y1502042D01*
X247850Y1501833D01*
X247558Y1501708D01*
X246517D01*
G01X247558D02*
X248183Y1500500D01*
G01X249533Y1501000D02*
X249783Y1500708D01*
X250117Y1500542D01*
X250492Y1500500D01*
X250825Y1500542D01*
X251158Y1500750D01*
X251367Y1501000D01*
X251408Y1501250D01*
X251325Y1501542D01*
X251033Y1501750D01*
X250742Y1501833D01*
X250367D01*
G01X250742D02*
X250992Y1501958D01*
X251200Y1502167D01*
X251283Y1502417D01*
X251200Y1502667D01*
X250992Y1502875D01*
X250617Y1503000D01*
X250242Y1502958D01*
X249867Y1502792D01*
G01X253467Y1500500D02*
X253550Y1501042D01*
X253675Y1501500D01*
X253842Y1501917D01*
X254050Y1502375D01*
X254383Y1503000D01*
X252717D01*
G01X256650Y1500500D02*
X256942Y1500542D01*
X257275Y1500667D01*
X257483Y1500875D01*
X257567Y1501167D01*
X257483Y1501458D01*
X257233Y1501708D01*
X256858Y1501833D01*
X256442D01*
X256192Y1501917D01*
X255983Y1502125D01*
X255900Y1502417D01*
X256025Y1502708D01*
X256317Y1502917D01*
X256650Y1503000D01*
X256983Y1502917D01*
X257275Y1502708D01*
X257400Y1502417D01*
X257317Y1502125D01*
X257108Y1501917D01*
X256858Y1501833D01*
X256442D01*
X256067Y1501708D01*
X255817Y1501458D01*
X255733Y1501167D01*
X255817Y1500875D01*
X256025Y1500667D01*
X256358Y1500542D01*
X256650Y1500500D01*
G01X227700Y1501300D02*
Y1497300D01*
X235100D01*
G01X218999Y1483067D02*
X216499D01*
Y1484108D01*
X216624Y1484442D01*
X216791Y1484650D01*
X217124Y1484733D01*
X217457Y1484650D01*
X217666Y1484400D01*
X217791Y1484108D01*
Y1483067D01*
G01Y1484108D02*
X218999Y1484733D01*
G01Y1487000D02*
X216499D01*
X216999Y1486500D01*
G01X218999D02*
Y1487500D01*
G01X218707Y1489392D02*
X218916Y1489683D01*
X218999Y1490017D01*
X218916Y1490350D01*
X218666Y1490642D01*
X218291Y1490850D01*
X217916Y1490933D01*
X217457D01*
X217082Y1490850D01*
X216749Y1490642D01*
X216582Y1490392D01*
X216499Y1490100D01*
X216582Y1489767D01*
X216749Y1489517D01*
X216999Y1489350D01*
X217332Y1489267D01*
X217624Y1489350D01*
X217916Y1489558D01*
X218082Y1489808D01*
X218124Y1490100D01*
X218041Y1490433D01*
X217832Y1490683D01*
X217457Y1490933D01*
G01X218999Y1493200D02*
X216499D01*
X216999Y1492700D01*
G01X218999D02*
Y1493700D01*
G01X250499Y1549850D02*
Y1544350D01*
G01X242499Y1549850D02*
X250499D01*
G01X242499Y1544350D02*
Y1549850D01*
G01Y1532250D02*
Y1537750D01*
G01X250499Y1532250D02*
X242499D01*
G01X250499Y1537750D02*
Y1532250D01*
G01X233700Y1553800D02*
Y1559300D01*
G01X241700Y1553800D02*
X233700D01*
G01X241700Y1559300D02*
Y1553800D01*
G01X225000D02*
Y1559300D01*
G01X233000Y1553800D02*
X225000D01*
G01X233000Y1559300D02*
Y1553800D01*
G01X216300D02*
Y1559300D01*
G01X224300Y1553800D02*
X216300D01*
G01X224300Y1559300D02*
Y1553800D01*
G01X210708Y1526767D02*
X210583Y1526517D01*
X210500Y1526225D01*
Y1525892D01*
X210625Y1525517D01*
X210833Y1525225D01*
X211083Y1525017D01*
X211500Y1524850D01*
X211875Y1524808D01*
X212250Y1524892D01*
X212500Y1525017D01*
X212750Y1525267D01*
X212917Y1525558D01*
X213000Y1525850D01*
Y1526142D01*
X212917Y1526433D01*
X212792Y1526683D01*
X212625Y1526892D01*
G01X210917Y1528158D02*
X210667Y1528408D01*
X210542Y1528700D01*
X210500Y1529033D01*
X210583Y1529450D01*
X210792Y1529742D01*
X211042Y1529825D01*
X211292Y1529783D01*
X211500Y1529617D01*
X211917Y1528783D01*
X212208Y1528408D01*
X212625Y1528158D01*
X213000Y1528075D01*
Y1529825D01*
G01X210500Y1532050D02*
X210583Y1531717D01*
X210792Y1531467D01*
X211042Y1531300D01*
X211375Y1531175D01*
X211750Y1531133D01*
X212125Y1531175D01*
X212458Y1531300D01*
X212708Y1531467D01*
X212917Y1531717D01*
X213000Y1532050D01*
X212917Y1532383D01*
X212708Y1532633D01*
X212458Y1532800D01*
X212125Y1532925D01*
X211750Y1532967D01*
X211375Y1532925D01*
X211042Y1532800D01*
X210792Y1532633D01*
X210583Y1532383D01*
X210500Y1532050D01*
G01X211958Y1534358D02*
X211667Y1534650D01*
X211500Y1534900D01*
X211417Y1535233D01*
X211500Y1535525D01*
X211667Y1535733D01*
X211917Y1535900D01*
X212208Y1535942D01*
X212458Y1535900D01*
X212708Y1535733D01*
X212917Y1535483D01*
X213000Y1535192D01*
X212917Y1534858D01*
X212667Y1534567D01*
X212292Y1534400D01*
X211875Y1534358D01*
X211333Y1534442D01*
X211042Y1534567D01*
X210750Y1534775D01*
X210542Y1535067D01*
X210500Y1535358D01*
X210583Y1535650D01*
X210792Y1535858D01*
G01X220999Y1521250D02*
Y1526750D01*
G01X228999Y1521250D02*
X220999D01*
G01X228999Y1526750D02*
Y1521250D01*
G01Y1538850D02*
Y1533350D01*
G01X220999Y1538850D02*
X228999D01*
G01X220999Y1533350D02*
Y1538850D01*
G01X244000Y1486400D02*
X243958Y1486067D01*
X243792Y1485775D01*
X243542Y1485525D01*
X243250Y1485358D01*
X242917Y1485275D01*
X242583D01*
X242250Y1485358D01*
X241958Y1485525D01*
X241708Y1485775D01*
X241542Y1486067D01*
X241500Y1486400D01*
X241542Y1486733D01*
X241708Y1487025D01*
X241958Y1487275D01*
X242250Y1487442D01*
X242583Y1487525D01*
X242917D01*
X243250Y1487442D01*
X243542Y1487275D01*
X243792Y1487025D01*
X243958Y1486733D01*
X244000Y1486400D01*
G01X243333Y1486733D02*
X244000Y1487233D01*
G01X243625Y1488583D02*
X243833Y1488833D01*
X243958Y1489125D01*
X244000Y1489500D01*
X243917Y1489875D01*
X243750Y1490167D01*
X243458Y1490375D01*
X243125Y1490417D01*
X242792Y1490333D01*
X242583Y1490125D01*
X242417Y1489833D01*
X242375Y1489542D01*
X242417Y1489250D01*
X242583Y1488875D01*
X241500Y1489000D01*
Y1490125D01*
G01X243708Y1491892D02*
X243917Y1492183D01*
X244000Y1492517D01*
X243917Y1492850D01*
X243667Y1493142D01*
X243292Y1493350D01*
X242917Y1493433D01*
X242458D01*
X242083Y1493350D01*
X241750Y1493142D01*
X241583Y1492892D01*
X241500Y1492600D01*
X241583Y1492267D01*
X241750Y1492017D01*
X242000Y1491850D01*
X242333Y1491767D01*
X242625Y1491850D01*
X242917Y1492058D01*
X243083Y1492308D01*
X243125Y1492600D01*
X243042Y1492933D01*
X242833Y1493183D01*
X242458Y1493433D01*
G01X239200Y1482700D02*
Y1496700D01*
G01X226200Y1482700D02*
X239200D01*
G01X226200Y1496700D02*
Y1482700D01*
G01X239200Y1496700D02*
X226200D01*
G01X222008Y1630467D02*
X221883Y1630217D01*
X221800Y1629925D01*
Y1629592D01*
X221925Y1629217D01*
X222133Y1628925D01*
X222383Y1628717D01*
X222800Y1628550D01*
X223175Y1628508D01*
X223550Y1628592D01*
X223800Y1628717D01*
X224050Y1628967D01*
X224217Y1629258D01*
X224300Y1629550D01*
Y1629842D01*
X224217Y1630133D01*
X224092Y1630383D01*
X223925Y1630592D01*
G01X223800Y1631733D02*
X224092Y1631983D01*
X224258Y1632317D01*
X224300Y1632692D01*
X224258Y1633025D01*
X224050Y1633358D01*
X223800Y1633567D01*
X223550Y1633608D01*
X223258Y1633525D01*
X223050Y1633233D01*
X222967Y1632942D01*
Y1632567D01*
G01Y1632942D02*
X222842Y1633192D01*
X222633Y1633400D01*
X222383Y1633483D01*
X222133Y1633400D01*
X221925Y1633192D01*
X221800Y1632817D01*
X221842Y1632442D01*
X222008Y1632067D01*
G01X224300Y1635750D02*
X224258Y1636042D01*
X224133Y1636375D01*
X223925Y1636583D01*
X223633Y1636667D01*
X223342Y1636583D01*
X223092Y1636333D01*
X222967Y1635958D01*
Y1635542D01*
X222883Y1635292D01*
X222675Y1635083D01*
X222383Y1635000D01*
X222092Y1635125D01*
X221883Y1635417D01*
X221800Y1635750D01*
X221883Y1636083D01*
X222092Y1636375D01*
X222383Y1636500D01*
X222675Y1636417D01*
X222883Y1636208D01*
X222967Y1635958D01*
Y1635542D01*
X223092Y1635167D01*
X223342Y1634917D01*
X223633Y1634833D01*
X223925Y1634917D01*
X224133Y1635125D01*
X224258Y1635458D01*
X224300Y1635750D01*
G01X224008Y1638142D02*
X224217Y1638433D01*
X224300Y1638767D01*
X224217Y1639100D01*
X223967Y1639392D01*
X223592Y1639600D01*
X223217Y1639683D01*
X222758D01*
X222383Y1639600D01*
X222050Y1639392D01*
X221883Y1639142D01*
X221800Y1638850D01*
X221883Y1638517D01*
X222050Y1638267D01*
X222300Y1638100D01*
X222633Y1638017D01*
X222925Y1638100D01*
X223217Y1638308D01*
X223383Y1638558D01*
X223425Y1638850D01*
X223342Y1639183D01*
X223133Y1639433D01*
X222758Y1639683D01*
G01X228300Y1628717D02*
X225800D01*
Y1629758D01*
X225925Y1630092D01*
X226092Y1630300D01*
X226425Y1630383D01*
X226758Y1630300D01*
X226967Y1630050D01*
X227092Y1629758D01*
Y1628717D01*
G01Y1629758D02*
X228300Y1630383D01*
G01X227925Y1631733D02*
X228133Y1631983D01*
X228258Y1632275D01*
X228300Y1632650D01*
X228217Y1633025D01*
X228050Y1633317D01*
X227758Y1633525D01*
X227425Y1633567D01*
X227092Y1633483D01*
X226883Y1633275D01*
X226717Y1632983D01*
X226675Y1632692D01*
X226717Y1632400D01*
X226883Y1632025D01*
X225800Y1632150D01*
Y1633275D01*
G01X228300Y1635667D02*
X227758Y1635750D01*
X227300Y1635875D01*
X226883Y1636042D01*
X226425Y1636250D01*
X225800Y1636583D01*
Y1634917D01*
G01X227800Y1637933D02*
X228092Y1638183D01*
X228258Y1638517D01*
X228300Y1638892D01*
X228258Y1639225D01*
X228050Y1639558D01*
X227800Y1639767D01*
X227550Y1639808D01*
X227258Y1639725D01*
X227050Y1639433D01*
X226967Y1639142D01*
Y1638767D01*
G01Y1639142D02*
X226842Y1639392D01*
X226633Y1639600D01*
X226383Y1639683D01*
X226133Y1639600D01*
X225925Y1639392D01*
X225800Y1639017D01*
X225842Y1638642D01*
X226008Y1638267D01*
G01X205000Y1643200D02*
X201000D01*
Y1635800D01*
G01X198066Y1619113D02*
Y1621613D01*
X199107D01*
X199441Y1621488D01*
X199649Y1621321D01*
X199732Y1620988D01*
X199649Y1620655D01*
X199399Y1620446D01*
X199107Y1620321D01*
X198066D01*
G01X199107D02*
X199732Y1619113D01*
G01X201207Y1621196D02*
X201457Y1621446D01*
X201749Y1621571D01*
X202082Y1621613D01*
X202499Y1621530D01*
X202791Y1621321D01*
X202874Y1621071D01*
X202832Y1620821D01*
X202666Y1620613D01*
X201832Y1620196D01*
X201457Y1619905D01*
X201207Y1619488D01*
X201124Y1619113D01*
X202874D01*
G01X205599D02*
Y1621613D01*
X204057Y1619821D01*
X206141D01*
G01X207491Y1619405D02*
X207782Y1619196D01*
X208116Y1619113D01*
X208449Y1619196D01*
X208741Y1619446D01*
X208949Y1619821D01*
X209032Y1620196D01*
Y1620655D01*
X208949Y1621030D01*
X208741Y1621363D01*
X208491Y1621530D01*
X208199Y1621613D01*
X207866Y1621530D01*
X207616Y1621363D01*
X207449Y1621113D01*
X207366Y1620780D01*
X207449Y1620488D01*
X207657Y1620196D01*
X207907Y1620030D01*
X208199Y1619988D01*
X208532Y1620071D01*
X208782Y1620280D01*
X209032Y1620655D01*
G01X193349Y1632613D02*
Y1628613D01*
X200749D01*
G01X236408Y1575267D02*
X236283Y1575017D01*
X236200Y1574725D01*
Y1574392D01*
X236325Y1574017D01*
X236533Y1573725D01*
X236783Y1573517D01*
X237200Y1573350D01*
X237575Y1573308D01*
X237950Y1573392D01*
X238200Y1573517D01*
X238450Y1573767D01*
X238617Y1574058D01*
X238700Y1574350D01*
Y1574642D01*
X238617Y1574933D01*
X238492Y1575183D01*
X238325Y1575392D01*
G01X236617Y1576658D02*
X236367Y1576908D01*
X236242Y1577200D01*
X236200Y1577533D01*
X236283Y1577950D01*
X236492Y1578242D01*
X236742Y1578325D01*
X236992Y1578283D01*
X237200Y1578117D01*
X237617Y1577283D01*
X237908Y1576908D01*
X238325Y1576658D01*
X238700Y1576575D01*
Y1578325D01*
G01X236200Y1580550D02*
X236283Y1580217D01*
X236492Y1579967D01*
X236742Y1579800D01*
X237075Y1579675D01*
X237450Y1579633D01*
X237825Y1579675D01*
X238158Y1579800D01*
X238408Y1579967D01*
X238617Y1580217D01*
X238700Y1580550D01*
X238617Y1580883D01*
X238408Y1581133D01*
X238158Y1581300D01*
X237825Y1581425D01*
X237450Y1581467D01*
X237075Y1581425D01*
X236742Y1581300D01*
X236492Y1581133D01*
X236283Y1580883D01*
X236200Y1580550D01*
G01X238700Y1583650D02*
X238658Y1583942D01*
X238533Y1584275D01*
X238325Y1584483D01*
X238033Y1584567D01*
X237742Y1584483D01*
X237492Y1584233D01*
X237367Y1583858D01*
Y1583442D01*
X237283Y1583192D01*
X237075Y1582983D01*
X236783Y1582900D01*
X236492Y1583025D01*
X236283Y1583317D01*
X236200Y1583650D01*
X236283Y1583983D01*
X236492Y1584275D01*
X236783Y1584400D01*
X237075Y1584317D01*
X237283Y1584108D01*
X237367Y1583858D01*
Y1583442D01*
X237492Y1583067D01*
X237742Y1582817D01*
X238033Y1582733D01*
X238325Y1582817D01*
X238533Y1583025D01*
X238658Y1583358D01*
X238700Y1583650D01*
G01X241700Y1571400D02*
Y1565900D01*
G01X233700Y1571400D02*
X241700D01*
G01X233700Y1565900D02*
Y1571400D01*
G01X227708Y1575267D02*
X227583Y1575017D01*
X227500Y1574725D01*
Y1574392D01*
X227625Y1574017D01*
X227833Y1573725D01*
X228083Y1573517D01*
X228500Y1573350D01*
X228875Y1573308D01*
X229250Y1573392D01*
X229500Y1573517D01*
X229750Y1573767D01*
X229917Y1574058D01*
X230000Y1574350D01*
Y1574642D01*
X229917Y1574933D01*
X229792Y1575183D01*
X229625Y1575392D01*
G01X227917Y1576658D02*
X227667Y1576908D01*
X227542Y1577200D01*
X227500Y1577533D01*
X227583Y1577950D01*
X227792Y1578242D01*
X228042Y1578325D01*
X228292Y1578283D01*
X228500Y1578117D01*
X228917Y1577283D01*
X229208Y1576908D01*
X229625Y1576658D01*
X230000Y1576575D01*
Y1578325D01*
G01X227500Y1580550D02*
X227583Y1580217D01*
X227792Y1579967D01*
X228042Y1579800D01*
X228375Y1579675D01*
X228750Y1579633D01*
X229125Y1579675D01*
X229458Y1579800D01*
X229708Y1579967D01*
X229917Y1580217D01*
X230000Y1580550D01*
X229917Y1580883D01*
X229708Y1581133D01*
X229458Y1581300D01*
X229125Y1581425D01*
X228750Y1581467D01*
X228375Y1581425D01*
X228042Y1581300D01*
X227792Y1581133D01*
X227583Y1580883D01*
X227500Y1580550D01*
G01X229708Y1582942D02*
X229917Y1583233D01*
X230000Y1583567D01*
X229917Y1583900D01*
X229667Y1584192D01*
X229292Y1584400D01*
X228917Y1584483D01*
X228458D01*
X228083Y1584400D01*
X227750Y1584192D01*
X227583Y1583942D01*
X227500Y1583650D01*
X227583Y1583317D01*
X227750Y1583067D01*
X228000Y1582900D01*
X228333Y1582817D01*
X228625Y1582900D01*
X228917Y1583108D01*
X229083Y1583358D01*
X229125Y1583650D01*
X229042Y1583983D01*
X228833Y1584233D01*
X228458Y1584483D01*
G01X233000Y1571400D02*
Y1565900D01*
G01X225000Y1571400D02*
X233000D01*
G01X225000Y1565900D02*
Y1571400D01*
G01X219008Y1575267D02*
X218883Y1575017D01*
X218800Y1574725D01*
Y1574392D01*
X218925Y1574017D01*
X219133Y1573725D01*
X219383Y1573517D01*
X219800Y1573350D01*
X220175Y1573308D01*
X220550Y1573392D01*
X220800Y1573517D01*
X221050Y1573767D01*
X221217Y1574058D01*
X221300Y1574350D01*
Y1574642D01*
X221217Y1574933D01*
X221092Y1575183D01*
X220925Y1575392D01*
G01X219217Y1576658D02*
X218967Y1576908D01*
X218842Y1577200D01*
X218800Y1577533D01*
X218883Y1577950D01*
X219092Y1578242D01*
X219342Y1578325D01*
X219592Y1578283D01*
X219800Y1578117D01*
X220217Y1577283D01*
X220508Y1576908D01*
X220925Y1576658D01*
X221300Y1576575D01*
Y1578325D01*
G01Y1580550D02*
X218800D01*
X219300Y1580050D01*
G01X221300D02*
Y1581050D01*
G01X218800Y1583650D02*
X218883Y1583317D01*
X219092Y1583067D01*
X219342Y1582900D01*
X219675Y1582775D01*
X220050Y1582733D01*
X220425Y1582775D01*
X220758Y1582900D01*
X221008Y1583067D01*
X221217Y1583317D01*
X221300Y1583650D01*
X221217Y1583983D01*
X221008Y1584233D01*
X220758Y1584400D01*
X220425Y1584525D01*
X220050Y1584567D01*
X219675Y1584525D01*
X219342Y1584400D01*
X219092Y1584233D01*
X218883Y1583983D01*
X218800Y1583650D01*
G01X224300Y1571400D02*
Y1565900D01*
G01X216300Y1571400D02*
X224300D01*
G01X216300Y1565900D02*
Y1571400D01*
G01X202483Y1662200D02*
Y1664700D01*
X203317D01*
X203650Y1664575D01*
X203900Y1664408D01*
X204108Y1664158D01*
X204275Y1663867D01*
X204317Y1663450D01*
X204275Y1663033D01*
X204108Y1662742D01*
X203900Y1662492D01*
X203650Y1662325D01*
X203317Y1662200D01*
X202483D01*
G01X205708Y1664283D02*
X205958Y1664533D01*
X206250Y1664658D01*
X206583Y1664700D01*
X207000Y1664617D01*
X207292Y1664408D01*
X207375Y1664158D01*
X207333Y1663908D01*
X207167Y1663700D01*
X206333Y1663283D01*
X205958Y1662992D01*
X205708Y1662575D01*
X205625Y1662200D01*
X207375D01*
G01X208683Y1662575D02*
X208933Y1662367D01*
X209225Y1662242D01*
X209600Y1662200D01*
X209975Y1662283D01*
X210267Y1662450D01*
X210475Y1662742D01*
X210517Y1663075D01*
X210433Y1663408D01*
X210225Y1663617D01*
X209933Y1663783D01*
X209642Y1663825D01*
X209350Y1663783D01*
X208975Y1663617D01*
X209100Y1664700D01*
X210225D01*
G01X214000Y1652000D02*
X197900D01*
G01X214000Y1659000D02*
Y1652000D01*
G01X197900Y1659000D02*
X214000D01*
G01X197900Y1652000D02*
Y1659000D01*
G01X183208Y1700267D02*
X183083Y1700017D01*
X183000Y1699725D01*
Y1699392D01*
X183125Y1699017D01*
X183333Y1698725D01*
X183583Y1698517D01*
X184000Y1698350D01*
X184375Y1698308D01*
X184750Y1698392D01*
X185000Y1698517D01*
X185250Y1698767D01*
X185417Y1699058D01*
X185500Y1699350D01*
Y1699642D01*
X185417Y1699933D01*
X185292Y1700183D01*
X185125Y1700392D01*
G01X185000Y1701533D02*
X185292Y1701783D01*
X185458Y1702117D01*
X185500Y1702492D01*
X185458Y1702825D01*
X185250Y1703158D01*
X185000Y1703367D01*
X184750Y1703408D01*
X184458Y1703325D01*
X184250Y1703033D01*
X184167Y1702742D01*
Y1702367D01*
G01Y1702742D02*
X184042Y1702992D01*
X183833Y1703200D01*
X183583Y1703283D01*
X183333Y1703200D01*
X183125Y1702992D01*
X183000Y1702617D01*
X183042Y1702242D01*
X183208Y1701867D01*
G01X185500Y1705467D02*
X184958Y1705550D01*
X184500Y1705675D01*
X184083Y1705842D01*
X183625Y1706050D01*
X183000Y1706383D01*
Y1704717D01*
G01X185500Y1709150D02*
X183000D01*
X184792Y1707608D01*
Y1709692D01*
G01X187000Y1658850D02*
X186958Y1658517D01*
X186792Y1658225D01*
X186542Y1657975D01*
X186250Y1657808D01*
X185917Y1657725D01*
X185583D01*
X185250Y1657808D01*
X184958Y1657975D01*
X184708Y1658225D01*
X184542Y1658517D01*
X184500Y1658850D01*
X184542Y1659183D01*
X184708Y1659475D01*
X184958Y1659725D01*
X185250Y1659892D01*
X185583Y1659975D01*
X185917D01*
X186250Y1659892D01*
X186542Y1659725D01*
X186792Y1659475D01*
X186958Y1659183D01*
X187000Y1658850D01*
G01X186333Y1659183D02*
X187000Y1659683D01*
G01X184917Y1661158D02*
X184667Y1661408D01*
X184542Y1661700D01*
X184500Y1662033D01*
X184583Y1662450D01*
X184792Y1662742D01*
X185042Y1662825D01*
X185292Y1662783D01*
X185500Y1662617D01*
X185917Y1661783D01*
X186208Y1661408D01*
X186625Y1661158D01*
X187000Y1661075D01*
Y1662825D01*
G01X184917Y1664258D02*
X184667Y1664508D01*
X184542Y1664800D01*
X184500Y1665133D01*
X184583Y1665550D01*
X184792Y1665842D01*
X185042Y1665925D01*
X185292Y1665883D01*
X185500Y1665717D01*
X185917Y1664883D01*
X186208Y1664508D01*
X186625Y1664258D01*
X187000Y1664175D01*
Y1665925D01*
G01X190399Y1644727D02*
Y1656127D01*
G01X185000Y1678400D02*
X184958Y1678067D01*
X184792Y1677775D01*
X184542Y1677525D01*
X184250Y1677358D01*
X183917Y1677275D01*
X183583D01*
X183250Y1677358D01*
X182958Y1677525D01*
X182708Y1677775D01*
X182542Y1678067D01*
X182500Y1678400D01*
X182542Y1678733D01*
X182708Y1679025D01*
X182958Y1679275D01*
X183250Y1679442D01*
X183583Y1679525D01*
X183917D01*
X184250Y1679442D01*
X184542Y1679275D01*
X184792Y1679025D01*
X184958Y1678733D01*
X185000Y1678400D01*
G01X184333Y1678733D02*
X185000Y1679233D01*
G01X183958Y1680708D02*
X183667Y1681000D01*
X183500Y1681250D01*
X183417Y1681583D01*
X183500Y1681875D01*
X183667Y1682083D01*
X183917Y1682250D01*
X184208Y1682292D01*
X184458Y1682250D01*
X184708Y1682083D01*
X184917Y1681833D01*
X185000Y1681542D01*
X184917Y1681208D01*
X184667Y1680917D01*
X184292Y1680750D01*
X183875Y1680708D01*
X183333Y1680792D01*
X183042Y1680917D01*
X182750Y1681125D01*
X182542Y1681417D01*
X182500Y1681708D01*
X182583Y1682000D01*
X182792Y1682208D01*
G01X183958Y1683808D02*
X183667Y1684100D01*
X183500Y1684350D01*
X183417Y1684683D01*
X183500Y1684975D01*
X183667Y1685183D01*
X183917Y1685350D01*
X184208Y1685392D01*
X184458Y1685350D01*
X184708Y1685183D01*
X184917Y1684933D01*
X185000Y1684642D01*
X184917Y1684308D01*
X184667Y1684017D01*
X184292Y1683850D01*
X183875Y1683808D01*
X183333Y1683892D01*
X183042Y1684017D01*
X182750Y1684225D01*
X182542Y1684517D01*
X182500Y1684808D01*
X182583Y1685100D01*
X182792Y1685308D01*
G01X180500Y1675400D02*
Y1688800D01*
G01X220517Y1645900D02*
Y1648400D01*
X221558D01*
X221892Y1648275D01*
X222100Y1648108D01*
X222183Y1647775D01*
X222100Y1647442D01*
X221850Y1647233D01*
X221558Y1647108D01*
X220517D01*
G01X221558D02*
X222183Y1645900D01*
G01X223533Y1646275D02*
X223783Y1646067D01*
X224075Y1645942D01*
X224450Y1645900D01*
X224825Y1645983D01*
X225117Y1646150D01*
X225325Y1646442D01*
X225367Y1646775D01*
X225283Y1647108D01*
X225075Y1647317D01*
X224783Y1647483D01*
X224492Y1647525D01*
X224200Y1647483D01*
X223825Y1647317D01*
X223950Y1648400D01*
X225075D01*
G01X226633Y1646275D02*
X226883Y1646067D01*
X227175Y1645942D01*
X227550Y1645900D01*
X227925Y1645983D01*
X228217Y1646150D01*
X228425Y1646442D01*
X228467Y1646775D01*
X228383Y1647108D01*
X228175Y1647317D01*
X227883Y1647483D01*
X227592Y1647525D01*
X227300Y1647483D01*
X226925Y1647317D01*
X227050Y1648400D01*
X228175D01*
G01X230650Y1645900D02*
X230942Y1645942D01*
X231275Y1646067D01*
X231483Y1646275D01*
X231567Y1646567D01*
X231483Y1646858D01*
X231233Y1647108D01*
X230858Y1647233D01*
X230442D01*
X230192Y1647317D01*
X229983Y1647525D01*
X229900Y1647817D01*
X230025Y1648108D01*
X230317Y1648317D01*
X230650Y1648400D01*
X230983Y1648317D01*
X231275Y1648108D01*
X231400Y1647817D01*
X231317Y1647525D01*
X231108Y1647317D01*
X230858Y1647233D01*
X230442D01*
X230067Y1647108D01*
X229817Y1646858D01*
X229733Y1646567D01*
X229817Y1646275D01*
X230025Y1646067D01*
X230358Y1645942D01*
X230650Y1645900D01*
G01X201300Y1651500D02*
Y1647500D01*
X208700D01*
G01X220117Y1641800D02*
Y1644300D01*
X221158D01*
X221492Y1644175D01*
X221700Y1644008D01*
X221783Y1643675D01*
X221700Y1643342D01*
X221450Y1643133D01*
X221158Y1643008D01*
X220117D01*
G01X221158D02*
X221783Y1641800D01*
G01X223258Y1643883D02*
X223508Y1644133D01*
X223800Y1644258D01*
X224133Y1644300D01*
X224550Y1644217D01*
X224842Y1644008D01*
X224925Y1643758D01*
X224883Y1643508D01*
X224717Y1643300D01*
X223883Y1642883D01*
X223508Y1642592D01*
X223258Y1642175D01*
X223175Y1641800D01*
X224925D01*
G01X227650D02*
Y1644300D01*
X226108Y1642508D01*
X228192D01*
G01X230250Y1641800D02*
X230542Y1641842D01*
X230875Y1641967D01*
X231083Y1642175D01*
X231167Y1642467D01*
X231083Y1642758D01*
X230833Y1643008D01*
X230458Y1643133D01*
X230042D01*
X229792Y1643217D01*
X229583Y1643425D01*
X229500Y1643717D01*
X229625Y1644008D01*
X229917Y1644217D01*
X230250Y1644300D01*
X230583Y1644217D01*
X230875Y1644008D01*
X231000Y1643717D01*
X230917Y1643425D01*
X230708Y1643217D01*
X230458Y1643133D01*
X230042D01*
X229667Y1643008D01*
X229417Y1642758D01*
X229333Y1642467D01*
X229417Y1642175D01*
X229625Y1641967D01*
X229958Y1641842D01*
X230250Y1641800D01*
G01X196800Y1647500D02*
Y1643500D01*
X204200D01*
G01X183000Y1658017D02*
X180500D01*
Y1659058D01*
X180625Y1659392D01*
X180792Y1659600D01*
X181125Y1659683D01*
X181458Y1659600D01*
X181667Y1659350D01*
X181792Y1659058D01*
Y1658017D01*
G01Y1659058D02*
X183000Y1659683D01*
G01X180917Y1661158D02*
X180667Y1661408D01*
X180542Y1661700D01*
X180500Y1662033D01*
X180583Y1662450D01*
X180792Y1662742D01*
X181042Y1662825D01*
X181292Y1662783D01*
X181500Y1662617D01*
X181917Y1661783D01*
X182208Y1661408D01*
X182625Y1661158D01*
X183000Y1661075D01*
Y1662825D01*
G01X182625Y1664133D02*
X182833Y1664383D01*
X182958Y1664675D01*
X183000Y1665050D01*
X182917Y1665425D01*
X182750Y1665717D01*
X182458Y1665925D01*
X182125Y1665967D01*
X181792Y1665883D01*
X181583Y1665675D01*
X181417Y1665383D01*
X181375Y1665092D01*
X181417Y1664800D01*
X181583Y1664425D01*
X180500Y1664550D01*
Y1665675D01*
G01X180917Y1667358D02*
X180667Y1667608D01*
X180542Y1667900D01*
X180500Y1668233D01*
X180583Y1668650D01*
X180792Y1668942D01*
X181042Y1669025D01*
X181292Y1668983D01*
X181500Y1668817D01*
X181917Y1667983D01*
X182208Y1667608D01*
X182625Y1667358D01*
X183000Y1667275D01*
Y1669025D01*
G01X187517Y1690500D02*
Y1693000D01*
X188558D01*
X188892Y1692875D01*
X189100Y1692708D01*
X189183Y1692375D01*
X189100Y1692042D01*
X188850Y1691833D01*
X188558Y1691708D01*
X187517D01*
G01X188558D02*
X189183Y1690500D01*
G01X190533Y1691000D02*
X190783Y1690708D01*
X191117Y1690542D01*
X191492Y1690500D01*
X191825Y1690542D01*
X192158Y1690750D01*
X192367Y1691000D01*
X192408Y1691250D01*
X192325Y1691542D01*
X192033Y1691750D01*
X191742Y1691833D01*
X191367D01*
G01X191742D02*
X191992Y1691958D01*
X192200Y1692167D01*
X192283Y1692417D01*
X192200Y1692667D01*
X191992Y1692875D01*
X191617Y1693000D01*
X191242Y1692958D01*
X190867Y1692792D01*
G01X193842Y1690792D02*
X194133Y1690583D01*
X194467Y1690500D01*
X194800Y1690583D01*
X195092Y1690833D01*
X195300Y1691208D01*
X195383Y1691583D01*
Y1692042D01*
X195300Y1692417D01*
X195092Y1692750D01*
X194842Y1692917D01*
X194550Y1693000D01*
X194217Y1692917D01*
X193967Y1692750D01*
X193800Y1692500D01*
X193717Y1692167D01*
X193800Y1691875D01*
X194008Y1691583D01*
X194258Y1691417D01*
X194550Y1691375D01*
X194883Y1691458D01*
X195133Y1691667D01*
X195383Y1692042D01*
G01X197567Y1690500D02*
X197650Y1691042D01*
X197775Y1691500D01*
X197942Y1691917D01*
X198150Y1692375D01*
X198483Y1693000D01*
X196817D01*
G01X191000Y1658017D02*
X188500D01*
Y1659058D01*
X188625Y1659392D01*
X188792Y1659600D01*
X189125Y1659683D01*
X189458Y1659600D01*
X189667Y1659350D01*
X189792Y1659058D01*
Y1658017D01*
G01Y1659058D02*
X191000Y1659683D01*
G01Y1662450D02*
X188500D01*
X190292Y1660908D01*
Y1662992D01*
G01X191000Y1665050D02*
X188500D01*
X189000Y1664550D01*
G01X191000D02*
Y1665550D01*
G01Y1668150D02*
X190958Y1668442D01*
X190833Y1668775D01*
X190625Y1668983D01*
X190333Y1669067D01*
X190042Y1668983D01*
X189792Y1668733D01*
X189667Y1668358D01*
Y1667942D01*
X189583Y1667692D01*
X189375Y1667483D01*
X189083Y1667400D01*
X188792Y1667525D01*
X188583Y1667817D01*
X188500Y1668150D01*
X188583Y1668483D01*
X188792Y1668775D01*
X189083Y1668900D01*
X189375Y1668817D01*
X189583Y1668608D01*
X189667Y1668358D01*
Y1667942D01*
X189792Y1667567D01*
X190042Y1667317D01*
X190333Y1667233D01*
X190625Y1667317D01*
X190833Y1667525D01*
X190958Y1667858D01*
X191000Y1668150D01*
G01X190800Y1649100D02*
X194800D01*
Y1656500D01*
G01X211999Y1777550D02*
Y1787550D01*
G01X218999D02*
Y1777550D01*
G01Y1782550D02*
X211999D01*
G01X222432Y1777550D02*
Y1787550D01*
X225766D01*
X227099Y1787050D01*
X228099Y1786383D01*
X228932Y1785383D01*
X229599Y1784216D01*
X229766Y1782550D01*
X229599Y1780883D01*
X228932Y1779717D01*
X228099Y1778716D01*
X227099Y1778050D01*
X225766Y1777550D01*
X222432D01*
G01X233032D02*
Y1787550D01*
X236366D01*
X237699Y1787050D01*
X238699Y1786383D01*
X239532Y1785383D01*
X240199Y1784216D01*
X240366Y1782550D01*
X240199Y1780883D01*
X239532Y1779717D01*
X238699Y1778716D01*
X237699Y1778050D01*
X236366Y1777550D01*
X233032D01*
G01X243632Y1779050D02*
X244632Y1778217D01*
X245799Y1777717D01*
X247299Y1777550D01*
X248799Y1777883D01*
X249966Y1778550D01*
X250799Y1779717D01*
X250966Y1781050D01*
X250632Y1782383D01*
X249799Y1783217D01*
X248632Y1783883D01*
X247466Y1784050D01*
X246299Y1783883D01*
X244799Y1783217D01*
X245299Y1787550D01*
X249799D01*
G01X252899Y1774217D02*
X262899D01*
G01X265166Y1787550D02*
Y1777550D01*
X271832D01*
G01X282432D02*
X275766D01*
Y1787550D01*
X282432D01*
G01X279766Y1782717D02*
X275766D01*
G01X286032Y1777550D02*
Y1787550D01*
X289366D01*
X290699Y1787050D01*
X291699Y1786383D01*
X292532Y1785383D01*
X293199Y1784216D01*
X293366Y1782550D01*
X293199Y1780883D01*
X292532Y1779717D01*
X291699Y1778716D01*
X290699Y1778050D01*
X289366Y1777550D01*
X286032D01*
G01X179581Y1801113D02*
Y1803613D01*
X180622D01*
X180956Y1803488D01*
X181164Y1803321D01*
X181247Y1802988D01*
X181164Y1802655D01*
X180914Y1802446D01*
X180622Y1802321D01*
X179581D01*
G01X180622D02*
X181247Y1801113D01*
G01X183514D02*
Y1803613D01*
X183014Y1803113D01*
G01Y1801113D02*
X184014D01*
G01X186531D02*
X186614Y1801655D01*
X186739Y1802113D01*
X186906Y1802530D01*
X187114Y1802988D01*
X187447Y1803613D01*
X185781D01*
G01X189714D02*
X189381Y1803530D01*
X189131Y1803321D01*
X188964Y1803071D01*
X188839Y1802738D01*
X188797Y1802363D01*
X188839Y1801988D01*
X188964Y1801655D01*
X189131Y1801405D01*
X189381Y1801196D01*
X189714Y1801113D01*
X190047Y1801196D01*
X190297Y1801405D01*
X190464Y1801655D01*
X190589Y1801988D01*
X190631Y1802363D01*
X190589Y1802738D01*
X190464Y1803071D01*
X190297Y1803321D01*
X190047Y1803530D01*
X189714Y1803613D01*
G01X179581Y1797113D02*
Y1799613D01*
X180622D01*
X180956Y1799488D01*
X181164Y1799321D01*
X181247Y1798988D01*
X181164Y1798655D01*
X180914Y1798446D01*
X180622Y1798321D01*
X179581D01*
G01X180622D02*
X181247Y1797113D01*
G01X183514D02*
Y1799613D01*
X183014Y1799113D01*
G01Y1797113D02*
X184014D01*
G01X186531D02*
X186614Y1797655D01*
X186739Y1798113D01*
X186906Y1798530D01*
X187114Y1798988D01*
X187447Y1799613D01*
X185781D01*
G01X188922Y1799196D02*
X189172Y1799446D01*
X189464Y1799571D01*
X189797Y1799613D01*
X190214Y1799530D01*
X190506Y1799321D01*
X190589Y1799071D01*
X190547Y1798821D01*
X190381Y1798613D01*
X189547Y1798196D01*
X189172Y1797905D01*
X188922Y1797488D01*
X188839Y1797113D01*
X190589D01*
G01X179581Y1793113D02*
Y1795613D01*
X180622D01*
X180956Y1795488D01*
X181164Y1795321D01*
X181247Y1794988D01*
X181164Y1794655D01*
X180914Y1794446D01*
X180622Y1794321D01*
X179581D01*
G01X180622D02*
X181247Y1793113D01*
G01X183514D02*
Y1795613D01*
X183014Y1795113D01*
G01Y1793113D02*
X184014D01*
G01X186531D02*
X186614Y1793655D01*
X186739Y1794113D01*
X186906Y1794530D01*
X187114Y1794988D01*
X187447Y1795613D01*
X185781D01*
G01X190214Y1793113D02*
Y1795613D01*
X188672Y1793821D01*
X190756D01*
G01X178516Y1766050D02*
Y1768550D01*
X179557D01*
X179891Y1768425D01*
X180099Y1768258D01*
X180182Y1767925D01*
X180099Y1767592D01*
X179849Y1767383D01*
X179557Y1767258D01*
X178516D01*
G01X179557D02*
X180182Y1766050D01*
G01X182949D02*
Y1768550D01*
X181407Y1766758D01*
X183491D01*
G01X184841Y1766342D02*
X185132Y1766133D01*
X185466Y1766050D01*
X185799Y1766133D01*
X186091Y1766383D01*
X186299Y1766758D01*
X186382Y1767133D01*
Y1767592D01*
X186299Y1767967D01*
X186091Y1768300D01*
X185841Y1768467D01*
X185549Y1768550D01*
X185216Y1768467D01*
X184966Y1768300D01*
X184799Y1768050D01*
X184716Y1767717D01*
X184799Y1767425D01*
X185007Y1767133D01*
X185257Y1766967D01*
X185549Y1766925D01*
X185882Y1767008D01*
X186132Y1767217D01*
X186382Y1767592D01*
G01X187732Y1766550D02*
X187982Y1766258D01*
X188316Y1766092D01*
X188691Y1766050D01*
X189024Y1766092D01*
X189357Y1766300D01*
X189566Y1766550D01*
X189607Y1766800D01*
X189524Y1767092D01*
X189232Y1767300D01*
X188941Y1767383D01*
X188566D01*
G01X188941D02*
X189191Y1767508D01*
X189399Y1767717D01*
X189482Y1767967D01*
X189399Y1768217D01*
X189191Y1768425D01*
X188816Y1768550D01*
X188441Y1768508D01*
X188066Y1768342D01*
G01X188099Y1771200D02*
Y1775200D01*
X180699D01*
G01X199899Y1771550D02*
X199566Y1771592D01*
X199274Y1771758D01*
X199024Y1772008D01*
X198857Y1772300D01*
X198774Y1772633D01*
Y1772967D01*
X198857Y1773300D01*
X199024Y1773592D01*
X199274Y1773842D01*
X199566Y1774008D01*
X199899Y1774050D01*
X200232Y1774008D01*
X200524Y1773842D01*
X200774Y1773592D01*
X200941Y1773300D01*
X201024Y1772967D01*
Y1772633D01*
X200941Y1772300D01*
X200774Y1772008D01*
X200524Y1771758D01*
X200232Y1771592D01*
X199899Y1771550D01*
G01X200232Y1772217D02*
X200732Y1771550D01*
G01X202082Y1772050D02*
X202332Y1771758D01*
X202666Y1771592D01*
X203041Y1771550D01*
X203374Y1771592D01*
X203707Y1771800D01*
X203916Y1772050D01*
X203957Y1772300D01*
X203874Y1772592D01*
X203582Y1772800D01*
X203291Y1772883D01*
X202916D01*
G01X203291D02*
X203541Y1773008D01*
X203749Y1773217D01*
X203832Y1773467D01*
X203749Y1773717D01*
X203541Y1773925D01*
X203166Y1774050D01*
X202791Y1774008D01*
X202416Y1773842D01*
G01X205391Y1771842D02*
X205682Y1771633D01*
X206016Y1771550D01*
X206349Y1771633D01*
X206641Y1771883D01*
X206849Y1772258D01*
X206932Y1772633D01*
Y1773092D01*
X206849Y1773467D01*
X206641Y1773800D01*
X206391Y1773967D01*
X206099Y1774050D01*
X205766Y1773967D01*
X205516Y1773800D01*
X205349Y1773550D01*
X205266Y1773217D01*
X205349Y1772925D01*
X205557Y1772633D01*
X205807Y1772467D01*
X206099Y1772425D01*
X206432Y1772508D01*
X206682Y1772717D01*
X206932Y1773092D01*
G01X183299Y1776000D02*
X197299D01*
G01X183299Y1789000D02*
Y1776000D01*
G01X197299Y1789000D02*
X183299D01*
G01X197299Y1776000D02*
Y1789000D01*
G01X211831Y1867850D02*
X221831D01*
G01Y1860850D02*
X211831D01*
G01X216831D02*
Y1867850D01*
G01X211831Y1857417D02*
X221831D01*
Y1854083D01*
X221331Y1852750D01*
X220664Y1851750D01*
X219664Y1850917D01*
X218497Y1850250D01*
X216831Y1850083D01*
X215164Y1850250D01*
X213998Y1850917D01*
X212997Y1851750D01*
X212331Y1852750D01*
X211831Y1854083D01*
Y1857417D01*
G01Y1846817D02*
X221831D01*
Y1843483D01*
X221331Y1842150D01*
X220664Y1841150D01*
X219664Y1840317D01*
X218497Y1839650D01*
X216831Y1839483D01*
X215164Y1839650D01*
X213998Y1840317D01*
X212997Y1841150D01*
X212331Y1842150D01*
X211831Y1843483D01*
Y1846817D01*
G01X213331Y1836217D02*
X212498Y1835217D01*
X211998Y1834050D01*
X211831Y1832550D01*
X212164Y1831050D01*
X212831Y1829883D01*
X213998Y1829050D01*
X215331Y1828883D01*
X216664Y1829217D01*
X217498Y1830050D01*
X218164Y1831217D01*
X218331Y1832383D01*
X218164Y1833550D01*
X217498Y1835050D01*
X221831Y1834550D01*
Y1830050D01*
G01X209208Y1889767D02*
X209083Y1889517D01*
X209000Y1889225D01*
Y1888892D01*
X209125Y1888517D01*
X209333Y1888225D01*
X209583Y1888017D01*
X210000Y1887850D01*
X210375Y1887808D01*
X210750Y1887892D01*
X211000Y1888017D01*
X211250Y1888267D01*
X211417Y1888558D01*
X211500Y1888850D01*
Y1889142D01*
X211417Y1889433D01*
X211292Y1889683D01*
X211125Y1889892D01*
G01X211500Y1891950D02*
X209000D01*
X209500Y1891450D01*
G01X211500D02*
Y1892450D01*
G01X211208Y1894342D02*
X211417Y1894633D01*
X211500Y1894967D01*
X211417Y1895300D01*
X211167Y1895592D01*
X210792Y1895800D01*
X210417Y1895883D01*
X209958D01*
X209583Y1895800D01*
X209250Y1895592D01*
X209083Y1895342D01*
X209000Y1895050D01*
X209083Y1894717D01*
X209250Y1894467D01*
X209500Y1894300D01*
X209833Y1894217D01*
X210125Y1894300D01*
X210417Y1894508D01*
X210583Y1894758D01*
X210625Y1895050D01*
X210542Y1895383D01*
X210333Y1895633D01*
X209958Y1895883D01*
G01X209000Y1898150D02*
X209083Y1897817D01*
X209292Y1897567D01*
X209542Y1897400D01*
X209875Y1897275D01*
X210250Y1897233D01*
X210625Y1897275D01*
X210958Y1897400D01*
X211208Y1897567D01*
X211417Y1897817D01*
X211500Y1898150D01*
X211417Y1898483D01*
X211208Y1898733D01*
X210958Y1898900D01*
X210625Y1899025D01*
X210250Y1899067D01*
X209875Y1899025D01*
X209542Y1898900D01*
X209292Y1898733D01*
X209083Y1898483D01*
X209000Y1898150D01*
G01X230000Y1864900D02*
X229958Y1864567D01*
X229792Y1864275D01*
X229542Y1864025D01*
X229250Y1863858D01*
X228917Y1863775D01*
X228583D01*
X228250Y1863858D01*
X227958Y1864025D01*
X227708Y1864275D01*
X227542Y1864567D01*
X227500Y1864900D01*
X227542Y1865233D01*
X227708Y1865525D01*
X227958Y1865775D01*
X228250Y1865942D01*
X228583Y1866025D01*
X228917D01*
X229250Y1865942D01*
X229542Y1865775D01*
X229792Y1865525D01*
X229958Y1865233D01*
X230000Y1864900D01*
G01X229333Y1865233D02*
X230000Y1865733D01*
G01X229625Y1867083D02*
X229833Y1867333D01*
X229958Y1867625D01*
X230000Y1868000D01*
X229917Y1868375D01*
X229750Y1868667D01*
X229458Y1868875D01*
X229125Y1868917D01*
X228792Y1868833D01*
X228583Y1868625D01*
X228417Y1868333D01*
X228375Y1868042D01*
X228417Y1867750D01*
X228583Y1867375D01*
X227500Y1867500D01*
Y1868625D01*
G01X228958Y1870308D02*
X228667Y1870600D01*
X228500Y1870850D01*
X228417Y1871183D01*
X228500Y1871475D01*
X228667Y1871683D01*
X228917Y1871850D01*
X229208Y1871892D01*
X229458Y1871850D01*
X229708Y1871683D01*
X229917Y1871433D01*
X230000Y1871142D01*
X229917Y1870808D01*
X229667Y1870517D01*
X229292Y1870350D01*
X228875Y1870308D01*
X228333Y1870392D01*
X228042Y1870517D01*
X227750Y1870725D01*
X227542Y1871017D01*
X227500Y1871308D01*
X227583Y1871600D01*
X227792Y1871808D01*
G01X215100Y1886100D02*
Y1874700D01*
G01X228500Y1886100D02*
X215100D01*
G01X228500Y1874700D02*
Y1886100D01*
G01X215100Y1874700D02*
X228500D01*
G01X203500Y1888017D02*
X201000D01*
Y1889058D01*
X201125Y1889392D01*
X201292Y1889600D01*
X201625Y1889683D01*
X201958Y1889600D01*
X202167Y1889350D01*
X202292Y1889058D01*
Y1888017D01*
G01Y1889058D02*
X203500Y1889683D01*
G01Y1891950D02*
X201000D01*
X201500Y1891450D01*
G01X203500D02*
Y1892450D01*
G01Y1894967D02*
X202958Y1895050D01*
X202500Y1895175D01*
X202083Y1895342D01*
X201625Y1895550D01*
X201000Y1895883D01*
Y1894217D01*
G01X202458Y1897358D02*
X202167Y1897650D01*
X202000Y1897900D01*
X201917Y1898233D01*
X202000Y1898525D01*
X202167Y1898733D01*
X202417Y1898900D01*
X202708Y1898942D01*
X202958Y1898900D01*
X203208Y1898733D01*
X203417Y1898483D01*
X203500Y1898192D01*
X203417Y1897858D01*
X203167Y1897567D01*
X202792Y1897400D01*
X202375Y1897358D01*
X201833Y1897442D01*
X201542Y1897567D01*
X201250Y1897775D01*
X201042Y1898067D01*
X201000Y1898358D01*
X201083Y1898650D01*
X201292Y1898858D01*
G01X234000Y1864067D02*
X231500D01*
Y1865108D01*
X231625Y1865442D01*
X231792Y1865650D01*
X232125Y1865733D01*
X232458Y1865650D01*
X232667Y1865400D01*
X232792Y1865108D01*
Y1864067D01*
G01Y1865108D02*
X234000Y1865733D01*
G01X233500Y1867083D02*
X233792Y1867333D01*
X233958Y1867667D01*
X234000Y1868042D01*
X233958Y1868375D01*
X233750Y1868708D01*
X233500Y1868917D01*
X233250Y1868958D01*
X232958Y1868875D01*
X232750Y1868583D01*
X232667Y1868292D01*
Y1867917D01*
G01Y1868292D02*
X232542Y1868542D01*
X232333Y1868750D01*
X232083Y1868833D01*
X231833Y1868750D01*
X231625Y1868542D01*
X231500Y1868167D01*
X231542Y1867792D01*
X231708Y1867417D01*
G01X234000Y1871017D02*
X233458Y1871100D01*
X233000Y1871225D01*
X232583Y1871392D01*
X232125Y1871600D01*
X231500Y1871933D01*
Y1870267D01*
G01X233625Y1873283D02*
X233833Y1873533D01*
X233958Y1873825D01*
X234000Y1874200D01*
X233917Y1874575D01*
X233750Y1874867D01*
X233458Y1875075D01*
X233125Y1875117D01*
X232792Y1875033D01*
X232583Y1874825D01*
X232417Y1874533D01*
X232375Y1874242D01*
X232417Y1873950D01*
X232583Y1873575D01*
X231500Y1873700D01*
Y1874825D01*
G01X233000Y1885900D02*
X229000D01*
Y1878500D01*
G01X215500Y1888017D02*
X213000D01*
Y1889058D01*
X213125Y1889392D01*
X213292Y1889600D01*
X213625Y1889683D01*
X213958Y1889600D01*
X214167Y1889350D01*
X214292Y1889058D01*
Y1888017D01*
G01Y1889058D02*
X215500Y1889683D01*
G01X215000Y1891033D02*
X215292Y1891283D01*
X215458Y1891617D01*
X215500Y1891992D01*
X215458Y1892325D01*
X215250Y1892658D01*
X215000Y1892867D01*
X214750Y1892908D01*
X214458Y1892825D01*
X214250Y1892533D01*
X214167Y1892242D01*
Y1891867D01*
G01Y1892242D02*
X214042Y1892492D01*
X213833Y1892700D01*
X213583Y1892783D01*
X213333Y1892700D01*
X213125Y1892492D01*
X213000Y1892117D01*
X213042Y1891742D01*
X213208Y1891367D01*
G01X215500Y1894967D02*
X214958Y1895050D01*
X214500Y1895175D01*
X214083Y1895342D01*
X213625Y1895550D01*
X213000Y1895883D01*
Y1894217D01*
G01X214458Y1897358D02*
X214167Y1897650D01*
X214000Y1897900D01*
X213917Y1898233D01*
X214000Y1898525D01*
X214167Y1898733D01*
X214417Y1898900D01*
X214708Y1898942D01*
X214958Y1898900D01*
X215208Y1898733D01*
X215417Y1898483D01*
X215500Y1898192D01*
X215417Y1897858D01*
X215167Y1897567D01*
X214792Y1897400D01*
X214375Y1897358D01*
X213833Y1897442D01*
X213542Y1897567D01*
X213250Y1897775D01*
X213042Y1898067D01*
X213000Y1898358D01*
X213083Y1898650D01*
X213292Y1898858D01*
G01X207500Y1888017D02*
X205000D01*
Y1889058D01*
X205125Y1889392D01*
X205292Y1889600D01*
X205625Y1889683D01*
X205958Y1889600D01*
X206167Y1889350D01*
X206292Y1889058D01*
Y1888017D01*
G01Y1889058D02*
X207500Y1889683D01*
G01Y1891950D02*
X205000D01*
X205500Y1891450D01*
G01X207500D02*
Y1892450D01*
G01Y1894967D02*
X206958Y1895050D01*
X206500Y1895175D01*
X206083Y1895342D01*
X205625Y1895550D01*
X205000Y1895883D01*
Y1894217D01*
G01X207500Y1898067D02*
X206958Y1898150D01*
X206500Y1898275D01*
X206083Y1898442D01*
X205625Y1898650D01*
X205000Y1898983D01*
Y1897317D01*
G01X238900Y1869500D02*
X238567Y1869542D01*
X238275Y1869708D01*
X238025Y1869958D01*
X237858Y1870250D01*
X237775Y1870583D01*
Y1870917D01*
X237858Y1871250D01*
X238025Y1871542D01*
X238275Y1871792D01*
X238567Y1871958D01*
X238900Y1872000D01*
X239233Y1871958D01*
X239525Y1871792D01*
X239775Y1871542D01*
X239942Y1871250D01*
X240025Y1870917D01*
Y1870583D01*
X239942Y1870250D01*
X239775Y1869958D01*
X239525Y1869708D01*
X239233Y1869542D01*
X238900Y1869500D01*
G01X239233Y1870167D02*
X239733Y1869500D01*
G01X241083Y1869875D02*
X241333Y1869667D01*
X241625Y1869542D01*
X242000Y1869500D01*
X242375Y1869583D01*
X242667Y1869750D01*
X242875Y1870042D01*
X242917Y1870375D01*
X242833Y1870708D01*
X242625Y1870917D01*
X242333Y1871083D01*
X242042Y1871125D01*
X241750Y1871083D01*
X241375Y1870917D01*
X241500Y1872000D01*
X242625D01*
G01X245017Y1869500D02*
X245100Y1870042D01*
X245225Y1870500D01*
X245392Y1870917D01*
X245600Y1871375D01*
X245933Y1872000D01*
X244267D01*
G01X246600Y1877200D02*
Y1891200D01*
G01X233600Y1877200D02*
X246600D01*
G01X233600Y1891200D02*
Y1877200D01*
G01X203367Y1832875D02*
X203575Y1833208D01*
X203700Y1833583D01*
Y1833917D01*
X203575Y1834250D01*
X203367Y1834500D01*
X203075Y1834625D01*
X202783Y1834542D01*
X202533Y1834333D01*
X202367Y1833958D01*
X202283Y1833458D01*
X202117Y1833167D01*
X201825Y1833042D01*
X201533Y1833125D01*
X201325Y1833333D01*
X201200Y1833625D01*
Y1833917D01*
X201283Y1834208D01*
X201492Y1834458D01*
G01X203700Y1835933D02*
X201200D01*
G01Y1837517D02*
X202742Y1835933D01*
G01X203700Y1837767D02*
X202033Y1836642D01*
G01X201200Y1839950D02*
X203700D01*
G01X201200Y1838992D02*
Y1840908D01*
G01X202658Y1842258D02*
X202367Y1842550D01*
X202200Y1842800D01*
X202117Y1843133D01*
X202200Y1843425D01*
X202367Y1843633D01*
X202617Y1843800D01*
X202908Y1843842D01*
X203158Y1843800D01*
X203408Y1843633D01*
X203617Y1843383D01*
X203700Y1843092D01*
X203617Y1842758D01*
X203367Y1842467D01*
X202992Y1842300D01*
X202575Y1842258D01*
X202033Y1842342D01*
X201742Y1842467D01*
X201450Y1842675D01*
X201242Y1842967D01*
X201200Y1843258D01*
X201283Y1843550D01*
X201492Y1843758D01*
G01X261367Y1910892D02*
X261117Y1911017D01*
X260825Y1911100D01*
X260492D01*
X260117Y1910975D01*
X259825Y1910767D01*
X259617Y1910517D01*
X259450Y1910100D01*
X259408Y1909725D01*
X259492Y1909350D01*
X259617Y1909100D01*
X259867Y1908850D01*
X260158Y1908683D01*
X260450Y1908600D01*
X260742D01*
X261033Y1908683D01*
X261283Y1908808D01*
X261492Y1908975D01*
G01X262633Y1909100D02*
X262883Y1908808D01*
X263217Y1908642D01*
X263592Y1908600D01*
X263925Y1908642D01*
X264258Y1908850D01*
X264467Y1909100D01*
X264508Y1909350D01*
X264425Y1909642D01*
X264133Y1909850D01*
X263842Y1909933D01*
X263467D01*
G01X263842D02*
X264092Y1910058D01*
X264300Y1910267D01*
X264383Y1910517D01*
X264300Y1910767D01*
X264092Y1910975D01*
X263717Y1911100D01*
X263342Y1911058D01*
X262967Y1910892D01*
G01X265858Y1909642D02*
X266150Y1909933D01*
X266400Y1910100D01*
X266733Y1910183D01*
X267025Y1910100D01*
X267233Y1909933D01*
X267400Y1909683D01*
X267442Y1909392D01*
X267400Y1909142D01*
X267233Y1908892D01*
X266983Y1908683D01*
X266692Y1908600D01*
X266358Y1908683D01*
X266067Y1908933D01*
X265900Y1909308D01*
X265858Y1909725D01*
X265942Y1910267D01*
X266067Y1910558D01*
X266275Y1910850D01*
X266567Y1911058D01*
X266858Y1911100D01*
X267150Y1911017D01*
X267358Y1910808D01*
G01X269042Y1908892D02*
X269333Y1908683D01*
X269667Y1908600D01*
X270000Y1908683D01*
X270292Y1908933D01*
X270500Y1909308D01*
X270583Y1909683D01*
Y1910142D01*
X270500Y1910517D01*
X270292Y1910850D01*
X270042Y1911017D01*
X269750Y1911100D01*
X269417Y1911017D01*
X269167Y1910850D01*
X269000Y1910600D01*
X268917Y1910267D01*
X269000Y1909975D01*
X269208Y1909683D01*
X269458Y1909517D01*
X269750Y1909475D01*
X270083Y1909558D01*
X270333Y1909767D01*
X270583Y1910142D01*
G01X202707Y1921817D02*
X202582Y1921567D01*
X202499Y1921275D01*
Y1920942D01*
X202624Y1920567D01*
X202832Y1920275D01*
X203082Y1920067D01*
X203499Y1919900D01*
X203874Y1919858D01*
X204249Y1919942D01*
X204499Y1920067D01*
X204749Y1920317D01*
X204916Y1920608D01*
X204999Y1920900D01*
Y1921192D01*
X204916Y1921483D01*
X204791Y1921733D01*
X204624Y1921942D01*
G01X204999Y1924000D02*
X202499D01*
X202999Y1923500D01*
G01X204999D02*
Y1924500D01*
G01Y1927100D02*
X204957Y1927392D01*
X204832Y1927725D01*
X204624Y1927933D01*
X204332Y1928017D01*
X204041Y1927933D01*
X203791Y1927683D01*
X203666Y1927308D01*
Y1926892D01*
X203582Y1926642D01*
X203374Y1926433D01*
X203082Y1926350D01*
X202791Y1926475D01*
X202582Y1926767D01*
X202499Y1927100D01*
X202582Y1927433D01*
X202791Y1927725D01*
X203082Y1927850D01*
X203374Y1927767D01*
X203582Y1927558D01*
X203666Y1927308D01*
Y1926892D01*
X203791Y1926517D01*
X204041Y1926267D01*
X204332Y1926183D01*
X204624Y1926267D01*
X204832Y1926475D01*
X204957Y1926808D01*
X204999Y1927100D01*
G01Y1930200D02*
X204957Y1930492D01*
X204832Y1930825D01*
X204624Y1931033D01*
X204332Y1931117D01*
X204041Y1931033D01*
X203791Y1930783D01*
X203666Y1930408D01*
Y1929992D01*
X203582Y1929742D01*
X203374Y1929533D01*
X203082Y1929450D01*
X202791Y1929575D01*
X202582Y1929867D01*
X202499Y1930200D01*
X202582Y1930533D01*
X202791Y1930825D01*
X203082Y1930950D01*
X203374Y1930867D01*
X203582Y1930658D01*
X203666Y1930408D01*
Y1929992D01*
X203791Y1929617D01*
X204041Y1929367D01*
X204332Y1929283D01*
X204624Y1929367D01*
X204832Y1929575D01*
X204957Y1929908D01*
X204999Y1930200D01*
G01X212493Y1968304D02*
X212368Y1968054D01*
X212285Y1967762D01*
Y1967429D01*
X212410Y1967054D01*
X212618Y1966762D01*
X212868Y1966554D01*
X213285Y1966387D01*
X213660Y1966345D01*
X214035Y1966429D01*
X214285Y1966554D01*
X214535Y1966804D01*
X214702Y1967095D01*
X214785Y1967387D01*
Y1967679D01*
X214702Y1967970D01*
X214577Y1968220D01*
X214410Y1968429D01*
G01X214785Y1970487D02*
X212285D01*
X212785Y1969987D01*
G01X214785D02*
Y1970987D01*
G01X214493Y1972879D02*
X214702Y1973170D01*
X214785Y1973504D01*
X214702Y1973837D01*
X214452Y1974129D01*
X214077Y1974337D01*
X213702Y1974420D01*
X213243D01*
X212868Y1974337D01*
X212535Y1974129D01*
X212368Y1973879D01*
X212285Y1973587D01*
X212368Y1973254D01*
X212535Y1973004D01*
X212785Y1972837D01*
X213118Y1972754D01*
X213410Y1972837D01*
X213702Y1973045D01*
X213868Y1973295D01*
X213910Y1973587D01*
X213827Y1973920D01*
X213618Y1974170D01*
X213243Y1974420D01*
G01X214410Y1975770D02*
X214618Y1976020D01*
X214743Y1976312D01*
X214785Y1976687D01*
X214702Y1977062D01*
X214535Y1977354D01*
X214243Y1977562D01*
X213910Y1977604D01*
X213577Y1977520D01*
X213368Y1977312D01*
X213202Y1977020D01*
X213160Y1976729D01*
X213202Y1976437D01*
X213368Y1976062D01*
X212285Y1976187D01*
Y1977312D01*
G01X260177Y1935491D02*
Y1916291D01*
X271377D01*
Y1935491D01*
X260177D01*
Y1935091D01*
G01X212999Y1901567D02*
X210499D01*
Y1902608D01*
X210624Y1902942D01*
X210791Y1903150D01*
X211124Y1903233D01*
X211457Y1903150D01*
X211666Y1902900D01*
X211791Y1902608D01*
Y1901567D01*
G01Y1902608D02*
X212999Y1903233D01*
G01Y1905500D02*
X210499D01*
X210999Y1905000D01*
G01X212999D02*
Y1906000D01*
G01Y1908517D02*
X212457Y1908600D01*
X211999Y1908725D01*
X211582Y1908892D01*
X211124Y1909100D01*
X210499Y1909433D01*
Y1907767D01*
G01X212624Y1910783D02*
X212832Y1911033D01*
X212957Y1911325D01*
X212999Y1911700D01*
X212916Y1912075D01*
X212749Y1912367D01*
X212457Y1912575D01*
X212124Y1912617D01*
X211791Y1912533D01*
X211582Y1912325D01*
X211416Y1912033D01*
X211374Y1911742D01*
X211416Y1911450D01*
X211582Y1911075D01*
X210499Y1911200D01*
Y1912325D01*
G01X241934Y1900187D02*
Y1913187D01*
G01X215934Y1900187D02*
X241934D01*
G01X215934Y1913187D02*
Y1900187D01*
G01X241934Y1913187D02*
X215934D01*
G01X208499Y1937567D02*
X205999D01*
Y1938608D01*
X206124Y1938942D01*
X206291Y1939150D01*
X206624Y1939233D01*
X206957Y1939150D01*
X207166Y1938900D01*
X207291Y1938608D01*
Y1937567D01*
G01Y1938608D02*
X208499Y1939233D01*
G01Y1941500D02*
X205999D01*
X206499Y1941000D01*
G01X208499D02*
Y1942000D01*
G01Y1944517D02*
X207957Y1944600D01*
X207499Y1944725D01*
X207082Y1944892D01*
X206624Y1945100D01*
X205999Y1945433D01*
Y1943767D01*
G01X208499Y1947700D02*
X208457Y1947992D01*
X208332Y1948325D01*
X208124Y1948533D01*
X207832Y1948617D01*
X207541Y1948533D01*
X207291Y1948283D01*
X207166Y1947908D01*
Y1947492D01*
X207082Y1947242D01*
X206874Y1947033D01*
X206582Y1946950D01*
X206291Y1947075D01*
X206082Y1947367D01*
X205999Y1947700D01*
X206082Y1948033D01*
X206291Y1948325D01*
X206582Y1948450D01*
X206874Y1948367D01*
X207082Y1948158D01*
X207166Y1947908D01*
Y1947492D01*
X207291Y1947117D01*
X207541Y1946867D01*
X207832Y1946783D01*
X208124Y1946867D01*
X208332Y1947075D01*
X208457Y1947408D01*
X208499Y1947700D01*
G01X240434Y1936487D02*
Y1949487D01*
G01X214434Y1936487D02*
X240434D01*
G01X214434Y1949487D02*
Y1936487D01*
G01X240434Y1949487D02*
X214434D01*
G01X221436Y1891665D02*
X225436D01*
Y1899065D01*
G01X238100Y1899300D02*
X234100D01*
Y1891900D01*
G01X211500Y1920350D02*
X214000D01*
G01X211500Y1919392D02*
Y1921308D01*
G01X214000Y1922617D02*
X211500D01*
Y1923617D01*
X211625Y1923950D01*
X211917Y1924200D01*
X212250Y1924283D01*
X212583Y1924200D01*
X212833Y1923992D01*
X212958Y1923617D01*
Y1922617D01*
G01X213500Y1925633D02*
X213792Y1925883D01*
X213958Y1926217D01*
X214000Y1926592D01*
X213958Y1926925D01*
X213750Y1927258D01*
X213500Y1927467D01*
X213250Y1927508D01*
X212958Y1927425D01*
X212750Y1927133D01*
X212667Y1926842D01*
Y1926467D01*
G01Y1926842D02*
X212542Y1927092D01*
X212333Y1927300D01*
X212083Y1927383D01*
X211833Y1927300D01*
X211625Y1927092D01*
X211500Y1926717D01*
X211542Y1926342D01*
X211708Y1925967D01*
G01X211500Y1929650D02*
X211583Y1929317D01*
X211792Y1929067D01*
X212042Y1928900D01*
X212375Y1928775D01*
X212750Y1928733D01*
X213125Y1928775D01*
X213458Y1928900D01*
X213708Y1929067D01*
X213917Y1929317D01*
X214000Y1929650D01*
X213917Y1929983D01*
X213708Y1930233D01*
X213458Y1930400D01*
X213125Y1930525D01*
X212750Y1930567D01*
X212375Y1930525D01*
X212042Y1930400D01*
X211792Y1930233D01*
X211583Y1929983D01*
X211500Y1929650D01*
G01X210708Y1939767D02*
X210583Y1939517D01*
X210500Y1939225D01*
Y1938892D01*
X210625Y1938517D01*
X210833Y1938225D01*
X211083Y1938017D01*
X211500Y1937850D01*
X211875Y1937808D01*
X212250Y1937892D01*
X212500Y1938017D01*
X212750Y1938267D01*
X212917Y1938558D01*
X213000Y1938850D01*
Y1939142D01*
X212917Y1939433D01*
X212792Y1939683D01*
X212625Y1939892D01*
G01X213000Y1941950D02*
X210500D01*
X211000Y1941450D01*
G01X213000D02*
Y1942450D01*
G01X212708Y1944342D02*
X212917Y1944633D01*
X213000Y1944967D01*
X212917Y1945300D01*
X212667Y1945592D01*
X212292Y1945800D01*
X211917Y1945883D01*
X211458D01*
X211083Y1945800D01*
X210750Y1945592D01*
X210583Y1945342D01*
X210500Y1945050D01*
X210583Y1944717D01*
X210750Y1944467D01*
X211000Y1944300D01*
X211333Y1944217D01*
X211625Y1944300D01*
X211917Y1944508D01*
X212083Y1944758D01*
X212125Y1945050D01*
X212042Y1945383D01*
X211833Y1945633D01*
X211458Y1945883D01*
G01X213000Y1948150D02*
X210500D01*
X211000Y1947650D01*
G01X213000D02*
Y1948650D01*
G01X250314Y1948413D02*
Y1942913D01*
G01X242314Y1948413D02*
X250314D01*
G01X242314Y1942913D02*
Y1948413D01*
G01Y1930813D02*
Y1936313D01*
G01X250314Y1930813D02*
X242314D01*
G01X250314Y1936313D02*
Y1930813D01*
G01X219508Y1971767D02*
X219383Y1971517D01*
X219300Y1971225D01*
Y1970892D01*
X219425Y1970517D01*
X219633Y1970225D01*
X219883Y1970017D01*
X220300Y1969850D01*
X220675Y1969808D01*
X221050Y1969892D01*
X221300Y1970017D01*
X221550Y1970267D01*
X221717Y1970558D01*
X221800Y1970850D01*
Y1971142D01*
X221717Y1971433D01*
X221592Y1971683D01*
X221425Y1971892D01*
G01X221800Y1973950D02*
X219300D01*
X219800Y1973450D01*
G01X221800D02*
Y1974450D01*
G01X221508Y1976342D02*
X221717Y1976633D01*
X221800Y1976967D01*
X221717Y1977300D01*
X221467Y1977592D01*
X221092Y1977800D01*
X220717Y1977883D01*
X220258D01*
X219883Y1977800D01*
X219550Y1977592D01*
X219383Y1977342D01*
X219300Y1977050D01*
X219383Y1976717D01*
X219550Y1976467D01*
X219800Y1976300D01*
X220133Y1976217D01*
X220425Y1976300D01*
X220717Y1976508D01*
X220883Y1976758D01*
X220925Y1977050D01*
X220842Y1977383D01*
X220633Y1977633D01*
X220258Y1977883D01*
G01X219717Y1979358D02*
X219467Y1979608D01*
X219342Y1979900D01*
X219300Y1980233D01*
X219383Y1980650D01*
X219592Y1980942D01*
X219842Y1981025D01*
X220092Y1980983D01*
X220300Y1980817D01*
X220717Y1979983D01*
X221008Y1979608D01*
X221425Y1979358D01*
X221800Y1979275D01*
Y1981025D01*
G01X216300Y1950300D02*
Y1955800D01*
G01X224300Y1950300D02*
X216300D01*
G01X224300Y1955800D02*
Y1950300D01*
G01Y1967900D02*
Y1962400D01*
G01X216300Y1967900D02*
X224300D01*
G01X216300Y1962400D02*
Y1967900D01*
G01X228208Y1971767D02*
X228083Y1971517D01*
X228000Y1971225D01*
Y1970892D01*
X228125Y1970517D01*
X228333Y1970225D01*
X228583Y1970017D01*
X229000Y1969850D01*
X229375Y1969808D01*
X229750Y1969892D01*
X230000Y1970017D01*
X230250Y1970267D01*
X230417Y1970558D01*
X230500Y1970850D01*
Y1971142D01*
X230417Y1971433D01*
X230292Y1971683D01*
X230125Y1971892D01*
G01X230500Y1973950D02*
X228000D01*
X228500Y1973450D01*
G01X230500D02*
Y1974450D01*
G01X230208Y1976342D02*
X230417Y1976633D01*
X230500Y1976967D01*
X230417Y1977300D01*
X230167Y1977592D01*
X229792Y1977800D01*
X229417Y1977883D01*
X228958D01*
X228583Y1977800D01*
X228250Y1977592D01*
X228083Y1977342D01*
X228000Y1977050D01*
X228083Y1976717D01*
X228250Y1976467D01*
X228500Y1976300D01*
X228833Y1976217D01*
X229125Y1976300D01*
X229417Y1976508D01*
X229583Y1976758D01*
X229625Y1977050D01*
X229542Y1977383D01*
X229333Y1977633D01*
X228958Y1977883D01*
G01X230000Y1979233D02*
X230292Y1979483D01*
X230458Y1979817D01*
X230500Y1980192D01*
X230458Y1980525D01*
X230250Y1980858D01*
X230000Y1981067D01*
X229750Y1981108D01*
X229458Y1981025D01*
X229250Y1980733D01*
X229167Y1980442D01*
Y1980067D01*
G01Y1980442D02*
X229042Y1980692D01*
X228833Y1980900D01*
X228583Y1980983D01*
X228333Y1980900D01*
X228125Y1980692D01*
X228000Y1980317D01*
X228042Y1979942D01*
X228208Y1979567D01*
G01X225000Y1950300D02*
Y1955800D01*
G01X233000Y1950300D02*
X225000D01*
G01X233000Y1955800D02*
Y1950300D01*
G01Y1967900D02*
Y1962400D01*
G01X225000Y1967900D02*
X233000D01*
G01X225000Y1962400D02*
Y1967900D01*
G01X236908Y1971767D02*
X236783Y1971517D01*
X236700Y1971225D01*
Y1970892D01*
X236825Y1970517D01*
X237033Y1970225D01*
X237283Y1970017D01*
X237700Y1969850D01*
X238075Y1969808D01*
X238450Y1969892D01*
X238700Y1970017D01*
X238950Y1970267D01*
X239117Y1970558D01*
X239200Y1970850D01*
Y1971142D01*
X239117Y1971433D01*
X238992Y1971683D01*
X238825Y1971892D01*
G01X239200Y1973950D02*
X236700D01*
X237200Y1973450D01*
G01X239200D02*
Y1974450D01*
G01X238908Y1976342D02*
X239117Y1976633D01*
X239200Y1976967D01*
X239117Y1977300D01*
X238867Y1977592D01*
X238492Y1977800D01*
X238117Y1977883D01*
X237658D01*
X237283Y1977800D01*
X236950Y1977592D01*
X236783Y1977342D01*
X236700Y1977050D01*
X236783Y1976717D01*
X236950Y1976467D01*
X237200Y1976300D01*
X237533Y1976217D01*
X237825Y1976300D01*
X238117Y1976508D01*
X238283Y1976758D01*
X238325Y1977050D01*
X238242Y1977383D01*
X238033Y1977633D01*
X237658Y1977883D01*
G01X239200Y1980650D02*
X236700D01*
X238492Y1979108D01*
Y1981192D01*
G01X233700Y1950300D02*
Y1955800D01*
G01X241700Y1950300D02*
X233700D01*
G01X241700Y1955800D02*
Y1950300D01*
G01Y1967900D02*
Y1962400D01*
G01X233700Y1967900D02*
X241700D01*
G01X233700Y1962400D02*
Y1967900D01*
G01X206708Y1921767D02*
X206583Y1921517D01*
X206500Y1921225D01*
Y1920892D01*
X206625Y1920517D01*
X206833Y1920225D01*
X207083Y1920017D01*
X207500Y1919850D01*
X207875Y1919808D01*
X208250Y1919892D01*
X208500Y1920017D01*
X208750Y1920267D01*
X208917Y1920558D01*
X209000Y1920850D01*
Y1921142D01*
X208917Y1921433D01*
X208792Y1921683D01*
X208625Y1921892D01*
G01X209000Y1923950D02*
X206500D01*
X207000Y1923450D01*
G01X209000D02*
Y1924450D01*
G01Y1927050D02*
X208958Y1927342D01*
X208833Y1927675D01*
X208625Y1927883D01*
X208333Y1927967D01*
X208042Y1927883D01*
X207792Y1927633D01*
X207667Y1927258D01*
Y1926842D01*
X207583Y1926592D01*
X207375Y1926383D01*
X207083Y1926300D01*
X206792Y1926425D01*
X206583Y1926717D01*
X206500Y1927050D01*
X206583Y1927383D01*
X206792Y1927675D01*
X207083Y1927800D01*
X207375Y1927717D01*
X207583Y1927508D01*
X207667Y1927258D01*
Y1926842D01*
X207792Y1926467D01*
X208042Y1926217D01*
X208333Y1926133D01*
X208625Y1926217D01*
X208833Y1926425D01*
X208958Y1926758D01*
X209000Y1927050D01*
G01X208708Y1929442D02*
X208917Y1929733D01*
X209000Y1930067D01*
X208917Y1930400D01*
X208667Y1930692D01*
X208292Y1930900D01*
X207917Y1930983D01*
X207458D01*
X207083Y1930900D01*
X206750Y1930692D01*
X206583Y1930442D01*
X206500Y1930150D01*
X206583Y1929817D01*
X206750Y1929567D01*
X207000Y1929400D01*
X207333Y1929317D01*
X207625Y1929400D01*
X207917Y1929608D01*
X208083Y1929858D01*
X208125Y1930150D01*
X208042Y1930483D01*
X207833Y1930733D01*
X207458Y1930983D01*
G01X221814Y1916813D02*
Y1922313D01*
G01X229814Y1916813D02*
X221814D01*
G01X229814Y1922313D02*
Y1916813D01*
G01Y1934413D02*
Y1928913D01*
G01X221814Y1934413D02*
X229814D01*
G01X221814Y1928913D02*
Y1934413D01*
G01X246600Y1891200D02*
X233600D01*
G01X283707Y56817D02*
X283582Y56567D01*
X283499Y56275D01*
Y55942D01*
X283624Y55567D01*
X283832Y55275D01*
X284082Y55067D01*
X284499Y54900D01*
X284874Y54858D01*
X285249Y54942D01*
X285499Y55067D01*
X285749Y55317D01*
X285916Y55608D01*
X285999Y55900D01*
Y56192D01*
X285916Y56483D01*
X285791Y56733D01*
X285624Y56942D01*
G01X285499Y58083D02*
X285791Y58333D01*
X285957Y58667D01*
X285999Y59042D01*
X285957Y59375D01*
X285749Y59708D01*
X285499Y59917D01*
X285249Y59958D01*
X284957Y59875D01*
X284749Y59583D01*
X284666Y59292D01*
Y58917D01*
G01Y59292D02*
X284541Y59542D01*
X284332Y59750D01*
X284082Y59833D01*
X283832Y59750D01*
X283624Y59542D01*
X283499Y59167D01*
X283541Y58792D01*
X283707Y58417D01*
G01X285499Y61183D02*
X285791Y61433D01*
X285957Y61767D01*
X285999Y62142D01*
X285957Y62475D01*
X285749Y62808D01*
X285499Y63017D01*
X285249Y63058D01*
X284957Y62975D01*
X284749Y62683D01*
X284666Y62392D01*
Y62017D01*
G01Y62392D02*
X284541Y62642D01*
X284332Y62850D01*
X284082Y62933D01*
X283832Y62850D01*
X283624Y62642D01*
X283499Y62267D01*
X283541Y61892D01*
X283707Y61517D01*
G01X283499Y65200D02*
X283582Y64867D01*
X283791Y64617D01*
X284041Y64450D01*
X284374Y64325D01*
X284749Y64283D01*
X285124Y64325D01*
X285457Y64450D01*
X285707Y64617D01*
X285916Y64867D01*
X285999Y65200D01*
X285916Y65533D01*
X285707Y65783D01*
X285457Y65950D01*
X285124Y66075D01*
X284749Y66117D01*
X284374Y66075D01*
X284041Y65950D01*
X283791Y65783D01*
X283582Y65533D01*
X283499Y65200D01*
G01X282307Y21817D02*
X282182Y21567D01*
X282099Y21275D01*
Y20942D01*
X282224Y20567D01*
X282432Y20275D01*
X282682Y20067D01*
X283099Y19900D01*
X283474Y19858D01*
X283849Y19942D01*
X284099Y20067D01*
X284349Y20317D01*
X284516Y20608D01*
X284599Y20900D01*
Y21192D01*
X284516Y21483D01*
X284391Y21733D01*
X284224Y21942D01*
G01X284099Y23083D02*
X284391Y23333D01*
X284557Y23667D01*
X284599Y24042D01*
X284557Y24375D01*
X284349Y24708D01*
X284099Y24917D01*
X283849Y24958D01*
X283557Y24875D01*
X283349Y24583D01*
X283266Y24292D01*
Y23917D01*
G01Y24292D02*
X283141Y24542D01*
X282932Y24750D01*
X282682Y24833D01*
X282432Y24750D01*
X282224Y24542D01*
X282099Y24167D01*
X282141Y23792D01*
X282307Y23417D01*
G01X284099Y26183D02*
X284391Y26433D01*
X284557Y26767D01*
X284599Y27142D01*
X284557Y27475D01*
X284349Y27808D01*
X284099Y28017D01*
X283849Y28058D01*
X283557Y27975D01*
X283349Y27683D01*
X283266Y27392D01*
Y27017D01*
G01Y27392D02*
X283141Y27642D01*
X282932Y27850D01*
X282682Y27933D01*
X282432Y27850D01*
X282224Y27642D01*
X282099Y27267D01*
X282141Y26892D01*
X282307Y26517D01*
G01X284599Y30200D02*
X284557Y30492D01*
X284432Y30825D01*
X284224Y31033D01*
X283932Y31117D01*
X283641Y31033D01*
X283391Y30783D01*
X283266Y30408D01*
Y29992D01*
X283182Y29742D01*
X282974Y29533D01*
X282682Y29450D01*
X282391Y29575D01*
X282182Y29867D01*
X282099Y30200D01*
X282182Y30533D01*
X282391Y30825D01*
X282682Y30950D01*
X282974Y30867D01*
X283182Y30658D01*
X283266Y30408D01*
Y29992D01*
X283391Y29617D01*
X283641Y29367D01*
X283932Y29283D01*
X284224Y29367D01*
X284432Y29575D01*
X284557Y29908D01*
X284599Y30200D01*
G01X279000Y41017D02*
X276500D01*
Y42058D01*
X276625Y42392D01*
X276792Y42600D01*
X277125Y42683D01*
X277458Y42600D01*
X277667Y42350D01*
X277792Y42058D01*
Y41017D01*
G01Y42058D02*
X279000Y42683D01*
G01X278500Y44033D02*
X278792Y44283D01*
X278958Y44617D01*
X279000Y44992D01*
X278958Y45325D01*
X278750Y45658D01*
X278500Y45867D01*
X278250Y45908D01*
X277958Y45825D01*
X277750Y45533D01*
X277667Y45242D01*
Y44867D01*
G01Y45242D02*
X277542Y45492D01*
X277333Y45700D01*
X277083Y45783D01*
X276833Y45700D01*
X276625Y45492D01*
X276500Y45117D01*
X276542Y44742D01*
X276708Y44367D01*
G01X276500Y48050D02*
X276583Y47717D01*
X276792Y47467D01*
X277042Y47300D01*
X277375Y47175D01*
X277750Y47133D01*
X278125Y47175D01*
X278458Y47300D01*
X278708Y47467D01*
X278917Y47717D01*
X279000Y48050D01*
X278917Y48383D01*
X278708Y48633D01*
X278458Y48800D01*
X278125Y48925D01*
X277750Y48967D01*
X277375Y48925D01*
X277042Y48800D01*
X276792Y48633D01*
X276583Y48383D01*
X276500Y48050D01*
G01X279000Y51650D02*
X276500D01*
X278292Y50108D01*
Y52192D01*
G01X317499Y37113D02*
Y50113D01*
G01X291499Y37113D02*
X317499D01*
G01X291499Y50113D02*
Y37113D01*
G01X317499Y50113D02*
X291499D01*
G01X332299Y65050D02*
Y61050D01*
X339699D01*
G01X332299Y69050D02*
Y65050D01*
X339699D01*
G01X281208Y42767D02*
X281083Y42517D01*
X281000Y42225D01*
Y41892D01*
X281125Y41517D01*
X281333Y41225D01*
X281583Y41017D01*
X282000Y40850D01*
X282375Y40808D01*
X282750Y40892D01*
X283000Y41017D01*
X283250Y41267D01*
X283417Y41558D01*
X283500Y41850D01*
Y42142D01*
X283417Y42433D01*
X283292Y42683D01*
X283125Y42892D01*
G01X283000Y44033D02*
X283292Y44283D01*
X283458Y44617D01*
X283500Y44992D01*
X283458Y45325D01*
X283250Y45658D01*
X283000Y45867D01*
X282750Y45908D01*
X282458Y45825D01*
X282250Y45533D01*
X282167Y45242D01*
Y44867D01*
G01Y45242D02*
X282042Y45492D01*
X281833Y45700D01*
X281583Y45783D01*
X281333Y45700D01*
X281125Y45492D01*
X281000Y45117D01*
X281042Y44742D01*
X281208Y44367D01*
G01X283000Y47133D02*
X283292Y47383D01*
X283458Y47717D01*
X283500Y48092D01*
X283458Y48425D01*
X283250Y48758D01*
X283000Y48967D01*
X282750Y49008D01*
X282458Y48925D01*
X282250Y48633D01*
X282167Y48342D01*
Y47967D01*
G01Y48342D02*
X282042Y48592D01*
X281833Y48800D01*
X281583Y48883D01*
X281333Y48800D01*
X281125Y48592D01*
X281000Y48217D01*
X281042Y47842D01*
X281208Y47467D01*
G01X283000Y50233D02*
X283292Y50483D01*
X283458Y50817D01*
X283500Y51192D01*
X283458Y51525D01*
X283250Y51858D01*
X283000Y52067D01*
X282750Y52108D01*
X282458Y52025D01*
X282250Y51733D01*
X282167Y51442D01*
Y51067D01*
G01Y51442D02*
X282042Y51692D01*
X281833Y51900D01*
X281583Y51983D01*
X281333Y51900D01*
X281125Y51692D01*
X281000Y51317D01*
X281042Y50942D01*
X281208Y50567D01*
G01X318499Y40313D02*
Y45813D01*
G01X326499Y40313D02*
X318499D01*
G01X326499Y45813D02*
Y40313D01*
G01Y57913D02*
Y52413D01*
G01X318499Y57913D02*
X326499D01*
G01X318499Y52413D02*
Y57913D01*
G01X313307Y7480D02*
X313182Y7230D01*
X313099Y6938D01*
Y6605D01*
X313224Y6230D01*
X313432Y5938D01*
X313682Y5730D01*
X314099Y5563D01*
X314474Y5521D01*
X314849Y5605D01*
X315099Y5730D01*
X315349Y5980D01*
X315516Y6271D01*
X315599Y6563D01*
Y6855D01*
X315516Y7146D01*
X315391Y7396D01*
X315224Y7605D01*
G01X315099Y8746D02*
X315391Y8996D01*
X315557Y9330D01*
X315599Y9705D01*
X315557Y10038D01*
X315349Y10371D01*
X315099Y10580D01*
X314849Y10621D01*
X314557Y10538D01*
X314349Y10246D01*
X314266Y9955D01*
Y9580D01*
G01Y9955D02*
X314141Y10205D01*
X313932Y10413D01*
X313682Y10496D01*
X313432Y10413D01*
X313224Y10205D01*
X313099Y9830D01*
X313141Y9455D01*
X313307Y9080D01*
G01X315099Y11846D02*
X315391Y12096D01*
X315557Y12430D01*
X315599Y12805D01*
X315557Y13138D01*
X315349Y13471D01*
X315099Y13680D01*
X314849Y13721D01*
X314557Y13638D01*
X314349Y13346D01*
X314266Y13055D01*
Y12680D01*
G01Y13055D02*
X314141Y13305D01*
X313932Y13513D01*
X313682Y13596D01*
X313432Y13513D01*
X313224Y13305D01*
X313099Y12930D01*
X313141Y12555D01*
X313307Y12180D01*
G01X315599Y16363D02*
X313099D01*
X314891Y14821D01*
Y16905D01*
G01X318099Y36413D02*
Y30913D01*
G01X310099Y36413D02*
X318099D01*
G01X310099Y30913D02*
Y36413D01*
G01Y18813D02*
Y24313D01*
G01X318099Y18813D02*
X310099D01*
G01X318099Y24313D02*
Y18813D01*
G01X304307Y7480D02*
X304182Y7230D01*
X304099Y6938D01*
Y6605D01*
X304224Y6230D01*
X304432Y5938D01*
X304682Y5730D01*
X305099Y5563D01*
X305474Y5521D01*
X305849Y5605D01*
X306099Y5730D01*
X306349Y5980D01*
X306516Y6271D01*
X306599Y6563D01*
Y6855D01*
X306516Y7146D01*
X306391Y7396D01*
X306224Y7605D01*
G01X306099Y8746D02*
X306391Y8996D01*
X306557Y9330D01*
X306599Y9705D01*
X306557Y10038D01*
X306349Y10371D01*
X306099Y10580D01*
X305849Y10621D01*
X305557Y10538D01*
X305349Y10246D01*
X305266Y9955D01*
Y9580D01*
G01Y9955D02*
X305141Y10205D01*
X304932Y10413D01*
X304682Y10496D01*
X304432Y10413D01*
X304224Y10205D01*
X304099Y9830D01*
X304141Y9455D01*
X304307Y9080D01*
G01X306099Y11846D02*
X306391Y12096D01*
X306557Y12430D01*
X306599Y12805D01*
X306557Y13138D01*
X306349Y13471D01*
X306099Y13680D01*
X305849Y13721D01*
X305557Y13638D01*
X305349Y13346D01*
X305266Y13055D01*
Y12680D01*
G01Y13055D02*
X305141Y13305D01*
X304932Y13513D01*
X304682Y13596D01*
X304432Y13513D01*
X304224Y13305D01*
X304099Y12930D01*
X304141Y12555D01*
X304307Y12180D01*
G01X306224Y14946D02*
X306432Y15196D01*
X306557Y15488D01*
X306599Y15863D01*
X306516Y16238D01*
X306349Y16530D01*
X306057Y16738D01*
X305724Y16780D01*
X305391Y16696D01*
X305182Y16488D01*
X305016Y16196D01*
X304974Y15905D01*
X305016Y15613D01*
X305182Y15238D01*
X304099Y15363D01*
Y16488D01*
G01X309099Y36413D02*
Y30913D01*
G01X301099Y36413D02*
X309099D01*
G01X301099Y30913D02*
Y36413D01*
G01Y18813D02*
Y24313D01*
G01X309099Y18813D02*
X301099D01*
G01X309099Y24313D02*
Y18813D01*
G01X295307Y7480D02*
X295182Y7230D01*
X295099Y6938D01*
Y6605D01*
X295224Y6230D01*
X295432Y5938D01*
X295682Y5730D01*
X296099Y5563D01*
X296474Y5521D01*
X296849Y5605D01*
X297099Y5730D01*
X297349Y5980D01*
X297516Y6271D01*
X297599Y6563D01*
Y6855D01*
X297516Y7146D01*
X297391Y7396D01*
X297224Y7605D01*
G01X297099Y8746D02*
X297391Y8996D01*
X297557Y9330D01*
X297599Y9705D01*
X297557Y10038D01*
X297349Y10371D01*
X297099Y10580D01*
X296849Y10621D01*
X296557Y10538D01*
X296349Y10246D01*
X296266Y9955D01*
Y9580D01*
G01Y9955D02*
X296141Y10205D01*
X295932Y10413D01*
X295682Y10496D01*
X295432Y10413D01*
X295224Y10205D01*
X295099Y9830D01*
X295141Y9455D01*
X295307Y9080D01*
G01X297099Y11846D02*
X297391Y12096D01*
X297557Y12430D01*
X297599Y12805D01*
X297557Y13138D01*
X297349Y13471D01*
X297099Y13680D01*
X296849Y13721D01*
X296557Y13638D01*
X296349Y13346D01*
X296266Y13055D01*
Y12680D01*
G01Y13055D02*
X296141Y13305D01*
X295932Y13513D01*
X295682Y13596D01*
X295432Y13513D01*
X295224Y13305D01*
X295099Y12930D01*
X295141Y12555D01*
X295307Y12180D01*
G01X296557Y15071D02*
X296266Y15363D01*
X296099Y15613D01*
X296016Y15946D01*
X296099Y16238D01*
X296266Y16446D01*
X296516Y16613D01*
X296807Y16655D01*
X297057Y16613D01*
X297307Y16446D01*
X297516Y16196D01*
X297599Y15905D01*
X297516Y15571D01*
X297266Y15280D01*
X296891Y15113D01*
X296474Y15071D01*
X295932Y15155D01*
X295641Y15280D01*
X295349Y15488D01*
X295141Y15780D01*
X295099Y16071D01*
X295182Y16363D01*
X295391Y16571D01*
G01X300099Y36413D02*
Y30913D01*
G01X292099Y36413D02*
X300099D01*
G01X292099Y30913D02*
Y36413D01*
G01Y18813D02*
Y24313D01*
G01X300099Y18813D02*
X292099D01*
G01X300099Y24313D02*
Y18813D01*
G01X287708Y57267D02*
X287583Y57017D01*
X287500Y56725D01*
Y56392D01*
X287625Y56017D01*
X287833Y55725D01*
X288083Y55517D01*
X288500Y55350D01*
X288875Y55308D01*
X289250Y55392D01*
X289500Y55517D01*
X289750Y55767D01*
X289917Y56058D01*
X290000Y56350D01*
Y56642D01*
X289917Y56933D01*
X289792Y57183D01*
X289625Y57392D01*
G01X289500Y58533D02*
X289792Y58783D01*
X289958Y59117D01*
X290000Y59492D01*
X289958Y59825D01*
X289750Y60158D01*
X289500Y60367D01*
X289250Y60408D01*
X288958Y60325D01*
X288750Y60033D01*
X288667Y59742D01*
Y59367D01*
G01Y59742D02*
X288542Y59992D01*
X288333Y60200D01*
X288083Y60283D01*
X287833Y60200D01*
X287625Y59992D01*
X287500Y59617D01*
X287542Y59242D01*
X287708Y58867D01*
G01X289500Y61633D02*
X289792Y61883D01*
X289958Y62217D01*
X290000Y62592D01*
X289958Y62925D01*
X289750Y63258D01*
X289500Y63467D01*
X289250Y63508D01*
X288958Y63425D01*
X288750Y63133D01*
X288667Y62842D01*
Y62467D01*
G01Y62842D02*
X288542Y63092D01*
X288333Y63300D01*
X288083Y63383D01*
X287833Y63300D01*
X287625Y63092D01*
X287500Y62717D01*
X287542Y62342D01*
X287708Y61967D01*
G01X290000Y65650D02*
X287500D01*
X288000Y65150D01*
G01X290000D02*
Y66150D01*
G01X304999Y69913D02*
Y64413D01*
G01X296999D02*
Y69913D01*
G01Y52313D02*
Y57813D01*
G01X304999Y52313D02*
X296999D01*
G01X304999Y57813D02*
Y52313D01*
G01X272208Y94267D02*
X272083Y94017D01*
X272000Y93725D01*
Y93392D01*
X272125Y93017D01*
X272333Y92725D01*
X272583Y92517D01*
X273000Y92350D01*
X273375Y92308D01*
X273750Y92392D01*
X274000Y92517D01*
X274250Y92767D01*
X274417Y93058D01*
X274500Y93350D01*
Y93642D01*
X274417Y93933D01*
X274292Y94183D01*
X274125Y94392D01*
G01X274000Y95533D02*
X274292Y95783D01*
X274458Y96117D01*
X274500Y96492D01*
X274458Y96825D01*
X274250Y97158D01*
X274000Y97367D01*
X273750Y97408D01*
X273458Y97325D01*
X273250Y97033D01*
X273167Y96742D01*
Y96367D01*
G01Y96742D02*
X273042Y96992D01*
X272833Y97200D01*
X272583Y97283D01*
X272333Y97200D01*
X272125Y96992D01*
X272000Y96617D01*
X272042Y96242D01*
X272208Y95867D01*
G01X274000Y98633D02*
X274292Y98883D01*
X274458Y99217D01*
X274500Y99592D01*
X274458Y99925D01*
X274250Y100258D01*
X274000Y100467D01*
X273750Y100508D01*
X273458Y100425D01*
X273250Y100133D01*
X273167Y99842D01*
Y99467D01*
G01Y99842D02*
X273042Y100092D01*
X272833Y100300D01*
X272583Y100383D01*
X272333Y100300D01*
X272125Y100092D01*
X272000Y99717D01*
X272042Y99342D01*
X272208Y98967D01*
G01X272417Y101858D02*
X272167Y102108D01*
X272042Y102400D01*
X272000Y102733D01*
X272083Y103150D01*
X272292Y103442D01*
X272542Y103525D01*
X272792Y103483D01*
X273000Y103317D01*
X273417Y102483D01*
X273708Y102108D01*
X274125Y101858D01*
X274500Y101775D01*
Y103525D01*
G01X325400Y102500D02*
X325067Y102542D01*
X324775Y102708D01*
X324525Y102958D01*
X324358Y103250D01*
X324275Y103583D01*
Y103917D01*
X324358Y104250D01*
X324525Y104542D01*
X324775Y104792D01*
X325067Y104958D01*
X325400Y105000D01*
X325733Y104958D01*
X326025Y104792D01*
X326275Y104542D01*
X326442Y104250D01*
X326525Y103917D01*
Y103583D01*
X326442Y103250D01*
X326275Y102958D01*
X326025Y102708D01*
X325733Y102542D01*
X325400Y102500D01*
G01X325733Y103167D02*
X326233Y102500D01*
G01X328417D02*
X328500Y103042D01*
X328625Y103500D01*
X328792Y103917D01*
X329000Y104375D01*
X329333Y105000D01*
X327667D01*
G01X332100Y102500D02*
Y105000D01*
X330558Y103208D01*
X332642D01*
G01X327800Y89200D02*
Y100600D01*
G01X314400Y89200D02*
X327800D01*
G01X314400Y100600D02*
Y89200D01*
G01X327800Y100600D02*
X314400D01*
G01X342799Y98550D02*
X344899Y96750D01*
X342799Y94550D01*
G01X342699Y90950D02*
X361899D01*
Y102150D01*
X342699D01*
Y90950D01*
X343099D01*
G01X278516Y76550D02*
Y79050D01*
X279557D01*
X279891Y78925D01*
X280099Y78758D01*
X280182Y78425D01*
X280099Y78092D01*
X279849Y77883D01*
X279557Y77758D01*
X278516D01*
G01X279557D02*
X280182Y76550D01*
G01X281532Y77050D02*
X281782Y76758D01*
X282116Y76592D01*
X282491Y76550D01*
X282824Y76592D01*
X283157Y76800D01*
X283366Y77050D01*
X283407Y77300D01*
X283324Y77592D01*
X283032Y77800D01*
X282741Y77883D01*
X282366D01*
G01X282741D02*
X282991Y78008D01*
X283199Y78217D01*
X283282Y78467D01*
X283199Y78717D01*
X282991Y78925D01*
X282616Y79050D01*
X282241Y79008D01*
X281866Y78842D01*
G01X285549Y79050D02*
X285216Y78967D01*
X284966Y78758D01*
X284799Y78508D01*
X284674Y78175D01*
X284632Y77800D01*
X284674Y77425D01*
X284799Y77092D01*
X284966Y76842D01*
X285216Y76633D01*
X285549Y76550D01*
X285882Y76633D01*
X286132Y76842D01*
X286299Y77092D01*
X286424Y77425D01*
X286466Y77800D01*
X286424Y78175D01*
X286299Y78508D01*
X286132Y78758D01*
X285882Y78967D01*
X285549Y79050D01*
G01X287857Y78633D02*
X288107Y78883D01*
X288399Y79008D01*
X288732Y79050D01*
X289149Y78967D01*
X289441Y78758D01*
X289524Y78508D01*
X289482Y78258D01*
X289316Y78050D01*
X288482Y77633D01*
X288107Y77342D01*
X287857Y76925D01*
X287774Y76550D01*
X289524D01*
G01X317499Y70613D02*
Y83613D01*
G01X291499Y70613D02*
X317499D01*
G01X291499Y83613D02*
Y70613D01*
G01X317499Y83613D02*
X291499D01*
G01X281017Y94000D02*
Y96500D01*
X282058D01*
X282392Y96375D01*
X282600Y96208D01*
X282683Y95875D01*
X282600Y95542D01*
X282350Y95333D01*
X282058Y95208D01*
X281017D01*
G01X282058D02*
X282683Y94000D01*
G01X284033Y94500D02*
X284283Y94208D01*
X284617Y94042D01*
X284992Y94000D01*
X285325Y94042D01*
X285658Y94250D01*
X285867Y94500D01*
X285908Y94750D01*
X285825Y95042D01*
X285533Y95250D01*
X285242Y95333D01*
X284867D01*
G01X285242D02*
X285492Y95458D01*
X285700Y95667D01*
X285783Y95917D01*
X285700Y96167D01*
X285492Y96375D01*
X285117Y96500D01*
X284742Y96458D01*
X284367Y96292D01*
G01X288050Y96500D02*
X287717Y96417D01*
X287467Y96208D01*
X287300Y95958D01*
X287175Y95625D01*
X287133Y95250D01*
X287175Y94875D01*
X287300Y94542D01*
X287467Y94292D01*
X287717Y94083D01*
X288050Y94000D01*
X288383Y94083D01*
X288633Y94292D01*
X288800Y94542D01*
X288925Y94875D01*
X288967Y95250D01*
X288925Y95625D01*
X288800Y95958D01*
X288633Y96208D01*
X288383Y96417D01*
X288050Y96500D01*
G01X291150Y94000D02*
Y96500D01*
X290650Y96000D01*
G01Y94000D02*
X291650D01*
G01X307699Y84613D02*
Y88613D01*
X300299D01*
G01X281017Y98000D02*
Y100500D01*
X282058D01*
X282392Y100375D01*
X282600Y100208D01*
X282683Y99875D01*
X282600Y99542D01*
X282350Y99333D01*
X282058Y99208D01*
X281017D01*
G01X282058D02*
X282683Y98000D01*
G01X285450D02*
Y100500D01*
X283908Y98708D01*
X285992D01*
G01X288050Y100500D02*
X287717Y100417D01*
X287467Y100208D01*
X287300Y99958D01*
X287175Y99625D01*
X287133Y99250D01*
X287175Y98875D01*
X287300Y98542D01*
X287467Y98292D01*
X287717Y98083D01*
X288050Y98000D01*
X288383Y98083D01*
X288633Y98292D01*
X288800Y98542D01*
X288925Y98875D01*
X288967Y99250D01*
X288925Y99625D01*
X288800Y99958D01*
X288633Y100208D01*
X288383Y100417D01*
X288050Y100500D01*
G01X291650Y98000D02*
Y100500D01*
X290108Y98708D01*
X292192D01*
G01X300300Y92700D02*
Y88700D01*
X307700D01*
G01X316517Y109500D02*
Y112000D01*
X317558D01*
X317892Y111875D01*
X318100Y111708D01*
X318183Y111375D01*
X318100Y111042D01*
X317850Y110833D01*
X317558Y110708D01*
X316517D01*
G01X317558D02*
X318183Y109500D01*
G01X320950D02*
Y112000D01*
X319408Y110208D01*
X321492D01*
G01X323550Y112000D02*
X323217Y111917D01*
X322967Y111708D01*
X322800Y111458D01*
X322675Y111125D01*
X322633Y110750D01*
X322675Y110375D01*
X322800Y110042D01*
X322967Y109792D01*
X323217Y109583D01*
X323550Y109500D01*
X323883Y109583D01*
X324133Y109792D01*
X324300Y110042D01*
X324425Y110375D01*
X324467Y110750D01*
X324425Y111125D01*
X324300Y111458D01*
X324133Y111708D01*
X323883Y111917D01*
X323550Y112000D01*
G01X325733Y109875D02*
X325983Y109667D01*
X326275Y109542D01*
X326650Y109500D01*
X327025Y109583D01*
X327317Y109750D01*
X327525Y110042D01*
X327567Y110375D01*
X327483Y110708D01*
X327275Y110917D01*
X326983Y111083D01*
X326692Y111125D01*
X326400Y111083D01*
X326025Y110917D01*
X326150Y112000D01*
X327275D01*
G01X321600Y103200D02*
Y107200D01*
X314200D01*
G01X335016Y72050D02*
Y74550D01*
X336057D01*
X336391Y74425D01*
X336599Y74258D01*
X336682Y73925D01*
X336599Y73592D01*
X336349Y73383D01*
X336057Y73258D01*
X335016D01*
G01X336057D02*
X336682Y72050D01*
G01X339449D02*
Y74550D01*
X337907Y72758D01*
X339991D01*
G01X341966Y72050D02*
X342049Y72592D01*
X342174Y73050D01*
X342341Y73467D01*
X342549Y73925D01*
X342882Y74550D01*
X341216D01*
G01X345649Y72050D02*
Y74550D01*
X344107Y72758D01*
X346191D01*
G01X335016Y76050D02*
Y78550D01*
X336057D01*
X336391Y78425D01*
X336599Y78258D01*
X336682Y77925D01*
X336599Y77592D01*
X336349Y77383D01*
X336057Y77258D01*
X335016D01*
G01X336057D02*
X336682Y76050D01*
G01X339449D02*
Y78550D01*
X337907Y76758D01*
X339991D01*
G01X341966Y76050D02*
X342049Y76592D01*
X342174Y77050D01*
X342341Y77467D01*
X342549Y77925D01*
X342882Y78550D01*
X341216D01*
G01X344232Y76425D02*
X344482Y76217D01*
X344774Y76092D01*
X345149Y76050D01*
X345524Y76133D01*
X345816Y76300D01*
X346024Y76592D01*
X346066Y76925D01*
X345982Y77258D01*
X345774Y77467D01*
X345482Y77633D01*
X345191Y77675D01*
X344899Y77633D01*
X344524Y77467D01*
X344649Y78550D01*
X345774D01*
G01X278500Y92517D02*
X276000D01*
Y93558D01*
X276125Y93892D01*
X276292Y94100D01*
X276625Y94183D01*
X276958Y94100D01*
X277167Y93850D01*
X277292Y93558D01*
Y92517D01*
G01Y93558D02*
X278500Y94183D01*
G01X278000Y95533D02*
X278292Y95783D01*
X278458Y96117D01*
X278500Y96492D01*
X278458Y96825D01*
X278250Y97158D01*
X278000Y97367D01*
X277750Y97408D01*
X277458Y97325D01*
X277250Y97033D01*
X277167Y96742D01*
Y96367D01*
G01Y96742D02*
X277042Y96992D01*
X276833Y97200D01*
X276583Y97283D01*
X276333Y97200D01*
X276125Y96992D01*
X276000Y96617D01*
X276042Y96242D01*
X276208Y95867D01*
G01X276000Y99550D02*
X276083Y99217D01*
X276292Y98967D01*
X276542Y98800D01*
X276875Y98675D01*
X277250Y98633D01*
X277625Y98675D01*
X277958Y98800D01*
X278208Y98967D01*
X278417Y99217D01*
X278500Y99550D01*
X278417Y99883D01*
X278208Y100133D01*
X277958Y100300D01*
X277625Y100425D01*
X277250Y100467D01*
X276875Y100425D01*
X276542Y100300D01*
X276292Y100133D01*
X276083Y99883D01*
X276000Y99550D01*
G01X278000Y101733D02*
X278292Y101983D01*
X278458Y102317D01*
X278500Y102692D01*
X278458Y103025D01*
X278250Y103358D01*
X278000Y103567D01*
X277750Y103608D01*
X277458Y103525D01*
X277250Y103233D01*
X277167Y102942D01*
Y102567D01*
G01Y102942D02*
X277042Y103192D01*
X276833Y103400D01*
X276583Y103483D01*
X276333Y103400D01*
X276125Y103192D01*
X276000Y102817D01*
X276042Y102442D01*
X276208Y102067D01*
G01X296999Y69913D02*
X304999D01*
G01X295900Y110500D02*
X295567Y110542D01*
X295275Y110708D01*
X295025Y110958D01*
X294858Y111250D01*
X294775Y111583D01*
Y111917D01*
X294858Y112250D01*
X295025Y112542D01*
X295275Y112792D01*
X295567Y112958D01*
X295900Y113000D01*
X296233Y112958D01*
X296525Y112792D01*
X296775Y112542D01*
X296942Y112250D01*
X297025Y111917D01*
Y111583D01*
X296942Y111250D01*
X296775Y110958D01*
X296525Y110708D01*
X296233Y110542D01*
X295900Y110500D01*
G01X296233Y111167D02*
X296733Y110500D01*
G01X298917D02*
X299000Y111042D01*
X299125Y111500D01*
X299292Y111917D01*
X299500Y112375D01*
X299833Y113000D01*
X298167D01*
G01X301183Y110875D02*
X301433Y110667D01*
X301725Y110542D01*
X302100Y110500D01*
X302475Y110583D01*
X302767Y110750D01*
X302975Y111042D01*
X303017Y111375D01*
X302933Y111708D01*
X302725Y111917D01*
X302433Y112083D01*
X302142Y112125D01*
X301850Y112083D01*
X301475Y111917D01*
X301600Y113000D01*
X302725D01*
G01X300500Y108400D02*
Y94400D01*
G01X313500Y108400D02*
X300500D01*
G01X313500Y94400D02*
Y108400D01*
G01X300500Y94400D02*
X313500D01*
G01X316708Y314267D02*
X316583Y314017D01*
X316500Y313725D01*
Y313392D01*
X316625Y313017D01*
X316833Y312725D01*
X317083Y312517D01*
X317500Y312350D01*
X317875Y312308D01*
X318250Y312392D01*
X318500Y312517D01*
X318750Y312767D01*
X318917Y313058D01*
X319000Y313350D01*
Y313642D01*
X318917Y313933D01*
X318792Y314183D01*
X318625Y314392D01*
G01X316917Y315658D02*
X316667Y315908D01*
X316542Y316200D01*
X316500Y316533D01*
X316583Y316950D01*
X316792Y317242D01*
X317042Y317325D01*
X317292Y317283D01*
X317500Y317117D01*
X317917Y316283D01*
X318208Y315908D01*
X318625Y315658D01*
X319000Y315575D01*
Y317325D01*
G01X318625Y318633D02*
X318833Y318883D01*
X318958Y319175D01*
X319000Y319550D01*
X318917Y319925D01*
X318750Y320217D01*
X318458Y320425D01*
X318125Y320467D01*
X317792Y320383D01*
X317583Y320175D01*
X317417Y319883D01*
X317375Y319592D01*
X317417Y319300D01*
X317583Y318925D01*
X316500Y319050D01*
Y320175D01*
G01X318500Y321733D02*
X318792Y321983D01*
X318958Y322317D01*
X319000Y322692D01*
X318958Y323025D01*
X318750Y323358D01*
X318500Y323567D01*
X318250Y323608D01*
X317958Y323525D01*
X317750Y323233D01*
X317667Y322942D01*
Y322567D01*
G01Y322942D02*
X317542Y323192D01*
X317333Y323400D01*
X317083Y323483D01*
X316833Y323400D01*
X316625Y323192D01*
X316500Y322817D01*
X316542Y322442D01*
X316708Y322067D01*
G01X299800Y300200D02*
X299467Y300242D01*
X299175Y300408D01*
X298925Y300658D01*
X298758Y300950D01*
X298675Y301283D01*
Y301617D01*
X298758Y301950D01*
X298925Y302242D01*
X299175Y302492D01*
X299467Y302658D01*
X299800Y302700D01*
X300133Y302658D01*
X300425Y302492D01*
X300675Y302242D01*
X300842Y301950D01*
X300925Y301617D01*
Y301283D01*
X300842Y300950D01*
X300675Y300658D01*
X300425Y300408D01*
X300133Y300242D01*
X299800Y300200D01*
G01X300133Y300867D02*
X300633Y300200D01*
G01X302900D02*
Y302700D01*
X302400Y302200D01*
G01Y300200D02*
X303400D01*
G01X305292Y300492D02*
X305583Y300283D01*
X305917Y300200D01*
X306250Y300283D01*
X306542Y300533D01*
X306750Y300908D01*
X306833Y301283D01*
Y301742D01*
X306750Y302117D01*
X306542Y302450D01*
X306292Y302617D01*
X306000Y302700D01*
X305667Y302617D01*
X305417Y302450D01*
X305250Y302200D01*
X305167Y301867D01*
X305250Y301575D01*
X305458Y301283D01*
X305708Y301117D01*
X306000Y301075D01*
X306333Y301158D01*
X306583Y301367D01*
X306833Y301742D01*
G01X265998Y313314D02*
X264198Y311214D01*
X261998Y313314D01*
G01X285827Y283816D02*
Y286316D01*
G01X287577D02*
Y283816D01*
G01Y285066D02*
X285827D01*
G01X289094Y284108D02*
X289385Y283899D01*
X289719Y283816D01*
X290052Y283899D01*
X290344Y284149D01*
X290552Y284524D01*
X290635Y284899D01*
Y285358D01*
X290552Y285733D01*
X290344Y286066D01*
X290094Y286233D01*
X289802Y286316D01*
X289469Y286233D01*
X289219Y286066D01*
X289052Y285816D01*
X288969Y285483D01*
X289052Y285191D01*
X289260Y284899D01*
X289510Y284733D01*
X289802Y284691D01*
X290135Y284774D01*
X290385Y284983D01*
X290635Y285358D01*
G01X331583Y377900D02*
Y380400D01*
X332417D01*
X332750Y380275D01*
X333000Y380108D01*
X333208Y379858D01*
X333375Y379567D01*
X333417Y379150D01*
X333375Y378733D01*
X333208Y378442D01*
X333000Y378192D01*
X332750Y378025D01*
X332417Y377900D01*
X331583D01*
G01X334808Y379983D02*
X335058Y380233D01*
X335350Y380358D01*
X335683Y380400D01*
X336100Y380317D01*
X336392Y380108D01*
X336475Y379858D01*
X336433Y379608D01*
X336267Y379400D01*
X335433Y378983D01*
X335058Y378692D01*
X334808Y378275D01*
X334725Y377900D01*
X336475D01*
G01X339200D02*
Y380400D01*
X337658Y378608D01*
X339742D01*
G01X313000Y383500D02*
X329100D01*
G01X313000Y376500D02*
Y383500D01*
G01X329100Y376500D02*
X313000D01*
G01X329100Y383500D02*
Y376500D01*
G01X300708Y381967D02*
X300583Y381717D01*
X300500Y381425D01*
Y381092D01*
X300625Y380717D01*
X300833Y380425D01*
X301083Y380217D01*
X301500Y380050D01*
X301875Y380008D01*
X302250Y380092D01*
X302500Y380217D01*
X302750Y380467D01*
X302917Y380758D01*
X303000Y381050D01*
Y381342D01*
X302917Y381633D01*
X302792Y381883D01*
X302625Y382092D01*
G01X302500Y383233D02*
X302792Y383483D01*
X302958Y383817D01*
X303000Y384192D01*
X302958Y384525D01*
X302750Y384858D01*
X302500Y385067D01*
X302250Y385108D01*
X301958Y385025D01*
X301750Y384733D01*
X301667Y384442D01*
Y384067D01*
G01Y384442D02*
X301542Y384692D01*
X301333Y384900D01*
X301083Y384983D01*
X300833Y384900D01*
X300625Y384692D01*
X300500Y384317D01*
X300542Y383942D01*
X300708Y383567D01*
G01X303000Y387250D02*
X302958Y387542D01*
X302833Y387875D01*
X302625Y388083D01*
X302333Y388167D01*
X302042Y388083D01*
X301792Y387833D01*
X301667Y387458D01*
Y387042D01*
X301583Y386792D01*
X301375Y386583D01*
X301083Y386500D01*
X300792Y386625D01*
X300583Y386917D01*
X300500Y387250D01*
X300583Y387583D01*
X300792Y387875D01*
X301083Y388000D01*
X301375Y387917D01*
X301583Y387708D01*
X301667Y387458D01*
Y387042D01*
X301792Y386667D01*
X302042Y386417D01*
X302333Y386333D01*
X302625Y386417D01*
X302833Y386625D01*
X302958Y386958D01*
X303000Y387250D01*
G01Y390350D02*
X302958Y390642D01*
X302833Y390975D01*
X302625Y391183D01*
X302333Y391267D01*
X302042Y391183D01*
X301792Y390933D01*
X301667Y390558D01*
Y390142D01*
X301583Y389892D01*
X301375Y389683D01*
X301083Y389600D01*
X300792Y389725D01*
X300583Y390017D01*
X300500Y390350D01*
X300583Y390683D01*
X300792Y390975D01*
X301083Y391100D01*
X301375Y391017D01*
X301583Y390808D01*
X301667Y390558D01*
Y390142D01*
X301792Y389767D01*
X302042Y389517D01*
X302333Y389433D01*
X302625Y389517D01*
X302833Y389725D01*
X302958Y390058D01*
X303000Y390350D01*
G01X289708Y325767D02*
X289583Y325517D01*
X289500Y325225D01*
Y324892D01*
X289625Y324517D01*
X289833Y324225D01*
X290083Y324017D01*
X290500Y323850D01*
X290875Y323808D01*
X291250Y323892D01*
X291500Y324017D01*
X291750Y324267D01*
X291917Y324558D01*
X292000Y324850D01*
Y325142D01*
X291917Y325433D01*
X291792Y325683D01*
X291625Y325892D01*
G01X289917Y327158D02*
X289667Y327408D01*
X289542Y327700D01*
X289500Y328033D01*
X289583Y328450D01*
X289792Y328742D01*
X290042Y328825D01*
X290292Y328783D01*
X290500Y328617D01*
X290917Y327783D01*
X291208Y327408D01*
X291625Y327158D01*
X292000Y327075D01*
Y328825D01*
G01Y331550D02*
X289500D01*
X291292Y330008D01*
Y332092D01*
G01X291625Y333233D02*
X291833Y333483D01*
X291958Y333775D01*
X292000Y334150D01*
X291917Y334525D01*
X291750Y334817D01*
X291458Y335025D01*
X291125Y335067D01*
X290792Y334983D01*
X290583Y334775D01*
X290417Y334483D01*
X290375Y334192D01*
X290417Y333900D01*
X290583Y333525D01*
X289500Y333650D01*
Y334775D01*
G01X312799Y349350D02*
X324199D01*
G01X312799Y362750D02*
Y349350D01*
G01X324199Y362750D02*
X312799D01*
G01X324199Y349350D02*
Y362750D01*
G01X298300Y380317D02*
X295800D01*
Y381358D01*
X295925Y381692D01*
X296092Y381900D01*
X296425Y381983D01*
X296758Y381900D01*
X296967Y381650D01*
X297092Y381358D01*
Y380317D01*
G01Y381358D02*
X298300Y381983D01*
G01X297925Y383333D02*
X298133Y383583D01*
X298258Y383875D01*
X298300Y384250D01*
X298217Y384625D01*
X298050Y384917D01*
X297758Y385125D01*
X297425Y385167D01*
X297092Y385083D01*
X296883Y384875D01*
X296717Y384583D01*
X296675Y384292D01*
X296717Y384000D01*
X296883Y383625D01*
X295800Y383750D01*
Y384875D01*
G01X298300Y387267D02*
X297758Y387350D01*
X297300Y387475D01*
X296883Y387642D01*
X296425Y387850D01*
X295800Y388183D01*
Y386517D01*
G01X296217Y389658D02*
X295967Y389908D01*
X295842Y390200D01*
X295800Y390533D01*
X295883Y390950D01*
X296092Y391242D01*
X296342Y391325D01*
X296592Y391283D01*
X296800Y391117D01*
X297217Y390283D01*
X297508Y389908D01*
X297925Y389658D01*
X298300Y389575D01*
Y391325D01*
G01X309000Y375700D02*
X305000D01*
Y368300D01*
G01X309000Y380717D02*
X306500D01*
Y381758D01*
X306625Y382092D01*
X306792Y382300D01*
X307125Y382383D01*
X307458Y382300D01*
X307667Y382050D01*
X307792Y381758D01*
Y380717D01*
G01Y381758D02*
X309000Y382383D01*
G01X308625Y383733D02*
X308833Y383983D01*
X308958Y384275D01*
X309000Y384650D01*
X308917Y385025D01*
X308750Y385317D01*
X308458Y385525D01*
X308125Y385567D01*
X307792Y385483D01*
X307583Y385275D01*
X307417Y384983D01*
X307375Y384692D01*
X307417Y384400D01*
X307583Y384025D01*
X306500Y384150D01*
Y385275D01*
G01X308625Y386833D02*
X308833Y387083D01*
X308958Y387375D01*
X309000Y387750D01*
X308917Y388125D01*
X308750Y388417D01*
X308458Y388625D01*
X308125Y388667D01*
X307792Y388583D01*
X307583Y388375D01*
X307417Y388083D01*
X307375Y387792D01*
X307417Y387500D01*
X307583Y387125D01*
X306500Y387250D01*
Y388375D01*
G01X309000Y390850D02*
X306500D01*
X307000Y390350D01*
G01X309000D02*
Y391350D01*
G01X313000Y368300D02*
X317000D01*
Y375700D01*
G01X299017Y319000D02*
Y321500D01*
X300058D01*
X300392Y321375D01*
X300600Y321208D01*
X300683Y320875D01*
X300600Y320542D01*
X300350Y320333D01*
X300058Y320208D01*
X299017D01*
G01X300058D02*
X300683Y319000D01*
G01X302158Y321083D02*
X302408Y321333D01*
X302700Y321458D01*
X303033Y321500D01*
X303450Y321417D01*
X303742Y321208D01*
X303825Y320958D01*
X303783Y320708D01*
X303617Y320500D01*
X302783Y320083D01*
X302408Y319792D01*
X302158Y319375D01*
X302075Y319000D01*
X303825D01*
G01X305133Y319500D02*
X305383Y319208D01*
X305717Y319042D01*
X306092Y319000D01*
X306425Y319042D01*
X306758Y319250D01*
X306967Y319500D01*
X307008Y319750D01*
X306925Y320042D01*
X306633Y320250D01*
X306342Y320333D01*
X305967D01*
G01X306342D02*
X306592Y320458D01*
X306800Y320667D01*
X306883Y320917D01*
X306800Y321167D01*
X306592Y321375D01*
X306217Y321500D01*
X305842Y321458D01*
X305467Y321292D01*
G01X309150Y319000D02*
Y321500D01*
X308650Y321000D01*
G01Y319000D02*
X309650D01*
G01X310699Y332050D02*
Y336050D01*
X303299D01*
G01X332316Y355650D02*
Y358150D01*
X333357D01*
X333691Y358025D01*
X333899Y357858D01*
X333982Y357525D01*
X333899Y357192D01*
X333649Y356983D01*
X333357Y356858D01*
X332316D01*
G01X333357D02*
X333982Y355650D01*
G01X335457Y357733D02*
X335707Y357983D01*
X335999Y358108D01*
X336332Y358150D01*
X336749Y358067D01*
X337041Y357858D01*
X337124Y357608D01*
X337082Y357358D01*
X336916Y357150D01*
X336082Y356733D01*
X335707Y356442D01*
X335457Y356025D01*
X335374Y355650D01*
X337124D01*
G01X338432Y356150D02*
X338682Y355858D01*
X339016Y355692D01*
X339391Y355650D01*
X339724Y355692D01*
X340057Y355900D01*
X340266Y356150D01*
X340307Y356400D01*
X340224Y356692D01*
X339932Y356900D01*
X339641Y356983D01*
X339266D01*
G01X339641D02*
X339891Y357108D01*
X340099Y357317D01*
X340182Y357567D01*
X340099Y357817D01*
X339891Y358025D01*
X339516Y358150D01*
X339141Y358108D01*
X338766Y357942D01*
G01X341657Y357733D02*
X341907Y357983D01*
X342199Y358108D01*
X342532Y358150D01*
X342949Y358067D01*
X343241Y357858D01*
X343324Y357608D01*
X343282Y357358D01*
X343116Y357150D01*
X342282Y356733D01*
X341907Y356442D01*
X341657Y356025D01*
X341574Y355650D01*
X343324D01*
G01X304799Y362050D02*
Y358050D01*
X312199D01*
G01X332517Y351600D02*
Y354100D01*
X333558D01*
X333892Y353975D01*
X334100Y353808D01*
X334183Y353475D01*
X334100Y353142D01*
X333850Y352933D01*
X333558Y352808D01*
X332517D01*
G01X333558D02*
X334183Y351600D01*
G01X335658Y353683D02*
X335908Y353933D01*
X336200Y354058D01*
X336533Y354100D01*
X336950Y354017D01*
X337242Y353808D01*
X337325Y353558D01*
X337283Y353308D01*
X337117Y353100D01*
X336283Y352683D01*
X335908Y352392D01*
X335658Y351975D01*
X335575Y351600D01*
X337325D01*
G01X338633Y352100D02*
X338883Y351808D01*
X339217Y351642D01*
X339592Y351600D01*
X339925Y351642D01*
X340258Y351850D01*
X340467Y352100D01*
X340508Y352350D01*
X340425Y352642D01*
X340133Y352850D01*
X339842Y352933D01*
X339467D01*
G01X339842D02*
X340092Y353058D01*
X340300Y353267D01*
X340383Y353517D01*
X340300Y353767D01*
X340092Y353975D01*
X339717Y354100D01*
X339342Y354058D01*
X338967Y353892D01*
G01X341733Y352100D02*
X341983Y351808D01*
X342317Y351642D01*
X342692Y351600D01*
X343025Y351642D01*
X343358Y351850D01*
X343567Y352100D01*
X343608Y352350D01*
X343525Y352642D01*
X343233Y352850D01*
X342942Y352933D01*
X342567D01*
G01X342942D02*
X343192Y353058D01*
X343400Y353267D01*
X343483Y353517D01*
X343400Y353767D01*
X343192Y353975D01*
X342817Y354100D01*
X342442Y354058D01*
X342067Y353892D01*
G01X304799Y358050D02*
Y354050D01*
X312199D01*
G01X299163Y327394D02*
Y329894D01*
X300204D01*
X300538Y329769D01*
X300746Y329602D01*
X300829Y329269D01*
X300746Y328936D01*
X300496Y328727D01*
X300204Y328602D01*
X299163D01*
G01X300204D02*
X300829Y327394D01*
G01X302304Y329477D02*
X302554Y329727D01*
X302846Y329852D01*
X303179Y329894D01*
X303596Y329811D01*
X303888Y329602D01*
X303971Y329352D01*
X303929Y329102D01*
X303763Y328894D01*
X302929Y328477D01*
X302554Y328186D01*
X302304Y327769D01*
X302221Y327394D01*
X303971D01*
G01X305279Y327894D02*
X305529Y327602D01*
X305863Y327436D01*
X306238Y327394D01*
X306571Y327436D01*
X306904Y327644D01*
X307113Y327894D01*
X307154Y328144D01*
X307071Y328436D01*
X306779Y328644D01*
X306488Y328727D01*
X306113D01*
G01X306488D02*
X306738Y328852D01*
X306946Y329061D01*
X307029Y329311D01*
X306946Y329561D01*
X306738Y329769D01*
X306363Y329894D01*
X305988Y329852D01*
X305613Y329686D01*
G01X309296Y327394D02*
X309588Y327436D01*
X309921Y327561D01*
X310129Y327769D01*
X310213Y328061D01*
X310129Y328352D01*
X309879Y328602D01*
X309504Y328727D01*
X309088D01*
X308838Y328811D01*
X308629Y329019D01*
X308546Y329311D01*
X308671Y329602D01*
X308963Y329811D01*
X309296Y329894D01*
X309629Y329811D01*
X309921Y329602D01*
X310046Y329311D01*
X309963Y329019D01*
X309754Y328811D01*
X309504Y328727D01*
X309088D01*
X308713Y328602D01*
X308463Y328352D01*
X308379Y328061D01*
X308463Y327769D01*
X308671Y327561D01*
X309004Y327436D01*
X309296Y327394D01*
G01X303299Y345550D02*
Y341550D01*
X310699D01*
G01X299163Y323394D02*
Y325894D01*
X300204D01*
X300538Y325769D01*
X300746Y325602D01*
X300829Y325269D01*
X300746Y324936D01*
X300496Y324727D01*
X300204Y324602D01*
X299163D01*
G01X300204D02*
X300829Y323394D01*
G01X302304Y325477D02*
X302554Y325727D01*
X302846Y325852D01*
X303179Y325894D01*
X303596Y325811D01*
X303888Y325602D01*
X303971Y325352D01*
X303929Y325102D01*
X303763Y324894D01*
X302929Y324477D01*
X302554Y324186D01*
X302304Y323769D01*
X302221Y323394D01*
X303971D01*
G01X305279Y323894D02*
X305529Y323602D01*
X305863Y323436D01*
X306238Y323394D01*
X306571Y323436D01*
X306904Y323644D01*
X307113Y323894D01*
X307154Y324144D01*
X307071Y324436D01*
X306779Y324644D01*
X306488Y324727D01*
X306113D01*
G01X306488D02*
X306738Y324852D01*
X306946Y325061D01*
X307029Y325311D01*
X306946Y325561D01*
X306738Y325769D01*
X306363Y325894D01*
X305988Y325852D01*
X305613Y325686D01*
G01X308588Y323686D02*
X308879Y323477D01*
X309213Y323394D01*
X309546Y323477D01*
X309838Y323727D01*
X310046Y324102D01*
X310129Y324477D01*
Y324936D01*
X310046Y325311D01*
X309838Y325644D01*
X309588Y325811D01*
X309296Y325894D01*
X308963Y325811D01*
X308713Y325644D01*
X308546Y325394D01*
X308463Y325061D01*
X308546Y324769D01*
X308754Y324477D01*
X309004Y324311D01*
X309296Y324269D01*
X309629Y324352D01*
X309879Y324561D01*
X310129Y324936D01*
G01X310699Y337050D02*
Y341050D01*
X303299D01*
G01X269300Y340617D02*
X266800D01*
Y341658D01*
X266925Y341992D01*
X267092Y342200D01*
X267425Y342283D01*
X267758Y342200D01*
X267967Y341950D01*
X268092Y341658D01*
Y340617D01*
G01Y341658D02*
X269300Y342283D01*
G01Y345050D02*
X266800D01*
X268592Y343508D01*
Y345592D01*
G01X268925Y346733D02*
X269133Y346983D01*
X269258Y347275D01*
X269300Y347650D01*
X269217Y348025D01*
X269050Y348317D01*
X268758Y348525D01*
X268425Y348567D01*
X268092Y348483D01*
X267883Y348275D01*
X267717Y347983D01*
X267675Y347692D01*
X267717Y347400D01*
X267883Y347025D01*
X266800Y347150D01*
Y348275D01*
G01X268258Y349958D02*
X267967Y350250D01*
X267800Y350500D01*
X267717Y350833D01*
X267800Y351125D01*
X267967Y351333D01*
X268217Y351500D01*
X268508Y351542D01*
X268758Y351500D01*
X269008Y351333D01*
X269217Y351083D01*
X269300Y350792D01*
X269217Y350458D01*
X268967Y350167D01*
X268592Y350000D01*
X268175Y349958D01*
X267633Y350042D01*
X267342Y350167D01*
X267050Y350375D01*
X266842Y350667D01*
X266800Y350958D01*
X266883Y351250D01*
X267092Y351458D01*
G01X282499Y347250D02*
X278499D01*
Y339850D01*
G01X273700Y340617D02*
X271200D01*
Y341658D01*
X271325Y341992D01*
X271492Y342200D01*
X271825Y342283D01*
X272158Y342200D01*
X272367Y341950D01*
X272492Y341658D01*
Y340617D01*
G01Y341658D02*
X273700Y342283D01*
G01Y345050D02*
X271200D01*
X272992Y343508D01*
Y345592D01*
G01X273325Y346733D02*
X273533Y346983D01*
X273658Y347275D01*
X273700Y347650D01*
X273617Y348025D01*
X273450Y348317D01*
X273158Y348525D01*
X272825Y348567D01*
X272492Y348483D01*
X272283Y348275D01*
X272117Y347983D01*
X272075Y347692D01*
X272117Y347400D01*
X272283Y347025D01*
X271200Y347150D01*
Y348275D01*
G01X273700Y350667D02*
X273158Y350750D01*
X272700Y350875D01*
X272283Y351042D01*
X271825Y351250D01*
X271200Y351583D01*
Y349917D01*
G01X286999Y347250D02*
X282999D01*
Y339850D01*
G01X337515Y336114D02*
Y338614D01*
X338556D01*
X338890Y338489D01*
X339098Y338322D01*
X339181Y337989D01*
X339098Y337656D01*
X338848Y337447D01*
X338556Y337322D01*
X337515D01*
G01X338556D02*
X339181Y336114D01*
G01X341948D02*
Y338614D01*
X340406Y336822D01*
X342490D01*
G01X343631Y336489D02*
X343881Y336281D01*
X344173Y336156D01*
X344548Y336114D01*
X344923Y336197D01*
X345215Y336364D01*
X345423Y336656D01*
X345465Y336989D01*
X345381Y337322D01*
X345173Y337531D01*
X344881Y337697D01*
X344590Y337739D01*
X344298Y337697D01*
X343923Y337531D01*
X344048Y338614D01*
X345173D01*
G01X347648Y336114D02*
X347940Y336156D01*
X348273Y336281D01*
X348481Y336489D01*
X348565Y336781D01*
X348481Y337072D01*
X348231Y337322D01*
X347856Y337447D01*
X347440D01*
X347190Y337531D01*
X346981Y337739D01*
X346898Y338031D01*
X347023Y338322D01*
X347315Y338531D01*
X347648Y338614D01*
X347981Y338531D01*
X348273Y338322D01*
X348398Y338031D01*
X348315Y337739D01*
X348106Y337531D01*
X347856Y337447D01*
X347440D01*
X347065Y337322D01*
X346815Y337072D01*
X346731Y336781D01*
X346815Y336489D01*
X347023Y336281D01*
X347356Y336156D01*
X347648Y336114D01*
G01X335198Y335114D02*
Y339114D01*
X327798D01*
G01X337515Y332114D02*
Y334614D01*
X338556D01*
X338890Y334489D01*
X339098Y334322D01*
X339181Y333989D01*
X339098Y333656D01*
X338848Y333447D01*
X338556Y333322D01*
X337515D01*
G01X338556D02*
X339181Y332114D01*
G01X341948D02*
Y334614D01*
X340406Y332822D01*
X342490D01*
G01X343631Y332489D02*
X343881Y332281D01*
X344173Y332156D01*
X344548Y332114D01*
X344923Y332197D01*
X345215Y332364D01*
X345423Y332656D01*
X345465Y332989D01*
X345381Y333322D01*
X345173Y333531D01*
X344881Y333697D01*
X344590Y333739D01*
X344298Y333697D01*
X343923Y333531D01*
X344048Y334614D01*
X345173D01*
G01X346940Y332406D02*
X347231Y332197D01*
X347565Y332114D01*
X347898Y332197D01*
X348190Y332447D01*
X348398Y332822D01*
X348481Y333197D01*
Y333656D01*
X348398Y334031D01*
X348190Y334364D01*
X347940Y334531D01*
X347648Y334614D01*
X347315Y334531D01*
X347065Y334364D01*
X346898Y334114D01*
X346815Y333781D01*
X346898Y333489D01*
X347106Y333197D01*
X347356Y333031D01*
X347648Y332989D01*
X347981Y333072D01*
X348231Y333281D01*
X348481Y333656D01*
G01X335198Y331114D02*
Y335114D01*
X327798D01*
G01X329517Y364000D02*
Y366500D01*
X330558D01*
X330892Y366375D01*
X331100Y366208D01*
X331183Y365875D01*
X331100Y365542D01*
X330850Y365333D01*
X330558Y365208D01*
X329517D01*
G01X330558D02*
X331183Y364000D01*
G01X333950D02*
Y366500D01*
X332408Y364708D01*
X334492D01*
G01X336550Y364000D02*
Y366500D01*
X336050Y366000D01*
G01Y364000D02*
X337050D01*
G01X339567D02*
X339650Y364542D01*
X339775Y365000D01*
X339942Y365417D01*
X340150Y365875D01*
X340483Y366500D01*
X338817D01*
G01X320400Y363200D02*
Y367200D01*
X313000D01*
G01X264283Y334000D02*
Y332208D01*
X264450Y331833D01*
X264783Y331583D01*
X265200Y331500D01*
X265617Y331583D01*
X265950Y331833D01*
X266117Y332208D01*
Y334000D01*
G01X267508Y333583D02*
X267758Y333833D01*
X268050Y333958D01*
X268383Y334000D01*
X268800Y333917D01*
X269092Y333708D01*
X269175Y333458D01*
X269133Y333208D01*
X268967Y333000D01*
X268133Y332583D01*
X267758Y332292D01*
X267508Y331875D01*
X267425Y331500D01*
X269175D01*
G01X271400D02*
X271692Y331542D01*
X272025Y331667D01*
X272233Y331875D01*
X272317Y332167D01*
X272233Y332458D01*
X271983Y332708D01*
X271608Y332833D01*
X271192D01*
X270942Y332917D01*
X270733Y333125D01*
X270650Y333417D01*
X270775Y333708D01*
X271067Y333917D01*
X271400Y334000D01*
X271733Y333917D01*
X272025Y333708D01*
X272150Y333417D01*
X272067Y333125D01*
X271858Y332917D01*
X271608Y332833D01*
X271192D01*
X270817Y332708D01*
X270567Y332458D01*
X270483Y332167D01*
X270567Y331875D01*
X270775Y331667D01*
X271108Y331542D01*
X271400Y331500D01*
G01X276499Y323850D02*
Y337250D01*
G01X286499Y323850D02*
X276499D01*
G01X286499Y337250D02*
Y323850D01*
G01X276499Y337250D02*
X286499D01*
G01X326983Y344500D02*
Y342708D01*
X327150Y342333D01*
X327483Y342083D01*
X327900Y342000D01*
X328317Y342083D01*
X328650Y342333D01*
X328817Y342708D01*
Y344500D01*
G01X330083Y342500D02*
X330333Y342208D01*
X330667Y342042D01*
X331042Y342000D01*
X331375Y342042D01*
X331708Y342250D01*
X331917Y342500D01*
X331958Y342750D01*
X331875Y343042D01*
X331583Y343250D01*
X331292Y343333D01*
X330917D01*
G01X331292D02*
X331542Y343458D01*
X331750Y343667D01*
X331833Y343917D01*
X331750Y344167D01*
X331542Y344375D01*
X331167Y344500D01*
X330792Y344458D01*
X330417Y344292D01*
G01X334100Y344500D02*
X333767Y344417D01*
X333517Y344208D01*
X333350Y343958D01*
X333225Y343625D01*
X333183Y343250D01*
X333225Y342875D01*
X333350Y342542D01*
X333517Y342292D01*
X333767Y342083D01*
X334100Y342000D01*
X334433Y342083D01*
X334683Y342292D01*
X334850Y342542D01*
X334975Y342875D01*
X335017Y343250D01*
X334975Y343625D01*
X334850Y343958D01*
X334683Y344208D01*
X334433Y344417D01*
X334100Y344500D01*
G01X311798Y341614D02*
X325198D01*
G01X311798Y331614D02*
Y341614D01*
G01X325198Y331614D02*
X311798D01*
G01X325198Y341614D02*
Y331614D01*
G01X287482Y375050D02*
Y373258D01*
X287649Y372883D01*
X287982Y372633D01*
X288399Y372550D01*
X288816Y372633D01*
X289149Y372883D01*
X289316Y373258D01*
Y375050D01*
G01X290707Y374633D02*
X290957Y374883D01*
X291249Y375008D01*
X291582Y375050D01*
X291999Y374967D01*
X292291Y374758D01*
X292374Y374508D01*
X292332Y374258D01*
X292166Y374050D01*
X291332Y373633D01*
X290957Y373342D01*
X290707Y372925D01*
X290624Y372550D01*
X292374D01*
G01X293891Y372842D02*
X294182Y372633D01*
X294516Y372550D01*
X294849Y372633D01*
X295141Y372883D01*
X295349Y373258D01*
X295432Y373633D01*
Y374092D01*
X295349Y374467D01*
X295141Y374800D01*
X294891Y374967D01*
X294599Y375050D01*
X294266Y374967D01*
X294016Y374800D01*
X293849Y374550D01*
X293766Y374217D01*
X293849Y373925D01*
X294057Y373633D01*
X294307Y373467D01*
X294599Y373425D01*
X294932Y373508D01*
X295182Y373717D01*
X295432Y374092D01*
G01X287999Y347750D02*
X289999Y349750D01*
X291999Y347750D01*
G01X295599D02*
Y366950D01*
X284399D01*
Y347750D01*
X295599D01*
G01X282350Y319600D02*
Y317100D01*
G01X281392Y319600D02*
X283308D01*
G01X284617Y317100D02*
Y319600D01*
X285617D01*
X285950Y319475D01*
X286200Y319183D01*
X286283Y318850D01*
X286200Y318517D01*
X285992Y318267D01*
X285617Y318142D01*
X284617D01*
G01X287633Y317600D02*
X287883Y317308D01*
X288217Y317142D01*
X288592Y317100D01*
X288925Y317142D01*
X289258Y317350D01*
X289467Y317600D01*
X289508Y317850D01*
X289425Y318142D01*
X289133Y318350D01*
X288842Y318433D01*
X288467D01*
G01X288842D02*
X289092Y318558D01*
X289300Y318767D01*
X289383Y319017D01*
X289300Y319267D01*
X289092Y319475D01*
X288717Y319600D01*
X288342Y319558D01*
X287967Y319392D01*
G01X292150Y317100D02*
Y319600D01*
X290608Y317808D01*
X292692D01*
G01X312208Y721767D02*
X312083Y721517D01*
X312000Y721225D01*
Y720892D01*
X312125Y720517D01*
X312333Y720225D01*
X312583Y720017D01*
X313000Y719850D01*
X313375Y719808D01*
X313750Y719892D01*
X314000Y720017D01*
X314250Y720267D01*
X314417Y720558D01*
X314500Y720850D01*
Y721142D01*
X314417Y721433D01*
X314292Y721683D01*
X314125Y721892D01*
G01X312417Y723158D02*
X312167Y723408D01*
X312042Y723700D01*
X312000Y724033D01*
X312083Y724450D01*
X312292Y724742D01*
X312542Y724825D01*
X312792Y724783D01*
X313000Y724617D01*
X313417Y723783D01*
X313708Y723408D01*
X314125Y723158D01*
X314500Y723075D01*
Y724825D01*
G01X314000Y726133D02*
X314292Y726383D01*
X314458Y726717D01*
X314500Y727092D01*
X314458Y727425D01*
X314250Y727758D01*
X314000Y727967D01*
X313750Y728008D01*
X313458Y727925D01*
X313250Y727633D01*
X313167Y727342D01*
Y726967D01*
G01Y727342D02*
X313042Y727592D01*
X312833Y727800D01*
X312583Y727883D01*
X312333Y727800D01*
X312125Y727592D01*
X312000Y727217D01*
X312042Y726842D01*
X312208Y726467D01*
G01X314125Y729233D02*
X314333Y729483D01*
X314458Y729775D01*
X314500Y730150D01*
X314417Y730525D01*
X314250Y730817D01*
X313958Y731025D01*
X313625Y731067D01*
X313292Y730983D01*
X313083Y730775D01*
X312917Y730483D01*
X312875Y730192D01*
X312917Y729900D01*
X313083Y729525D01*
X312000Y729650D01*
Y730775D01*
G01X263399Y722050D02*
X263066Y722092D01*
X262774Y722258D01*
X262524Y722508D01*
X262357Y722800D01*
X262274Y723133D01*
Y723467D01*
X262357Y723800D01*
X262524Y724092D01*
X262774Y724342D01*
X263066Y724508D01*
X263399Y724550D01*
X263732Y724508D01*
X264024Y724342D01*
X264274Y724092D01*
X264441Y723800D01*
X264524Y723467D01*
Y723133D01*
X264441Y722800D01*
X264274Y722508D01*
X264024Y722258D01*
X263732Y722092D01*
X263399Y722050D01*
G01X263732Y722717D02*
X264232Y722050D01*
G01X266499D02*
Y724550D01*
X265999Y724050D01*
G01Y722050D02*
X266999D01*
G01X269516D02*
X269599Y722592D01*
X269724Y723050D01*
X269891Y723467D01*
X270099Y723925D01*
X270432Y724550D01*
X268766D01*
G01X266499Y719750D02*
X264699Y717650D01*
X262499Y719750D01*
G01X289999Y707067D02*
X287499D01*
Y708108D01*
X287624Y708442D01*
X287791Y708650D01*
X288124Y708733D01*
X288457Y708650D01*
X288666Y708400D01*
X288791Y708108D01*
Y707067D01*
G01Y708108D02*
X289999Y708733D01*
G01Y711500D02*
X287499D01*
X289291Y709958D01*
Y712042D01*
G01X289624Y713183D02*
X289832Y713433D01*
X289957Y713725D01*
X289999Y714100D01*
X289916Y714475D01*
X289749Y714767D01*
X289457Y714975D01*
X289124Y715017D01*
X288791Y714933D01*
X288582Y714725D01*
X288416Y714433D01*
X288374Y714142D01*
X288416Y713850D01*
X288582Y713475D01*
X287499Y713600D01*
Y714725D01*
G01X287916Y716408D02*
X287666Y716658D01*
X287541Y716950D01*
X287499Y717283D01*
X287582Y717700D01*
X287791Y717992D01*
X288041Y718075D01*
X288291Y718033D01*
X288499Y717867D01*
X288916Y717033D01*
X289207Y716658D01*
X289624Y716408D01*
X289999Y716325D01*
Y718075D01*
G01X293999Y707067D02*
X291499D01*
Y708108D01*
X291624Y708442D01*
X291791Y708650D01*
X292124Y708733D01*
X292457Y708650D01*
X292666Y708400D01*
X292791Y708108D01*
Y707067D01*
G01Y708108D02*
X293999Y708733D01*
G01Y711500D02*
X291499D01*
X293291Y709958D01*
Y712042D01*
G01X293624Y713183D02*
X293832Y713433D01*
X293957Y713725D01*
X293999Y714100D01*
X293916Y714475D01*
X293749Y714767D01*
X293457Y714975D01*
X293124Y715017D01*
X292791Y714933D01*
X292582Y714725D01*
X292416Y714433D01*
X292374Y714142D01*
X292416Y713850D01*
X292582Y713475D01*
X291499Y713600D01*
Y714725D01*
G01X293499Y716283D02*
X293791Y716533D01*
X293957Y716867D01*
X293999Y717242D01*
X293957Y717575D01*
X293749Y717908D01*
X293499Y718117D01*
X293249Y718158D01*
X292957Y718075D01*
X292749Y717783D01*
X292666Y717492D01*
Y717117D01*
G01Y717492D02*
X292541Y717742D01*
X292332Y717950D01*
X292082Y718033D01*
X291832Y717950D01*
X291624Y717742D01*
X291499Y717367D01*
X291541Y716992D01*
X291707Y716617D01*
G01X284482Y704550D02*
Y702758D01*
X284649Y702383D01*
X284982Y702133D01*
X285399Y702050D01*
X285816Y702133D01*
X286149Y702383D01*
X286316Y702758D01*
Y704550D01*
G01X287707Y704133D02*
X287957Y704383D01*
X288249Y704508D01*
X288582Y704550D01*
X288999Y704467D01*
X289291Y704258D01*
X289374Y704008D01*
X289332Y703758D01*
X289166Y703550D01*
X288332Y703133D01*
X287957Y702842D01*
X287707Y702425D01*
X287624Y702050D01*
X289374D01*
G01X290682Y702425D02*
X290932Y702217D01*
X291224Y702092D01*
X291599Y702050D01*
X291974Y702133D01*
X292266Y702300D01*
X292474Y702592D01*
X292516Y702925D01*
X292432Y703258D01*
X292224Y703467D01*
X291932Y703633D01*
X291641Y703675D01*
X291349Y703633D01*
X290974Y703467D01*
X291099Y704550D01*
X292224D01*
G01X282000Y714350D02*
X284500D01*
G01X282000Y713392D02*
Y715308D01*
G01X284500Y716617D02*
X282000D01*
Y717617D01*
X282125Y717950D01*
X282417Y718200D01*
X282750Y718283D01*
X283083Y718200D01*
X283333Y717992D01*
X283458Y717617D01*
Y716617D01*
G01X284000Y719633D02*
X284292Y719883D01*
X284458Y720217D01*
X284500Y720592D01*
X284458Y720925D01*
X284250Y721258D01*
X284000Y721467D01*
X283750Y721508D01*
X283458Y721425D01*
X283250Y721133D01*
X283167Y720842D01*
Y720467D01*
G01Y720842D02*
X283042Y721092D01*
X282833Y721300D01*
X282583Y721383D01*
X282333Y721300D01*
X282125Y721092D01*
X282000Y720717D01*
X282042Y720342D01*
X282208Y719967D01*
G01X284000Y722733D02*
X284292Y722983D01*
X284458Y723317D01*
X284500Y723692D01*
X284458Y724025D01*
X284250Y724358D01*
X284000Y724567D01*
X283750Y724608D01*
X283458Y724525D01*
X283250Y724233D01*
X283167Y723942D01*
Y723567D01*
G01Y723942D02*
X283042Y724192D01*
X282833Y724400D01*
X282583Y724483D01*
X282333Y724400D01*
X282125Y724192D01*
X282000Y723817D01*
X282042Y723442D01*
X282208Y723067D01*
G01X269227Y695228D02*
Y697728D01*
G01X270977D02*
Y695228D01*
G01Y696478D02*
X269227D01*
G01X273702Y695228D02*
Y697728D01*
X272160Y695936D01*
X274244D01*
G01X309983Y795500D02*
Y798000D01*
X310817D01*
X311150Y797875D01*
X311400Y797708D01*
X311608Y797458D01*
X311775Y797167D01*
X311817Y796750D01*
X311775Y796333D01*
X311608Y796042D01*
X311400Y795792D01*
X311150Y795625D01*
X310817Y795500D01*
X309983D01*
G01X313208Y797583D02*
X313458Y797833D01*
X313750Y797958D01*
X314083Y798000D01*
X314500Y797917D01*
X314792Y797708D01*
X314875Y797458D01*
X314833Y797208D01*
X314667Y797000D01*
X313833Y796583D01*
X313458Y796292D01*
X313208Y795875D01*
X313125Y795500D01*
X314875D01*
G01X316183Y796000D02*
X316433Y795708D01*
X316767Y795542D01*
X317142Y795500D01*
X317475Y795542D01*
X317808Y795750D01*
X318017Y796000D01*
X318058Y796250D01*
X317975Y796542D01*
X317683Y796750D01*
X317392Y796833D01*
X317017D01*
G01X317392D02*
X317642Y796958D01*
X317850Y797167D01*
X317933Y797417D01*
X317850Y797667D01*
X317642Y797875D01*
X317267Y798000D01*
X316892Y797958D01*
X316517Y797792D01*
G01X306500Y789000D02*
X322600D01*
G01X306500Y782000D02*
Y789000D01*
G01X322600Y782000D02*
X306500D01*
G01X322600Y789000D02*
Y782000D01*
G01X329767Y755792D02*
X329517Y755917D01*
X329225Y756000D01*
X328892D01*
X328517Y755875D01*
X328225Y755667D01*
X328017Y755417D01*
X327850Y755000D01*
X327808Y754625D01*
X327892Y754250D01*
X328017Y754000D01*
X328267Y753750D01*
X328558Y753583D01*
X328850Y753500D01*
X329142D01*
X329433Y753583D01*
X329683Y753708D01*
X329892Y753875D01*
G01X331033Y754000D02*
X331283Y753708D01*
X331617Y753542D01*
X331992Y753500D01*
X332325Y753542D01*
X332658Y753750D01*
X332867Y754000D01*
X332908Y754250D01*
X332825Y754542D01*
X332533Y754750D01*
X332242Y754833D01*
X331867D01*
G01X332242D02*
X332492Y754958D01*
X332700Y755167D01*
X332783Y755417D01*
X332700Y755667D01*
X332492Y755875D01*
X332117Y756000D01*
X331742Y755958D01*
X331367Y755792D01*
G01X334967Y753500D02*
X335050Y754042D01*
X335175Y754500D01*
X335342Y754917D01*
X335550Y755375D01*
X335883Y756000D01*
X334217D01*
G01X337358Y755583D02*
X337608Y755833D01*
X337900Y755958D01*
X338233Y756000D01*
X338650Y755917D01*
X338942Y755708D01*
X339025Y755458D01*
X338983Y755208D01*
X338817Y755000D01*
X337983Y754583D01*
X337608Y754292D01*
X337358Y753875D01*
X337275Y753500D01*
X339025D01*
G01X327208Y773767D02*
X327083Y773517D01*
X327000Y773225D01*
Y772892D01*
X327125Y772517D01*
X327333Y772225D01*
X327583Y772017D01*
X328000Y771850D01*
X328375Y771808D01*
X328750Y771892D01*
X329000Y772017D01*
X329250Y772267D01*
X329417Y772558D01*
X329500Y772850D01*
Y773142D01*
X329417Y773433D01*
X329292Y773683D01*
X329125Y773892D01*
G01X329000Y775033D02*
X329292Y775283D01*
X329458Y775617D01*
X329500Y775992D01*
X329458Y776325D01*
X329250Y776658D01*
X329000Y776867D01*
X328750Y776908D01*
X328458Y776825D01*
X328250Y776533D01*
X328167Y776242D01*
Y775867D01*
G01Y776242D02*
X328042Y776492D01*
X327833Y776700D01*
X327583Y776783D01*
X327333Y776700D01*
X327125Y776492D01*
X327000Y776117D01*
X327042Y775742D01*
X327208Y775367D01*
G01X329500Y779050D02*
X329458Y779342D01*
X329333Y779675D01*
X329125Y779883D01*
X328833Y779967D01*
X328542Y779883D01*
X328292Y779633D01*
X328167Y779258D01*
Y778842D01*
X328083Y778592D01*
X327875Y778383D01*
X327583Y778300D01*
X327292Y778425D01*
X327083Y778717D01*
X327000Y779050D01*
X327083Y779383D01*
X327292Y779675D01*
X327583Y779800D01*
X327875Y779717D01*
X328083Y779508D01*
X328167Y779258D01*
Y778842D01*
X328292Y778467D01*
X328542Y778217D01*
X328833Y778133D01*
X329125Y778217D01*
X329333Y778425D01*
X329458Y778758D01*
X329500Y779050D01*
G01Y782067D02*
X328958Y782150D01*
X328500Y782275D01*
X328083Y782442D01*
X327625Y782650D01*
X327000Y782983D01*
Y781317D01*
G01X292708Y732267D02*
X292583Y732017D01*
X292500Y731725D01*
Y731392D01*
X292625Y731017D01*
X292833Y730725D01*
X293083Y730517D01*
X293500Y730350D01*
X293875Y730308D01*
X294250Y730392D01*
X294500Y730517D01*
X294750Y730767D01*
X294917Y731058D01*
X295000Y731350D01*
Y731642D01*
X294917Y731933D01*
X294792Y732183D01*
X294625Y732392D01*
G01X292917Y733658D02*
X292667Y733908D01*
X292542Y734200D01*
X292500Y734533D01*
X292583Y734950D01*
X292792Y735242D01*
X293042Y735325D01*
X293292Y735283D01*
X293500Y735117D01*
X293917Y734283D01*
X294208Y733908D01*
X294625Y733658D01*
X295000Y733575D01*
Y735325D01*
G01X292917Y736758D02*
X292667Y737008D01*
X292542Y737300D01*
X292500Y737633D01*
X292583Y738050D01*
X292792Y738342D01*
X293042Y738425D01*
X293292Y738383D01*
X293500Y738217D01*
X293917Y737383D01*
X294208Y737008D01*
X294625Y736758D01*
X295000Y736675D01*
Y738425D01*
G01X294708Y739942D02*
X294917Y740233D01*
X295000Y740567D01*
X294917Y740900D01*
X294667Y741192D01*
X294292Y741400D01*
X293917Y741483D01*
X293458D01*
X293083Y741400D01*
X292750Y741192D01*
X292583Y740942D01*
X292500Y740650D01*
X292583Y740317D01*
X292750Y740067D01*
X293000Y739900D01*
X293333Y739817D01*
X293625Y739900D01*
X293917Y740108D01*
X294083Y740358D01*
X294125Y740650D01*
X294042Y740983D01*
X293833Y741233D01*
X293458Y741483D01*
G01X338500Y758900D02*
X338458Y758567D01*
X338292Y758275D01*
X338042Y758025D01*
X337750Y757858D01*
X337417Y757775D01*
X337083D01*
X336750Y757858D01*
X336458Y758025D01*
X336208Y758275D01*
X336042Y758567D01*
X336000Y758900D01*
X336042Y759233D01*
X336208Y759525D01*
X336458Y759775D01*
X336750Y759942D01*
X337083Y760025D01*
X337417D01*
X337750Y759942D01*
X338042Y759775D01*
X338292Y759525D01*
X338458Y759233D01*
X338500Y758900D01*
G01X337833Y759233D02*
X338500Y759733D01*
G01Y762000D02*
X336000D01*
X336500Y761500D01*
G01X338500D02*
Y762500D01*
G01Y765100D02*
X338458Y765392D01*
X338333Y765725D01*
X338125Y765933D01*
X337833Y766017D01*
X337542Y765933D01*
X337292Y765683D01*
X337167Y765308D01*
Y764892D01*
X337083Y764642D01*
X336875Y764433D01*
X336583Y764350D01*
X336292Y764475D01*
X336083Y764767D01*
X336000Y765100D01*
X336083Y765433D01*
X336292Y765725D01*
X336583Y765850D01*
X336875Y765767D01*
X337083Y765558D01*
X337167Y765308D01*
Y764892D01*
X337292Y764517D01*
X337542Y764267D01*
X337833Y764183D01*
X338125Y764267D01*
X338333Y764475D01*
X338458Y764808D01*
X338500Y765100D01*
G01X313799Y756350D02*
X325199D01*
G01X313799Y769750D02*
Y756350D01*
G01X325199Y769750D02*
X313799D01*
G01X325199Y756350D02*
Y769750D01*
G01X333900Y772517D02*
X331400D01*
Y773558D01*
X331525Y773892D01*
X331692Y774100D01*
X332025Y774183D01*
X332358Y774100D01*
X332567Y773850D01*
X332692Y773558D01*
Y772517D01*
G01Y773558D02*
X333900Y774183D01*
G01X333525Y775533D02*
X333733Y775783D01*
X333858Y776075D01*
X333900Y776450D01*
X333817Y776825D01*
X333650Y777117D01*
X333358Y777325D01*
X333025Y777367D01*
X332692Y777283D01*
X332483Y777075D01*
X332317Y776783D01*
X332275Y776492D01*
X332317Y776200D01*
X332483Y775825D01*
X331400Y775950D01*
Y777075D01*
G01X333900Y779467D02*
X333358Y779550D01*
X332900Y779675D01*
X332483Y779842D01*
X332025Y780050D01*
X331400Y780383D01*
Y778717D01*
G01X333900Y782650D02*
X331400D01*
X331900Y782150D01*
G01X333900D02*
Y783150D01*
G01X313000Y776700D02*
X309000D01*
Y769300D01*
G01X308917Y790700D02*
Y793200D01*
X309958D01*
X310292Y793075D01*
X310500Y792908D01*
X310583Y792575D01*
X310500Y792242D01*
X310250Y792033D01*
X309958Y791908D01*
X308917D01*
G01X309958D02*
X310583Y790700D01*
G01X311933Y791075D02*
X312183Y790867D01*
X312475Y790742D01*
X312850Y790700D01*
X313225Y790783D01*
X313517Y790950D01*
X313725Y791242D01*
X313767Y791575D01*
X313683Y791908D01*
X313475Y792117D01*
X313183Y792283D01*
X312892Y792325D01*
X312600Y792283D01*
X312225Y792117D01*
X312350Y793200D01*
X313475D01*
G01X315033Y791075D02*
X315283Y790867D01*
X315575Y790742D01*
X315950Y790700D01*
X316325Y790783D01*
X316617Y790950D01*
X316825Y791242D01*
X316867Y791575D01*
X316783Y791908D01*
X316575Y792117D01*
X316283Y792283D01*
X315992Y792325D01*
X315700Y792283D01*
X315325Y792117D01*
X315450Y793200D01*
X316575D01*
G01X318967Y790700D02*
X319050Y791242D01*
X319175Y791700D01*
X319342Y792117D01*
X319550Y792575D01*
X319883Y793200D01*
X318217D01*
G01X317700Y777000D02*
Y781000D01*
X310300D01*
G01X338517Y737500D02*
Y740000D01*
X339558D01*
X339892Y739875D01*
X340100Y739708D01*
X340183Y739375D01*
X340100Y739042D01*
X339850Y738833D01*
X339558Y738708D01*
X338517D01*
G01X339558D02*
X340183Y737500D01*
G01X341658Y739583D02*
X341908Y739833D01*
X342200Y739958D01*
X342533Y740000D01*
X342950Y739917D01*
X343242Y739708D01*
X343325Y739458D01*
X343283Y739208D01*
X343117Y739000D01*
X342283Y738583D01*
X341908Y738292D01*
X341658Y737875D01*
X341575Y737500D01*
X343325D01*
G01X344758Y739583D02*
X345008Y739833D01*
X345300Y739958D01*
X345633Y740000D01*
X346050Y739917D01*
X346342Y739708D01*
X346425Y739458D01*
X346383Y739208D01*
X346217Y739000D01*
X345383Y738583D01*
X345008Y738292D01*
X344758Y737875D01*
X344675Y737500D01*
X346425D01*
G01X348650Y740000D02*
X348317Y739917D01*
X348067Y739708D01*
X347900Y739458D01*
X347775Y739125D01*
X347733Y738750D01*
X347775Y738375D01*
X347900Y738042D01*
X348067Y737792D01*
X348317Y737583D01*
X348650Y737500D01*
X348983Y737583D01*
X349233Y737792D01*
X349400Y738042D01*
X349525Y738375D01*
X349567Y738750D01*
X349525Y739125D01*
X349400Y739458D01*
X349233Y739708D01*
X348983Y739917D01*
X348650Y740000D01*
G01X312199Y740050D02*
Y744050D01*
X304799D01*
G01X334000Y757517D02*
X331500D01*
Y758558D01*
X331625Y758892D01*
X331792Y759100D01*
X332125Y759183D01*
X332458Y759100D01*
X332667Y758850D01*
X332792Y758558D01*
Y757517D01*
G01Y758558D02*
X334000Y759183D01*
G01X331917Y760658D02*
X331667Y760908D01*
X331542Y761200D01*
X331500Y761533D01*
X331583Y761950D01*
X331792Y762242D01*
X332042Y762325D01*
X332292Y762283D01*
X332500Y762117D01*
X332917Y761283D01*
X333208Y760908D01*
X333625Y760658D01*
X334000Y760575D01*
Y762325D01*
G01X331917Y763758D02*
X331667Y764008D01*
X331542Y764300D01*
X331500Y764633D01*
X331583Y765050D01*
X331792Y765342D01*
X332042Y765425D01*
X332292Y765383D01*
X332500Y765217D01*
X332917Y764383D01*
X333208Y764008D01*
X333625Y763758D01*
X334000Y763675D01*
Y765425D01*
G01Y767650D02*
X331500D01*
X332000Y767150D01*
G01X334000D02*
Y768150D01*
G01X305799Y769050D02*
Y765050D01*
X313199D01*
G01X330000Y757517D02*
X327500D01*
Y758558D01*
X327625Y758892D01*
X327792Y759100D01*
X328125Y759183D01*
X328458Y759100D01*
X328667Y758850D01*
X328792Y758558D01*
Y757517D01*
G01Y758558D02*
X330000Y759183D01*
G01X327917Y760658D02*
X327667Y760908D01*
X327542Y761200D01*
X327500Y761533D01*
X327583Y761950D01*
X327792Y762242D01*
X328042Y762325D01*
X328292Y762283D01*
X328500Y762117D01*
X328917Y761283D01*
X329208Y760908D01*
X329625Y760658D01*
X330000Y760575D01*
Y762325D01*
G01X327917Y763758D02*
X327667Y764008D01*
X327542Y764300D01*
X327500Y764633D01*
X327583Y765050D01*
X327792Y765342D01*
X328042Y765425D01*
X328292Y765383D01*
X328500Y765217D01*
X328917Y764383D01*
X329208Y764008D01*
X329625Y763758D01*
X330000Y763675D01*
Y765425D01*
G01X327917Y766858D02*
X327667Y767108D01*
X327542Y767400D01*
X327500Y767733D01*
X327583Y768150D01*
X327792Y768442D01*
X328042Y768525D01*
X328292Y768483D01*
X328500Y768317D01*
X328917Y767483D01*
X329208Y767108D01*
X329625Y766858D01*
X330000Y766775D01*
Y768525D01*
G01X305799Y764550D02*
Y760550D01*
X313199D01*
G01X338517Y745500D02*
Y748000D01*
X339558D01*
X339892Y747875D01*
X340100Y747708D01*
X340183Y747375D01*
X340100Y747042D01*
X339850Y746833D01*
X339558Y746708D01*
X338517D01*
G01X339558D02*
X340183Y745500D01*
G01X341658Y747583D02*
X341908Y747833D01*
X342200Y747958D01*
X342533Y748000D01*
X342950Y747917D01*
X343242Y747708D01*
X343325Y747458D01*
X343283Y747208D01*
X343117Y747000D01*
X342283Y746583D01*
X341908Y746292D01*
X341658Y745875D01*
X341575Y745500D01*
X343325D01*
G01X344758Y747583D02*
X345008Y747833D01*
X345300Y747958D01*
X345633Y748000D01*
X346050Y747917D01*
X346342Y747708D01*
X346425Y747458D01*
X346383Y747208D01*
X346217Y747000D01*
X345383Y746583D01*
X345008Y746292D01*
X344758Y745875D01*
X344675Y745500D01*
X346425D01*
G01X349150D02*
Y748000D01*
X347608Y746208D01*
X349692D01*
G01X304799Y752050D02*
Y748050D01*
X312199D01*
G01X338517Y741500D02*
Y744000D01*
X339558D01*
X339892Y743875D01*
X340100Y743708D01*
X340183Y743375D01*
X340100Y743042D01*
X339850Y742833D01*
X339558Y742708D01*
X338517D01*
G01X339558D02*
X340183Y741500D01*
G01X341658Y743583D02*
X341908Y743833D01*
X342200Y743958D01*
X342533Y744000D01*
X342950Y743917D01*
X343242Y743708D01*
X343325Y743458D01*
X343283Y743208D01*
X343117Y743000D01*
X342283Y742583D01*
X341908Y742292D01*
X341658Y741875D01*
X341575Y741500D01*
X343325D01*
G01X344758Y743583D02*
X345008Y743833D01*
X345300Y743958D01*
X345633Y744000D01*
X346050Y743917D01*
X346342Y743708D01*
X346425Y743458D01*
X346383Y743208D01*
X346217Y743000D01*
X345383Y742583D01*
X345008Y742292D01*
X344758Y741875D01*
X344675Y741500D01*
X346425D01*
G01X347733Y741875D02*
X347983Y741667D01*
X348275Y741542D01*
X348650Y741500D01*
X349025Y741583D01*
X349317Y741750D01*
X349525Y742042D01*
X349567Y742375D01*
X349483Y742708D01*
X349275Y742917D01*
X348983Y743083D01*
X348692Y743125D01*
X348400Y743083D01*
X348025Y742917D01*
X348150Y744000D01*
X349275D01*
G01X312199Y744050D02*
Y748050D01*
X304799D01*
G01X283499Y753750D02*
X279499D01*
Y746350D01*
G01X287499Y753750D02*
X283499D01*
Y746350D01*
G01X336699Y743050D02*
Y747050D01*
X329299D01*
G01X336699Y739050D02*
Y743050D01*
X329299D01*
G01X335517Y772500D02*
Y775000D01*
X336558D01*
X336892Y774875D01*
X337100Y774708D01*
X337183Y774375D01*
X337100Y774042D01*
X336850Y773833D01*
X336558Y773708D01*
X335517D01*
G01X336558D02*
X337183Y772500D01*
G01X339950D02*
Y775000D01*
X338408Y773208D01*
X340492D01*
G01X342550Y772500D02*
Y775000D01*
X342050Y774500D01*
G01Y772500D02*
X343050D01*
G01X344858Y773542D02*
X345150Y773833D01*
X345400Y774000D01*
X345733Y774083D01*
X346025Y774000D01*
X346233Y773833D01*
X346400Y773583D01*
X346442Y773292D01*
X346400Y773042D01*
X346233Y772792D01*
X345983Y772583D01*
X345692Y772500D01*
X345358Y772583D01*
X345067Y772833D01*
X344900Y773208D01*
X344858Y773625D01*
X344942Y774167D01*
X345067Y774458D01*
X345275Y774750D01*
X345567Y774958D01*
X345858Y775000D01*
X346150Y774917D01*
X346358Y774708D01*
G01X321400Y770200D02*
Y774200D01*
X314000D01*
G01X277499Y730350D02*
Y743750D01*
G01X287499Y730350D02*
X277499D01*
G01X287499Y743750D02*
Y730350D01*
G01X277499Y743750D02*
X287499D01*
G01X313299Y748550D02*
X326699D01*
G01X313299Y738550D02*
Y748550D01*
G01X326699Y738550D02*
X313299D01*
G01X326699Y748550D02*
Y738550D01*
G01X286982Y780550D02*
Y778758D01*
X287149Y778383D01*
X287482Y778133D01*
X287899Y778050D01*
X288316Y778133D01*
X288649Y778383D01*
X288816Y778758D01*
Y780550D01*
G01X290207Y780133D02*
X290457Y780383D01*
X290749Y780508D01*
X291082Y780550D01*
X291499Y780467D01*
X291791Y780258D01*
X291874Y780008D01*
X291832Y779758D01*
X291666Y779550D01*
X290832Y779133D01*
X290457Y778842D01*
X290207Y778425D01*
X290124Y778050D01*
X291874D01*
G01X293307Y779092D02*
X293599Y779383D01*
X293849Y779550D01*
X294182Y779633D01*
X294474Y779550D01*
X294682Y779383D01*
X294849Y779133D01*
X294891Y778842D01*
X294849Y778592D01*
X294682Y778342D01*
X294432Y778133D01*
X294141Y778050D01*
X293807Y778133D01*
X293516Y778383D01*
X293349Y778758D01*
X293307Y779175D01*
X293391Y779717D01*
X293516Y780008D01*
X293724Y780300D01*
X294016Y780508D01*
X294307Y780550D01*
X294599Y780467D01*
X294807Y780258D01*
G01X288999Y754250D02*
X290999Y756250D01*
X292999Y754250D01*
G01X296599D02*
Y773450D01*
X285399D01*
Y754250D01*
X296599D01*
G01X269227Y1100739D02*
Y1103239D01*
G01X270977D02*
Y1100739D01*
G01Y1101989D02*
X269227D01*
G01X273202Y1100739D02*
X273494Y1100781D01*
X273827Y1100906D01*
X274035Y1101114D01*
X274119Y1101406D01*
X274035Y1101697D01*
X273785Y1101947D01*
X273410Y1102072D01*
X272994D01*
X272744Y1102156D01*
X272535Y1102364D01*
X272452Y1102656D01*
X272577Y1102947D01*
X272869Y1103156D01*
X273202Y1103239D01*
X273535Y1103156D01*
X273827Y1102947D01*
X273952Y1102656D01*
X273869Y1102364D01*
X273660Y1102156D01*
X273410Y1102072D01*
X272994D01*
X272619Y1101947D01*
X272369Y1101697D01*
X272285Y1101406D01*
X272369Y1101114D01*
X272577Y1100906D01*
X272910Y1100781D01*
X273202Y1100739D01*
G01X296208Y1532317D02*
X296083Y1532067D01*
X296000Y1531775D01*
Y1531442D01*
X296125Y1531067D01*
X296333Y1530775D01*
X296583Y1530567D01*
X297000Y1530400D01*
X297375Y1530358D01*
X297750Y1530442D01*
X298000Y1530567D01*
X298250Y1530817D01*
X298417Y1531108D01*
X298500Y1531400D01*
Y1531692D01*
X298417Y1531983D01*
X298292Y1532233D01*
X298125Y1532442D01*
G01X296417Y1533708D02*
X296167Y1533958D01*
X296042Y1534250D01*
X296000Y1534583D01*
X296083Y1535000D01*
X296292Y1535292D01*
X296542Y1535375D01*
X296792Y1535333D01*
X297000Y1535167D01*
X297417Y1534333D01*
X297708Y1533958D01*
X298125Y1533708D01*
X298500Y1533625D01*
Y1535375D01*
G01X296000Y1537600D02*
X296083Y1537267D01*
X296292Y1537017D01*
X296542Y1536850D01*
X296875Y1536725D01*
X297250Y1536683D01*
X297625Y1536725D01*
X297958Y1536850D01*
X298208Y1537017D01*
X298417Y1537267D01*
X298500Y1537600D01*
X298417Y1537933D01*
X298208Y1538183D01*
X297958Y1538350D01*
X297625Y1538475D01*
X297250Y1538517D01*
X296875Y1538475D01*
X296542Y1538350D01*
X296292Y1538183D01*
X296083Y1537933D01*
X296000Y1537600D01*
G01X298000Y1539783D02*
X298292Y1540033D01*
X298458Y1540367D01*
X298500Y1540742D01*
X298458Y1541075D01*
X298250Y1541408D01*
X298000Y1541617D01*
X297750Y1541658D01*
X297458Y1541575D01*
X297250Y1541283D01*
X297167Y1540992D01*
Y1540617D01*
G01Y1540992D02*
X297042Y1541242D01*
X296833Y1541450D01*
X296583Y1541533D01*
X296333Y1541450D01*
X296125Y1541242D01*
X296000Y1540867D01*
X296042Y1540492D01*
X296208Y1540117D01*
G01X313208Y1533867D02*
X313083Y1533617D01*
X313000Y1533325D01*
Y1532992D01*
X313125Y1532617D01*
X313333Y1532325D01*
X313583Y1532117D01*
X314000Y1531950D01*
X314375Y1531908D01*
X314750Y1531992D01*
X315000Y1532117D01*
X315250Y1532367D01*
X315417Y1532658D01*
X315500Y1532950D01*
Y1533242D01*
X315417Y1533533D01*
X315292Y1533783D01*
X315125Y1533992D01*
G01X315500Y1536050D02*
X313000D01*
X313500Y1535550D01*
G01X315500D02*
Y1536550D01*
G01X315208Y1538442D02*
X315417Y1538733D01*
X315500Y1539067D01*
X315417Y1539400D01*
X315167Y1539692D01*
X314792Y1539900D01*
X314417Y1539983D01*
X313958D01*
X313583Y1539900D01*
X313250Y1539692D01*
X313083Y1539442D01*
X313000Y1539150D01*
X313083Y1538817D01*
X313250Y1538567D01*
X313500Y1538400D01*
X313833Y1538317D01*
X314125Y1538400D01*
X314417Y1538608D01*
X314583Y1538858D01*
X314625Y1539150D01*
X314542Y1539483D01*
X314333Y1539733D01*
X313958Y1539983D01*
G01X315500Y1542167D02*
X314958Y1542250D01*
X314500Y1542375D01*
X314083Y1542542D01*
X313625Y1542750D01*
X313000Y1543083D01*
Y1541417D01*
G01X269267Y1535792D02*
X269017Y1535917D01*
X268725Y1536000D01*
X268392D01*
X268017Y1535875D01*
X267725Y1535667D01*
X267517Y1535417D01*
X267350Y1535000D01*
X267308Y1534625D01*
X267392Y1534250D01*
X267517Y1534000D01*
X267767Y1533750D01*
X268058Y1533583D01*
X268350Y1533500D01*
X268642D01*
X268933Y1533583D01*
X269183Y1533708D01*
X269392Y1533875D01*
G01X270658Y1535583D02*
X270908Y1535833D01*
X271200Y1535958D01*
X271533Y1536000D01*
X271950Y1535917D01*
X272242Y1535708D01*
X272325Y1535458D01*
X272283Y1535208D01*
X272117Y1535000D01*
X271283Y1534583D01*
X270908Y1534292D01*
X270658Y1533875D01*
X270575Y1533500D01*
X272325D01*
G01X274550D02*
Y1536000D01*
X274050Y1535500D01*
G01Y1533500D02*
X275050D01*
G01X277650D02*
Y1536000D01*
X277150Y1535500D01*
G01Y1533500D02*
X278150D01*
G01X294300Y1518800D02*
X294258Y1518467D01*
X294092Y1518175D01*
X293842Y1517925D01*
X293550Y1517758D01*
X293217Y1517675D01*
X292883D01*
X292550Y1517758D01*
X292258Y1517925D01*
X292008Y1518175D01*
X291842Y1518467D01*
X291800Y1518800D01*
X291842Y1519133D01*
X292008Y1519425D01*
X292258Y1519675D01*
X292550Y1519842D01*
X292883Y1519925D01*
X293217D01*
X293550Y1519842D01*
X293842Y1519675D01*
X294092Y1519425D01*
X294258Y1519133D01*
X294300Y1518800D01*
G01X293633Y1519133D02*
X294300Y1519633D01*
G01Y1521900D02*
X291800D01*
X292300Y1521400D01*
G01X294300D02*
Y1522400D01*
G01X293800Y1524083D02*
X294092Y1524333D01*
X294258Y1524667D01*
X294300Y1525042D01*
X294258Y1525375D01*
X294050Y1525708D01*
X293800Y1525917D01*
X293550Y1525958D01*
X293258Y1525875D01*
X293050Y1525583D01*
X292967Y1525292D01*
Y1524917D01*
G01Y1525292D02*
X292842Y1525542D01*
X292633Y1525750D01*
X292383Y1525833D01*
X292133Y1525750D01*
X291925Y1525542D01*
X291800Y1525167D01*
X291842Y1524792D01*
X292008Y1524417D01*
G01X264999Y1531250D02*
X263199Y1529150D01*
X260999Y1531250D01*
G01X336016Y1553550D02*
Y1556050D01*
X337057D01*
X337391Y1555925D01*
X337599Y1555758D01*
X337682Y1555425D01*
X337599Y1555092D01*
X337349Y1554883D01*
X337057Y1554758D01*
X336016D01*
G01X337057D02*
X337682Y1553550D01*
G01X339949D02*
Y1556050D01*
X339449Y1555550D01*
G01Y1553550D02*
X340449D01*
G01X342341Y1553842D02*
X342632Y1553633D01*
X342966Y1553550D01*
X343299Y1553633D01*
X343591Y1553883D01*
X343799Y1554258D01*
X343882Y1554633D01*
Y1555092D01*
X343799Y1555467D01*
X343591Y1555800D01*
X343341Y1555967D01*
X343049Y1556050D01*
X342716Y1555967D01*
X342466Y1555800D01*
X342299Y1555550D01*
X342216Y1555217D01*
X342299Y1554925D01*
X342507Y1554633D01*
X342757Y1554467D01*
X343049Y1554425D01*
X343382Y1554508D01*
X343632Y1554717D01*
X343882Y1555092D01*
G01X345357Y1555633D02*
X345607Y1555883D01*
X345899Y1556008D01*
X346232Y1556050D01*
X346649Y1555967D01*
X346941Y1555758D01*
X347024Y1555508D01*
X346982Y1555258D01*
X346816Y1555050D01*
X345982Y1554633D01*
X345607Y1554342D01*
X345357Y1553925D01*
X345274Y1553550D01*
X347024D01*
G01X308699Y1552550D02*
Y1556550D01*
X301299D01*
G01X336016Y1557550D02*
Y1560050D01*
X337057D01*
X337391Y1559925D01*
X337599Y1559758D01*
X337682Y1559425D01*
X337599Y1559092D01*
X337349Y1558883D01*
X337057Y1558758D01*
X336016D01*
G01X337057D02*
X337682Y1557550D01*
G01X339949D02*
Y1560050D01*
X339449Y1559550D01*
G01Y1557550D02*
X340449D01*
G01X342341Y1557842D02*
X342632Y1557633D01*
X342966Y1557550D01*
X343299Y1557633D01*
X343591Y1557883D01*
X343799Y1558258D01*
X343882Y1558633D01*
Y1559092D01*
X343799Y1559467D01*
X343591Y1559800D01*
X343341Y1559967D01*
X343049Y1560050D01*
X342716Y1559967D01*
X342466Y1559800D01*
X342299Y1559550D01*
X342216Y1559217D01*
X342299Y1558925D01*
X342507Y1558633D01*
X342757Y1558467D01*
X343049Y1558425D01*
X343382Y1558508D01*
X343632Y1558717D01*
X343882Y1559092D01*
G01X346066Y1557550D02*
X346149Y1558092D01*
X346274Y1558550D01*
X346441Y1558967D01*
X346649Y1559425D01*
X346982Y1560050D01*
X345316D01*
G01X308699Y1556550D02*
Y1560550D01*
X301299D01*
G01X286017Y1556500D02*
Y1559000D01*
X287058D01*
X287392Y1558875D01*
X287600Y1558708D01*
X287683Y1558375D01*
X287600Y1558042D01*
X287350Y1557833D01*
X287058Y1557708D01*
X286017D01*
G01X287058D02*
X287683Y1556500D01*
G01X290450D02*
Y1559000D01*
X288908Y1557208D01*
X290992D01*
G01X293550Y1556500D02*
Y1559000D01*
X292008Y1557208D01*
X294092D01*
G01X296067Y1556500D02*
X296150Y1557042D01*
X296275Y1557500D01*
X296442Y1557917D01*
X296650Y1558375D01*
X296983Y1559000D01*
X295317D01*
G01X333199Y1555550D02*
Y1559550D01*
X325799D01*
G01X333199Y1551550D02*
Y1555550D01*
X325799D01*
G01X289000Y1538983D02*
X290792D01*
X291167Y1539150D01*
X291417Y1539483D01*
X291500Y1539900D01*
X291417Y1540317D01*
X291167Y1540650D01*
X290792Y1540817D01*
X289000D01*
G01X291500Y1543000D02*
X289000D01*
X289500Y1542500D01*
G01X291500D02*
Y1543500D01*
G01X291208Y1545392D02*
X291417Y1545683D01*
X291500Y1546017D01*
X291417Y1546350D01*
X291167Y1546642D01*
X290792Y1546850D01*
X290417Y1546933D01*
X289958D01*
X289583Y1546850D01*
X289250Y1546642D01*
X289083Y1546392D01*
X289000Y1546100D01*
X289083Y1545767D01*
X289250Y1545517D01*
X289500Y1545350D01*
X289833Y1545267D01*
X290125Y1545350D01*
X290417Y1545558D01*
X290583Y1545808D01*
X290625Y1546100D01*
X290542Y1546433D01*
X290333Y1546683D01*
X289958Y1546933D01*
G01X276499Y1541350D02*
Y1554750D01*
G01X286499Y1541350D02*
X276499D01*
G01X286499Y1554750D02*
Y1541350D01*
G01X276499Y1554750D02*
X286499D01*
G01X309799Y1552050D02*
Y1562050D01*
G01X323199Y1552050D02*
X309799D01*
G01X323199Y1562050D02*
Y1552050D01*
G01X264767Y1539792D02*
X264517Y1539917D01*
X264225Y1540000D01*
X263892D01*
X263517Y1539875D01*
X263225Y1539667D01*
X263017Y1539417D01*
X262850Y1539000D01*
X262808Y1538625D01*
X262892Y1538250D01*
X263017Y1538000D01*
X263267Y1537750D01*
X263558Y1537583D01*
X263850Y1537500D01*
X264142D01*
X264433Y1537583D01*
X264683Y1537708D01*
X264892Y1537875D01*
G01X266158Y1539583D02*
X266408Y1539833D01*
X266700Y1539958D01*
X267033Y1540000D01*
X267450Y1539917D01*
X267742Y1539708D01*
X267825Y1539458D01*
X267783Y1539208D01*
X267617Y1539000D01*
X266783Y1538583D01*
X266408Y1538292D01*
X266158Y1537875D01*
X266075Y1537500D01*
X267825D01*
G01X270050Y1540000D02*
X269717Y1539917D01*
X269467Y1539708D01*
X269300Y1539458D01*
X269175Y1539125D01*
X269133Y1538750D01*
X269175Y1538375D01*
X269300Y1538042D01*
X269467Y1537792D01*
X269717Y1537583D01*
X270050Y1537500D01*
X270383Y1537583D01*
X270633Y1537792D01*
X270800Y1538042D01*
X270925Y1538375D01*
X270967Y1538750D01*
X270925Y1539125D01*
X270800Y1539458D01*
X270633Y1539708D01*
X270383Y1539917D01*
X270050Y1540000D01*
G01X273067Y1537500D02*
X273150Y1538042D01*
X273275Y1538500D01*
X273442Y1538917D01*
X273650Y1539375D01*
X273983Y1540000D01*
X272317D01*
G01X288527Y1504851D02*
Y1507351D01*
G01X290277D02*
Y1504851D01*
G01Y1506101D02*
X288527D01*
G01X291585Y1505351D02*
X291835Y1505059D01*
X292169Y1504893D01*
X292544Y1504851D01*
X292877Y1504893D01*
X293210Y1505101D01*
X293419Y1505351D01*
X293460Y1505601D01*
X293377Y1505893D01*
X293085Y1506101D01*
X292794Y1506184D01*
X292419D01*
G01X292794D02*
X293044Y1506309D01*
X293252Y1506518D01*
X293335Y1506768D01*
X293252Y1507018D01*
X293044Y1507226D01*
X292669Y1507351D01*
X292294Y1507309D01*
X291919Y1507143D01*
G01X326683Y1604900D02*
Y1607400D01*
X327517D01*
X327850Y1607275D01*
X328100Y1607108D01*
X328308Y1606858D01*
X328475Y1606567D01*
X328517Y1606150D01*
X328475Y1605733D01*
X328308Y1605442D01*
X328100Y1605192D01*
X327850Y1605025D01*
X327517Y1604900D01*
X326683D01*
G01X329908Y1606983D02*
X330158Y1607233D01*
X330450Y1607358D01*
X330783Y1607400D01*
X331200Y1607317D01*
X331492Y1607108D01*
X331575Y1606858D01*
X331533Y1606608D01*
X331367Y1606400D01*
X330533Y1605983D01*
X330158Y1605692D01*
X329908Y1605275D01*
X329825Y1604900D01*
X331575D01*
G01X333800D02*
Y1607400D01*
X333300Y1606900D01*
G01Y1604900D02*
X334300D01*
G01X306500Y1600500D02*
X322600D01*
G01X306500Y1593500D02*
Y1600500D01*
G01X322600Y1593500D02*
X306500D01*
G01X322600Y1600500D02*
Y1593500D01*
G01X331608Y1587667D02*
X331483Y1587417D01*
X331400Y1587125D01*
Y1586792D01*
X331525Y1586417D01*
X331733Y1586125D01*
X331983Y1585917D01*
X332400Y1585750D01*
X332775Y1585708D01*
X333150Y1585792D01*
X333400Y1585917D01*
X333650Y1586167D01*
X333817Y1586458D01*
X333900Y1586750D01*
Y1587042D01*
X333817Y1587333D01*
X333692Y1587583D01*
X333525Y1587792D01*
G01X333400Y1588933D02*
X333692Y1589183D01*
X333858Y1589517D01*
X333900Y1589892D01*
X333858Y1590225D01*
X333650Y1590558D01*
X333400Y1590767D01*
X333150Y1590808D01*
X332858Y1590725D01*
X332650Y1590433D01*
X332567Y1590142D01*
Y1589767D01*
G01Y1590142D02*
X332442Y1590392D01*
X332233Y1590600D01*
X331983Y1590683D01*
X331733Y1590600D01*
X331525Y1590392D01*
X331400Y1590017D01*
X331442Y1589642D01*
X331608Y1589267D01*
G01X333900Y1592950D02*
X333858Y1593242D01*
X333733Y1593575D01*
X333525Y1593783D01*
X333233Y1593867D01*
X332942Y1593783D01*
X332692Y1593533D01*
X332567Y1593158D01*
Y1592742D01*
X332483Y1592492D01*
X332275Y1592283D01*
X331983Y1592200D01*
X331692Y1592325D01*
X331483Y1592617D01*
X331400Y1592950D01*
X331483Y1593283D01*
X331692Y1593575D01*
X331983Y1593700D01*
X332275Y1593617D01*
X332483Y1593408D01*
X332567Y1593158D01*
Y1592742D01*
X332692Y1592367D01*
X332942Y1592117D01*
X333233Y1592033D01*
X333525Y1592117D01*
X333733Y1592325D01*
X333858Y1592658D01*
X333900Y1592950D01*
G01X333525Y1595133D02*
X333733Y1595383D01*
X333858Y1595675D01*
X333900Y1596050D01*
X333817Y1596425D01*
X333650Y1596717D01*
X333358Y1596925D01*
X333025Y1596967D01*
X332692Y1596883D01*
X332483Y1596675D01*
X332317Y1596383D01*
X332275Y1596092D01*
X332317Y1595800D01*
X332483Y1595425D01*
X331400Y1595550D01*
Y1596675D01*
G01X345500Y1570200D02*
X345458Y1569867D01*
X345292Y1569575D01*
X345042Y1569325D01*
X344750Y1569158D01*
X344417Y1569075D01*
X344083D01*
X343750Y1569158D01*
X343458Y1569325D01*
X343208Y1569575D01*
X343042Y1569867D01*
X343000Y1570200D01*
X343042Y1570533D01*
X343208Y1570825D01*
X343458Y1571075D01*
X343750Y1571242D01*
X344083Y1571325D01*
X344417D01*
X344750Y1571242D01*
X345042Y1571075D01*
X345292Y1570825D01*
X345458Y1570533D01*
X345500Y1570200D01*
G01X344833Y1570533D02*
X345500Y1571033D01*
G01Y1573300D02*
X343000D01*
X343500Y1572800D01*
G01X345500D02*
Y1573800D01*
G01Y1576900D02*
X343000D01*
X344792Y1575358D01*
Y1577442D01*
G01X312799Y1566850D02*
X324199D01*
G01X312799Y1580250D02*
Y1566850D01*
G01X324199Y1580250D02*
X312799D01*
G01X324199Y1566850D02*
Y1580250D01*
G01X338200Y1585317D02*
X335700D01*
Y1586358D01*
X335825Y1586692D01*
X335992Y1586900D01*
X336325Y1586983D01*
X336658Y1586900D01*
X336867Y1586650D01*
X336992Y1586358D01*
Y1585317D01*
G01Y1586358D02*
X338200Y1586983D01*
G01X337825Y1588333D02*
X338033Y1588583D01*
X338158Y1588875D01*
X338200Y1589250D01*
X338117Y1589625D01*
X337950Y1589917D01*
X337658Y1590125D01*
X337325Y1590167D01*
X336992Y1590083D01*
X336783Y1589875D01*
X336617Y1589583D01*
X336575Y1589292D01*
X336617Y1589000D01*
X336783Y1588625D01*
X335700Y1588750D01*
Y1589875D01*
G01X337158Y1591558D02*
X336867Y1591850D01*
X336700Y1592100D01*
X336617Y1592433D01*
X336700Y1592725D01*
X336867Y1592933D01*
X337117Y1593100D01*
X337408Y1593142D01*
X337658Y1593100D01*
X337908Y1592933D01*
X338117Y1592683D01*
X338200Y1592392D01*
X338117Y1592058D01*
X337867Y1591767D01*
X337492Y1591600D01*
X337075Y1591558D01*
X336533Y1591642D01*
X336242Y1591767D01*
X335950Y1591975D01*
X335742Y1592267D01*
X335700Y1592558D01*
X335783Y1592850D01*
X335992Y1593058D01*
G01X337908Y1594742D02*
X338117Y1595033D01*
X338200Y1595367D01*
X338117Y1595700D01*
X337867Y1595992D01*
X337492Y1596200D01*
X337117Y1596283D01*
X336658D01*
X336283Y1596200D01*
X335950Y1595992D01*
X335783Y1595742D01*
X335700Y1595450D01*
X335783Y1595117D01*
X335950Y1594867D01*
X336200Y1594700D01*
X336533Y1594617D01*
X336825Y1594700D01*
X337117Y1594908D01*
X337283Y1595158D01*
X337325Y1595450D01*
X337242Y1595783D01*
X337033Y1596033D01*
X336658Y1596283D01*
G01X312500Y1588200D02*
X308500D01*
Y1580800D01*
G01X332117Y1598800D02*
Y1601300D01*
X333158D01*
X333492Y1601175D01*
X333700Y1601008D01*
X333783Y1600675D01*
X333700Y1600342D01*
X333450Y1600133D01*
X333158Y1600008D01*
X332117D01*
G01X333158D02*
X333783Y1598800D01*
G01X335133Y1599175D02*
X335383Y1598967D01*
X335675Y1598842D01*
X336050Y1598800D01*
X336425Y1598883D01*
X336717Y1599050D01*
X336925Y1599342D01*
X336967Y1599675D01*
X336883Y1600008D01*
X336675Y1600217D01*
X336383Y1600383D01*
X336092Y1600425D01*
X335800Y1600383D01*
X335425Y1600217D01*
X335550Y1601300D01*
X336675D01*
G01X338233Y1599175D02*
X338483Y1598967D01*
X338775Y1598842D01*
X339150Y1598800D01*
X339525Y1598883D01*
X339817Y1599050D01*
X340025Y1599342D01*
X340067Y1599675D01*
X339983Y1600008D01*
X339775Y1600217D01*
X339483Y1600383D01*
X339192Y1600425D01*
X338900Y1600383D01*
X338525Y1600217D01*
X338650Y1601300D01*
X339775D01*
G01X341333Y1599175D02*
X341583Y1598967D01*
X341875Y1598842D01*
X342250Y1598800D01*
X342625Y1598883D01*
X342917Y1599050D01*
X343125Y1599342D01*
X343167Y1599675D01*
X343083Y1600008D01*
X342875Y1600217D01*
X342583Y1600383D01*
X342292Y1600425D01*
X342000Y1600383D01*
X341625Y1600217D01*
X341750Y1601300D01*
X342875D01*
G01X318200Y1589000D02*
Y1593000D01*
X310800D01*
G01X341817Y1589900D02*
Y1592400D01*
X342858D01*
X343192Y1592275D01*
X343400Y1592108D01*
X343483Y1591775D01*
X343400Y1591442D01*
X343150Y1591233D01*
X342858Y1591108D01*
X341817D01*
G01X342858D02*
X343483Y1589900D01*
G01X345750D02*
Y1592400D01*
X345250Y1591900D01*
G01Y1589900D02*
X346250D01*
G01X348142Y1590192D02*
X348433Y1589983D01*
X348767Y1589900D01*
X349100Y1589983D01*
X349392Y1590233D01*
X349600Y1590608D01*
X349683Y1590983D01*
Y1591442D01*
X349600Y1591817D01*
X349392Y1592150D01*
X349142Y1592317D01*
X348850Y1592400D01*
X348517Y1592317D01*
X348267Y1592150D01*
X348100Y1591900D01*
X348017Y1591567D01*
X348100Y1591275D01*
X348308Y1590983D01*
X348558Y1590817D01*
X348850Y1590775D01*
X349183Y1590858D01*
X349433Y1591067D01*
X349683Y1591442D01*
G01X351033Y1590400D02*
X351283Y1590108D01*
X351617Y1589942D01*
X351992Y1589900D01*
X352325Y1589942D01*
X352658Y1590150D01*
X352867Y1590400D01*
X352908Y1590650D01*
X352825Y1590942D01*
X352533Y1591150D01*
X352242Y1591233D01*
X351867D01*
G01X352242D02*
X352492Y1591358D01*
X352700Y1591567D01*
X352783Y1591817D01*
X352700Y1592067D01*
X352492Y1592275D01*
X352117Y1592400D01*
X351742Y1592358D01*
X351367Y1592192D01*
G01X320200Y1585000D02*
Y1589000D01*
X312800D01*
G01X329917Y1570600D02*
Y1573100D01*
X330958D01*
X331292Y1572975D01*
X331500Y1572808D01*
X331583Y1572475D01*
X331500Y1572142D01*
X331250Y1571933D01*
X330958Y1571808D01*
X329917D01*
G01X330958D02*
X331583Y1570600D01*
G01X333850D02*
Y1573100D01*
X333350Y1572600D01*
G01Y1570600D02*
X334350D01*
G01X336242Y1570892D02*
X336533Y1570683D01*
X336867Y1570600D01*
X337200Y1570683D01*
X337492Y1570933D01*
X337700Y1571308D01*
X337783Y1571683D01*
Y1572142D01*
X337700Y1572517D01*
X337492Y1572850D01*
X337242Y1573017D01*
X336950Y1573100D01*
X336617Y1573017D01*
X336367Y1572850D01*
X336200Y1572600D01*
X336117Y1572267D01*
X336200Y1571975D01*
X336408Y1571683D01*
X336658Y1571517D01*
X336950Y1571475D01*
X337283Y1571558D01*
X337533Y1571767D01*
X337783Y1572142D01*
G01X340550Y1570600D02*
Y1573100D01*
X339008Y1571308D01*
X341092D01*
G01X304799Y1575050D02*
Y1571050D01*
X312199D01*
G01X336016Y1561550D02*
Y1564050D01*
X337057D01*
X337391Y1563925D01*
X337599Y1563758D01*
X337682Y1563425D01*
X337599Y1563092D01*
X337349Y1562883D01*
X337057Y1562758D01*
X336016D01*
G01X337057D02*
X337682Y1561550D01*
G01X339949D02*
Y1564050D01*
X339449Y1563550D01*
G01Y1561550D02*
X340449D01*
G01X342341Y1561842D02*
X342632Y1561633D01*
X342966Y1561550D01*
X343299Y1561633D01*
X343591Y1561883D01*
X343799Y1562258D01*
X343882Y1562633D01*
Y1563092D01*
X343799Y1563467D01*
X343591Y1563800D01*
X343341Y1563967D01*
X343049Y1564050D01*
X342716Y1563967D01*
X342466Y1563800D01*
X342299Y1563550D01*
X342216Y1563217D01*
X342299Y1562925D01*
X342507Y1562633D01*
X342757Y1562467D01*
X343049Y1562425D01*
X343382Y1562508D01*
X343632Y1562717D01*
X343882Y1563092D01*
G01X345357Y1562592D02*
X345649Y1562883D01*
X345899Y1563050D01*
X346232Y1563133D01*
X346524Y1563050D01*
X346732Y1562883D01*
X346899Y1562633D01*
X346941Y1562342D01*
X346899Y1562092D01*
X346732Y1561842D01*
X346482Y1561633D01*
X346191Y1561550D01*
X345857Y1561633D01*
X345566Y1561883D01*
X345399Y1562258D01*
X345357Y1562675D01*
X345441Y1563217D01*
X345566Y1563508D01*
X345774Y1563800D01*
X346066Y1564008D01*
X346357Y1564050D01*
X346649Y1563967D01*
X346857Y1563758D01*
G01X301299Y1564550D02*
Y1560550D01*
X308699D01*
G01X286016D02*
Y1563050D01*
X287057D01*
X287391Y1562925D01*
X287599Y1562758D01*
X287682Y1562425D01*
X287599Y1562092D01*
X287349Y1561883D01*
X287057Y1561758D01*
X286016D01*
G01X287057D02*
X287682Y1560550D01*
G01X290449D02*
Y1563050D01*
X288907Y1561258D01*
X290991D01*
G01X293549Y1560550D02*
Y1563050D01*
X292007Y1561258D01*
X294091D01*
G01X295357Y1561592D02*
X295649Y1561883D01*
X295899Y1562050D01*
X296232Y1562133D01*
X296524Y1562050D01*
X296732Y1561883D01*
X296899Y1561633D01*
X296941Y1561342D01*
X296899Y1561092D01*
X296732Y1560842D01*
X296482Y1560633D01*
X296191Y1560550D01*
X295857Y1560633D01*
X295566Y1560883D01*
X295399Y1561258D01*
X295357Y1561675D01*
X295441Y1562217D01*
X295566Y1562508D01*
X295774Y1562800D01*
X296066Y1563008D01*
X296357Y1563050D01*
X296649Y1562967D01*
X296857Y1562758D01*
G01X280499Y1564750D02*
X276499D01*
Y1557350D01*
G01X284499Y1564750D02*
X280499D01*
Y1557350D01*
G01X341517Y1585300D02*
Y1587800D01*
X342558D01*
X342892Y1587675D01*
X343100Y1587508D01*
X343183Y1587175D01*
X343100Y1586842D01*
X342850Y1586633D01*
X342558Y1586508D01*
X341517D01*
G01X342558D02*
X343183Y1585300D01*
G01X345950D02*
Y1587800D01*
X344408Y1586008D01*
X346492D01*
G01X348550Y1585300D02*
Y1587800D01*
X348050Y1587300D01*
G01Y1585300D02*
X349050D01*
G01X352150D02*
Y1587800D01*
X350608Y1586008D01*
X352692D01*
G01X320400Y1580600D02*
Y1584600D01*
X313000D01*
G01X309799Y1562050D02*
X323199D01*
G01X282483Y1594500D02*
Y1592708D01*
X282650Y1592333D01*
X282983Y1592083D01*
X283400Y1592000D01*
X283817Y1592083D01*
X284150Y1592333D01*
X284317Y1592708D01*
Y1594500D01*
G01X285708Y1594083D02*
X285958Y1594333D01*
X286250Y1594458D01*
X286583Y1594500D01*
X287000Y1594417D01*
X287292Y1594208D01*
X287375Y1593958D01*
X287333Y1593708D01*
X287167Y1593500D01*
X286333Y1593083D01*
X285958Y1592792D01*
X285708Y1592375D01*
X285625Y1592000D01*
X287375D01*
G01X289600Y1594500D02*
X289267Y1594417D01*
X289017Y1594208D01*
X288850Y1593958D01*
X288725Y1593625D01*
X288683Y1593250D01*
X288725Y1592875D01*
X288850Y1592542D01*
X289017Y1592292D01*
X289267Y1592083D01*
X289600Y1592000D01*
X289933Y1592083D01*
X290183Y1592292D01*
X290350Y1592542D01*
X290475Y1592875D01*
X290517Y1593250D01*
X290475Y1593625D01*
X290350Y1593958D01*
X290183Y1594208D01*
X289933Y1594417D01*
X289600Y1594500D01*
G01X287999Y1565250D02*
X289999Y1567250D01*
X291999Y1565250D01*
G01X295599D02*
Y1584450D01*
X284399D01*
Y1565250D01*
X295599D01*
G01X339500Y1975500D02*
Y1959400D01*
G01X332500D02*
Y1975500D01*
G01X339500Y1959400D02*
X332500D01*
G01X296708Y1927767D02*
X296583Y1927517D01*
X296500Y1927225D01*
Y1926892D01*
X296625Y1926517D01*
X296833Y1926225D01*
X297083Y1926017D01*
X297500Y1925850D01*
X297875Y1925808D01*
X298250Y1925892D01*
X298500Y1926017D01*
X298750Y1926267D01*
X298917Y1926558D01*
X299000Y1926850D01*
Y1927142D01*
X298917Y1927433D01*
X298792Y1927683D01*
X298625Y1927892D01*
G01X299000Y1929950D02*
X296500D01*
X297000Y1929450D01*
G01X299000D02*
Y1930450D01*
G01Y1933050D02*
X298958Y1933342D01*
X298833Y1933675D01*
X298625Y1933883D01*
X298333Y1933967D01*
X298042Y1933883D01*
X297792Y1933633D01*
X297667Y1933258D01*
Y1932842D01*
X297583Y1932592D01*
X297375Y1932383D01*
X297083Y1932300D01*
X296792Y1932425D01*
X296583Y1932717D01*
X296500Y1933050D01*
X296583Y1933383D01*
X296792Y1933675D01*
X297083Y1933800D01*
X297375Y1933717D01*
X297583Y1933508D01*
X297667Y1933258D01*
Y1932842D01*
X297792Y1932467D01*
X298042Y1932217D01*
X298333Y1932133D01*
X298625Y1932217D01*
X298833Y1932425D01*
X298958Y1932758D01*
X299000Y1933050D01*
G01Y1936067D02*
X298458Y1936150D01*
X298000Y1936275D01*
X297583Y1936442D01*
X297125Y1936650D01*
X296500Y1936983D01*
Y1935317D01*
G01X311208Y1914267D02*
X311083Y1914017D01*
X311000Y1913725D01*
Y1913392D01*
X311125Y1913017D01*
X311333Y1912725D01*
X311583Y1912517D01*
X312000Y1912350D01*
X312375Y1912308D01*
X312750Y1912392D01*
X313000Y1912517D01*
X313250Y1912767D01*
X313417Y1913058D01*
X313500Y1913350D01*
Y1913642D01*
X313417Y1913933D01*
X313292Y1914183D01*
X313125Y1914392D01*
G01X313500Y1916450D02*
X311000D01*
X311500Y1915950D01*
G01X313500D02*
Y1916950D01*
G01Y1919550D02*
X313458Y1919842D01*
X313333Y1920175D01*
X313125Y1920383D01*
X312833Y1920467D01*
X312542Y1920383D01*
X312292Y1920133D01*
X312167Y1919758D01*
Y1919342D01*
X312083Y1919092D01*
X311875Y1918883D01*
X311583Y1918800D01*
X311292Y1918925D01*
X311083Y1919217D01*
X311000Y1919550D01*
X311083Y1919883D01*
X311292Y1920175D01*
X311583Y1920300D01*
X311875Y1920217D01*
X312083Y1920008D01*
X312167Y1919758D01*
Y1919342D01*
X312292Y1918967D01*
X312542Y1918717D01*
X312833Y1918633D01*
X313125Y1918717D01*
X313333Y1918925D01*
X313458Y1919258D01*
X313500Y1919550D01*
G01Y1922650D02*
X311000D01*
X311500Y1922150D01*
G01X313500D02*
Y1923150D01*
G01X315940Y1956072D02*
X327340D01*
G01X315940Y1969472D02*
Y1956072D01*
G01X327340Y1969472D02*
X315940D01*
G01X327340Y1956072D02*
Y1969472D01*
G01X263600Y1940000D02*
X263267Y1940042D01*
X262975Y1940208D01*
X262725Y1940458D01*
X262558Y1940750D01*
X262475Y1941083D01*
Y1941417D01*
X262558Y1941750D01*
X262725Y1942042D01*
X262975Y1942292D01*
X263267Y1942458D01*
X263600Y1942500D01*
X263933Y1942458D01*
X264225Y1942292D01*
X264475Y1942042D01*
X264642Y1941750D01*
X264725Y1941417D01*
Y1941083D01*
X264642Y1940750D01*
X264475Y1940458D01*
X264225Y1940208D01*
X263933Y1940042D01*
X263600Y1940000D01*
G01X263933Y1940667D02*
X264433Y1940000D01*
G01X266700D02*
Y1942500D01*
X266200Y1942000D01*
G01Y1940000D02*
X267200D01*
G01X269800D02*
Y1942500D01*
X269300Y1942000D01*
G01Y1940000D02*
X270300D01*
G01X267777Y1935391D02*
X265977Y1933291D01*
X263777Y1935391D01*
G01X332000Y1975200D02*
X328000D01*
Y1967800D01*
G01X311500Y1968300D02*
X315500D01*
Y1975700D01*
G01X315921Y1942909D02*
Y1946909D01*
X308521D01*
G01X308077Y1968191D02*
Y1964191D01*
X315477D01*
G01X308077D02*
Y1960191D01*
X315477D01*
G01X308158Y1955328D02*
Y1951328D01*
X315558D01*
G01X315921Y1946909D02*
Y1950909D01*
X308521D01*
G01X284999Y1915067D02*
X282499D01*
Y1916108D01*
X282624Y1916442D01*
X282791Y1916650D01*
X283124Y1916733D01*
X283457Y1916650D01*
X283666Y1916400D01*
X283791Y1916108D01*
Y1915067D01*
G01Y1916108D02*
X284999Y1916733D01*
G01Y1919500D02*
X282499D01*
X284291Y1917958D01*
Y1920042D01*
G01X284999Y1922600D02*
X282499D01*
X284291Y1921058D01*
Y1923142D01*
G01X282916Y1924408D02*
X282666Y1924658D01*
X282541Y1924950D01*
X282499Y1925283D01*
X282582Y1925700D01*
X282791Y1925992D01*
X283041Y1926075D01*
X283291Y1926033D01*
X283499Y1925867D01*
X283916Y1925033D01*
X284207Y1924658D01*
X284624Y1924408D01*
X284999Y1924325D01*
Y1926075D01*
G01X286358Y1957028D02*
X282358D01*
Y1949628D01*
G01X288499Y1915067D02*
X285999D01*
Y1916108D01*
X286124Y1916442D01*
X286291Y1916650D01*
X286624Y1916733D01*
X286957Y1916650D01*
X287166Y1916400D01*
X287291Y1916108D01*
Y1915067D01*
G01Y1916108D02*
X288499Y1916733D01*
G01Y1919500D02*
X285999D01*
X287791Y1917958D01*
Y1920042D01*
G01X288499Y1922600D02*
X285999D01*
X287791Y1921058D01*
Y1923142D01*
G01X287999Y1924283D02*
X288291Y1924533D01*
X288457Y1924867D01*
X288499Y1925242D01*
X288457Y1925575D01*
X288249Y1925908D01*
X287999Y1926117D01*
X287749Y1926158D01*
X287457Y1926075D01*
X287249Y1925783D01*
X287166Y1925492D01*
Y1925117D01*
G01Y1925492D02*
X287041Y1925742D01*
X286832Y1925950D01*
X286582Y1926033D01*
X286332Y1925950D01*
X286124Y1925742D01*
X285999Y1925367D01*
X286041Y1924992D01*
X286207Y1924617D01*
G01X290358Y1957028D02*
X286358D01*
Y1949628D01*
G01X343516Y1946550D02*
Y1949050D01*
X344557D01*
X344891Y1948925D01*
X345099Y1948758D01*
X345182Y1948425D01*
X345099Y1948092D01*
X344849Y1947883D01*
X344557Y1947758D01*
X343516D01*
G01X344557D02*
X345182Y1946550D01*
G01X347949D02*
Y1949050D01*
X346407Y1947258D01*
X348491D01*
G01X351049Y1946550D02*
Y1949050D01*
X349507Y1947258D01*
X351591D01*
G01X354149Y1946550D02*
Y1949050D01*
X352607Y1947258D01*
X354691D01*
G01X341421Y1945409D02*
Y1949409D01*
X334021D01*
G01X343516Y1942050D02*
Y1944550D01*
X344557D01*
X344891Y1944425D01*
X345099Y1944258D01*
X345182Y1943925D01*
X345099Y1943592D01*
X344849Y1943383D01*
X344557Y1943258D01*
X343516D01*
G01X344557D02*
X345182Y1942050D01*
G01X347949D02*
Y1944550D01*
X346407Y1942758D01*
X348491D01*
G01X351049Y1942050D02*
Y1944550D01*
X349507Y1942758D01*
X351591D01*
G01X352732Y1942425D02*
X352982Y1942217D01*
X353274Y1942092D01*
X353649Y1942050D01*
X354024Y1942133D01*
X354316Y1942300D01*
X354524Y1942592D01*
X354566Y1942925D01*
X354482Y1943258D01*
X354274Y1943467D01*
X353982Y1943633D01*
X353691Y1943675D01*
X353399Y1943633D01*
X353024Y1943467D01*
X353149Y1944550D01*
X354274D01*
G01X341421Y1941409D02*
Y1945409D01*
X334021D01*
G01X323600Y1969900D02*
Y1973900D01*
X316200D01*
G01X326044Y1936381D02*
Y1934589D01*
X326211Y1934214D01*
X326544Y1933964D01*
X326961Y1933881D01*
X327378Y1933964D01*
X327711Y1934214D01*
X327878Y1934589D01*
Y1936381D01*
G01X330061Y1933881D02*
Y1936381D01*
X329561Y1935881D01*
G01Y1933881D02*
X330561D01*
G01X333161D02*
X333453Y1933923D01*
X333786Y1934048D01*
X333994Y1934256D01*
X334078Y1934548D01*
X333994Y1934839D01*
X333744Y1935089D01*
X333369Y1935214D01*
X332953D01*
X332703Y1935298D01*
X332494Y1935506D01*
X332411Y1935798D01*
X332536Y1936089D01*
X332828Y1936298D01*
X333161Y1936381D01*
X333494Y1936298D01*
X333786Y1936089D01*
X333911Y1935798D01*
X333828Y1935506D01*
X333619Y1935298D01*
X333369Y1935214D01*
X332953D01*
X332578Y1935089D01*
X332328Y1934839D01*
X332244Y1934548D01*
X332328Y1934256D01*
X332536Y1934048D01*
X332869Y1933923D01*
X333161Y1933881D01*
G01X317021Y1951909D02*
X330421D01*
G01X317021Y1941909D02*
Y1951909D01*
G01X330421Y1941909D02*
X317021D01*
G01X330421Y1951909D02*
Y1941909D01*
G01X282482Y1913050D02*
Y1911258D01*
X282649Y1910883D01*
X282982Y1910633D01*
X283399Y1910550D01*
X283816Y1910633D01*
X284149Y1910883D01*
X284316Y1911258D01*
Y1913050D01*
G01X286499Y1910550D02*
Y1913050D01*
X285999Y1912550D01*
G01Y1910550D02*
X286999D01*
G01X288807Y1911592D02*
X289099Y1911883D01*
X289349Y1912050D01*
X289682Y1912133D01*
X289974Y1912050D01*
X290182Y1911883D01*
X290349Y1911633D01*
X290391Y1911342D01*
X290349Y1911092D01*
X290182Y1910842D01*
X289932Y1910633D01*
X289641Y1910550D01*
X289307Y1910633D01*
X289016Y1910883D01*
X288849Y1911258D01*
X288807Y1911675D01*
X288891Y1912217D01*
X289016Y1912508D01*
X289224Y1912800D01*
X289516Y1913008D01*
X289807Y1913050D01*
X290099Y1912967D01*
X290307Y1912758D01*
G01X281149Y1932750D02*
Y1946150D01*
G01X291149Y1932750D02*
X281149D01*
G01X291149Y1946150D02*
Y1932750D01*
G01X281149Y1946150D02*
X291149D01*
G01X287777Y1957891D02*
X289777Y1959891D01*
X291777Y1957891D01*
G01X295377D02*
Y1977091D01*
X284177D01*
Y1957891D01*
X295377D01*
G01X294177Y1899463D02*
Y1901963D01*
G01X295927D02*
Y1899463D01*
G01Y1900713D02*
X294177D01*
G01X298152Y1899463D02*
Y1901963D01*
X297652Y1901463D01*
G01Y1899463D02*
X298652D01*
G01X300460Y1901546D02*
X300710Y1901796D01*
X301002Y1901921D01*
X301335Y1901963D01*
X301752Y1901880D01*
X302044Y1901671D01*
X302127Y1901421D01*
X302085Y1901171D01*
X301919Y1900963D01*
X301085Y1900546D01*
X300710Y1900255D01*
X300460Y1899838D01*
X300377Y1899463D01*
X302127D01*
G01X332500Y1975500D02*
X339500D01*
G01X286482Y1985550D02*
Y1983758D01*
X286649Y1983383D01*
X286982Y1983133D01*
X287399Y1983050D01*
X287816Y1983133D01*
X288149Y1983383D01*
X288316Y1983758D01*
Y1985550D01*
G01X290499Y1983050D02*
Y1985550D01*
X289999Y1985050D01*
G01Y1983050D02*
X290999D01*
G01X293516D02*
X293599Y1983592D01*
X293724Y1984050D01*
X293891Y1984467D01*
X294099Y1984925D01*
X294432Y1985550D01*
X292766D01*
G01X360483Y63000D02*
Y65500D01*
X361317D01*
X361650Y65375D01*
X361900Y65208D01*
X362108Y64958D01*
X362275Y64667D01*
X362317Y64250D01*
X362275Y63833D01*
X362108Y63542D01*
X361900Y63292D01*
X361650Y63125D01*
X361317Y63000D01*
X360483D01*
G01X363708Y65083D02*
X363958Y65333D01*
X364250Y65458D01*
X364583Y65500D01*
X365000Y65417D01*
X365292Y65208D01*
X365375Y64958D01*
X365333Y64708D01*
X365167Y64500D01*
X364333Y64083D01*
X363958Y63792D01*
X363708Y63375D01*
X363625Y63000D01*
X365375D01*
G01X366892Y63292D02*
X367183Y63083D01*
X367517Y63000D01*
X367850Y63083D01*
X368142Y63333D01*
X368350Y63708D01*
X368433Y64083D01*
Y64542D01*
X368350Y64917D01*
X368142Y65250D01*
X367892Y65417D01*
X367600Y65500D01*
X367267Y65417D01*
X367017Y65250D01*
X366850Y65000D01*
X366767Y64667D01*
X366850Y64375D01*
X367058Y64083D01*
X367308Y63917D01*
X367600Y63875D01*
X367933Y63958D01*
X368183Y64167D01*
X368433Y64542D01*
G01X356000Y56500D02*
X372100D01*
G01X356000Y49500D02*
Y56500D01*
G01X372100Y49500D02*
X356000D01*
G01X372100Y56500D02*
Y49500D01*
G01X412208Y35267D02*
X412083Y35017D01*
X412000Y34725D01*
Y34392D01*
X412125Y34017D01*
X412333Y33725D01*
X412583Y33517D01*
X413000Y33350D01*
X413375Y33308D01*
X413750Y33392D01*
X414000Y33517D01*
X414250Y33767D01*
X414417Y34058D01*
X414500Y34350D01*
Y34642D01*
X414417Y34933D01*
X414292Y35183D01*
X414125Y35392D01*
G01X414000Y36533D02*
X414292Y36783D01*
X414458Y37117D01*
X414500Y37492D01*
X414458Y37825D01*
X414250Y38158D01*
X414000Y38367D01*
X413750Y38408D01*
X413458Y38325D01*
X413250Y38033D01*
X413167Y37742D01*
Y37367D01*
G01Y37742D02*
X413042Y37992D01*
X412833Y38200D01*
X412583Y38283D01*
X412333Y38200D01*
X412125Y37992D01*
X412000Y37617D01*
X412042Y37242D01*
X412208Y36867D01*
G01X414208Y39842D02*
X414417Y40133D01*
X414500Y40467D01*
X414417Y40800D01*
X414167Y41092D01*
X413792Y41300D01*
X413417Y41383D01*
X412958D01*
X412583Y41300D01*
X412250Y41092D01*
X412083Y40842D01*
X412000Y40550D01*
X412083Y40217D01*
X412250Y39967D01*
X412500Y39800D01*
X412833Y39717D01*
X413125Y39800D01*
X413417Y40008D01*
X413583Y40258D01*
X413625Y40550D01*
X413542Y40883D01*
X413333Y41133D01*
X412958Y41383D01*
G01X414000Y42733D02*
X414292Y42983D01*
X414458Y43317D01*
X414500Y43692D01*
X414458Y44025D01*
X414250Y44358D01*
X414000Y44567D01*
X413750Y44608D01*
X413458Y44525D01*
X413250Y44233D01*
X413167Y43942D01*
Y43567D01*
G01Y43942D02*
X413042Y44192D01*
X412833Y44400D01*
X412583Y44483D01*
X412333Y44400D01*
X412125Y44192D01*
X412000Y43817D01*
X412042Y43442D01*
X412208Y43067D01*
G01X427963Y36147D02*
X427921Y35814D01*
X427755Y35522D01*
X427505Y35272D01*
X427213Y35105D01*
X426880Y35022D01*
X426546D01*
X426213Y35105D01*
X425921Y35272D01*
X425671Y35522D01*
X425505Y35814D01*
X425463Y36147D01*
X425505Y36480D01*
X425671Y36772D01*
X425921Y37022D01*
X426213Y37189D01*
X426546Y37272D01*
X426880D01*
X427213Y37189D01*
X427505Y37022D01*
X427755Y36772D01*
X427921Y36480D01*
X427963Y36147D01*
G01X427296Y36480D02*
X427963Y36980D01*
G01X427463Y38330D02*
X427755Y38580D01*
X427921Y38914D01*
X427963Y39289D01*
X427921Y39622D01*
X427713Y39955D01*
X427463Y40164D01*
X427213Y40205D01*
X426921Y40122D01*
X426713Y39830D01*
X426630Y39539D01*
Y39164D01*
G01Y39539D02*
X426505Y39789D01*
X426296Y39997D01*
X426046Y40080D01*
X425796Y39997D01*
X425588Y39789D01*
X425463Y39414D01*
X425505Y39039D01*
X425671Y38664D01*
G01X425463Y42347D02*
X425546Y42014D01*
X425755Y41764D01*
X426005Y41597D01*
X426338Y41472D01*
X426713Y41430D01*
X427088Y41472D01*
X427421Y41597D01*
X427671Y41764D01*
X427880Y42014D01*
X427963Y42347D01*
X427880Y42680D01*
X427671Y42930D01*
X427421Y43097D01*
X427088Y43222D01*
X426713Y43264D01*
X426338Y43222D01*
X426005Y43097D01*
X425755Y42930D01*
X425546Y42680D01*
X425463Y42347D01*
G01X397199Y33350D02*
Y44750D01*
G01X383799Y33350D02*
X397199D01*
G01X383799Y44750D02*
Y33350D01*
G01X397199Y44750D02*
X383799D01*
G01X410500Y33517D02*
X408000D01*
Y34558D01*
X408125Y34892D01*
X408292Y35100D01*
X408625Y35183D01*
X408958Y35100D01*
X409167Y34850D01*
X409292Y34558D01*
Y33517D01*
G01Y34558D02*
X410500Y35183D01*
G01X410125Y36533D02*
X410333Y36783D01*
X410458Y37075D01*
X410500Y37450D01*
X410417Y37825D01*
X410250Y38117D01*
X409958Y38325D01*
X409625Y38367D01*
X409292Y38283D01*
X409083Y38075D01*
X408917Y37783D01*
X408875Y37492D01*
X408917Y37200D01*
X409083Y36825D01*
X408000Y36950D01*
Y38075D01*
G01X410500Y40467D02*
X409958Y40550D01*
X409500Y40675D01*
X409083Y40842D01*
X408625Y41050D01*
X408000Y41383D01*
Y39717D01*
G01X410500Y43567D02*
X409958Y43650D01*
X409500Y43775D01*
X409083Y43942D01*
X408625Y44150D01*
X408000Y44483D01*
Y42817D01*
G01X365000Y48200D02*
X361000D01*
Y40800D01*
G01X418700Y32917D02*
X416200D01*
Y33958D01*
X416325Y34292D01*
X416492Y34500D01*
X416825Y34583D01*
X417158Y34500D01*
X417367Y34250D01*
X417492Y33958D01*
Y32917D01*
G01Y33958D02*
X418700Y34583D01*
G01X418325Y35933D02*
X418533Y36183D01*
X418658Y36475D01*
X418700Y36850D01*
X418617Y37225D01*
X418450Y37517D01*
X418158Y37725D01*
X417825Y37767D01*
X417492Y37683D01*
X417283Y37475D01*
X417117Y37183D01*
X417075Y36892D01*
X417117Y36600D01*
X417283Y36225D01*
X416200Y36350D01*
Y37475D01*
G01X417658Y39158D02*
X417367Y39450D01*
X417200Y39700D01*
X417117Y40033D01*
X417200Y40325D01*
X417367Y40533D01*
X417617Y40700D01*
X417908Y40742D01*
X418158Y40700D01*
X418408Y40533D01*
X418617Y40283D01*
X418700Y39992D01*
X418617Y39658D01*
X418367Y39367D01*
X417992Y39200D01*
X417575Y39158D01*
X417033Y39242D01*
X416742Y39367D01*
X416450Y39575D01*
X416242Y39867D01*
X416200Y40158D01*
X416283Y40450D01*
X416492Y40658D01*
G01X416617Y42258D02*
X416367Y42508D01*
X416242Y42800D01*
X416200Y43133D01*
X416283Y43550D01*
X416492Y43842D01*
X416742Y43925D01*
X416992Y43883D01*
X417200Y43717D01*
X417617Y42883D01*
X417908Y42508D01*
X418325Y42258D01*
X418700Y42175D01*
Y43925D01*
G01X376200Y44500D02*
Y48500D01*
X368800D01*
G01X400517Y59000D02*
Y61500D01*
X401558D01*
X401892Y61375D01*
X402100Y61208D01*
X402183Y60875D01*
X402100Y60542D01*
X401850Y60333D01*
X401558Y60208D01*
X400517D01*
G01X401558D02*
X402183Y59000D01*
G01X403533Y59500D02*
X403783Y59208D01*
X404117Y59042D01*
X404492Y59000D01*
X404825Y59042D01*
X405158Y59250D01*
X405367Y59500D01*
X405408Y59750D01*
X405325Y60042D01*
X405033Y60250D01*
X404742Y60333D01*
X404367D01*
G01X404742D02*
X404992Y60458D01*
X405200Y60667D01*
X405283Y60917D01*
X405200Y61167D01*
X404992Y61375D01*
X404617Y61500D01*
X404242Y61458D01*
X403867Y61292D01*
G01X407550Y61500D02*
X407217Y61417D01*
X406967Y61208D01*
X406800Y60958D01*
X406675Y60625D01*
X406633Y60250D01*
X406675Y59875D01*
X406800Y59542D01*
X406967Y59292D01*
X407217Y59083D01*
X407550Y59000D01*
X407883Y59083D01*
X408133Y59292D01*
X408300Y59542D01*
X408425Y59875D01*
X408467Y60250D01*
X408425Y60625D01*
X408300Y60958D01*
X408133Y61208D01*
X407883Y61417D01*
X407550Y61500D01*
G01X409733Y59375D02*
X409983Y59167D01*
X410275Y59042D01*
X410650Y59000D01*
X411025Y59083D01*
X411317Y59250D01*
X411525Y59542D01*
X411567Y59875D01*
X411483Y60208D01*
X411275Y60417D01*
X410983Y60583D01*
X410692Y60625D01*
X410400Y60583D01*
X410025Y60417D01*
X410150Y61500D01*
X411275D01*
G01X398799Y58050D02*
Y54050D01*
X406199D01*
G01X391516Y28550D02*
Y31050D01*
X392557D01*
X392891Y30925D01*
X393099Y30758D01*
X393182Y30425D01*
X393099Y30092D01*
X392849Y29883D01*
X392557Y29758D01*
X391516D01*
G01X392557D02*
X393182Y28550D01*
G01X394532Y29050D02*
X394782Y28758D01*
X395116Y28592D01*
X395491Y28550D01*
X395824Y28592D01*
X396157Y28800D01*
X396366Y29050D01*
X396407Y29300D01*
X396324Y29592D01*
X396032Y29800D01*
X395741Y29883D01*
X395366D01*
G01X395741D02*
X395991Y30008D01*
X396199Y30217D01*
X396282Y30467D01*
X396199Y30717D01*
X395991Y30925D01*
X395616Y31050D01*
X395241Y31008D01*
X394866Y30842D01*
G01X398549Y31050D02*
X398216Y30967D01*
X397966Y30758D01*
X397799Y30508D01*
X397674Y30175D01*
X397632Y29800D01*
X397674Y29425D01*
X397799Y29092D01*
X397966Y28842D01*
X398216Y28633D01*
X398549Y28550D01*
X398882Y28633D01*
X399132Y28842D01*
X399299Y29092D01*
X399424Y29425D01*
X399466Y29800D01*
X399424Y30175D01*
X399299Y30508D01*
X399132Y30758D01*
X398882Y30967D01*
X398549Y31050D01*
G01X400857Y29592D02*
X401149Y29883D01*
X401399Y30050D01*
X401732Y30133D01*
X402024Y30050D01*
X402232Y29883D01*
X402399Y29633D01*
X402441Y29342D01*
X402399Y29092D01*
X402232Y28842D01*
X401982Y28633D01*
X401691Y28550D01*
X401357Y28633D01*
X401066Y28883D01*
X400899Y29258D01*
X400857Y29675D01*
X400941Y30217D01*
X401066Y30508D01*
X401274Y30800D01*
X401566Y31008D01*
X401857Y31050D01*
X402149Y30967D01*
X402357Y30758D01*
G01X381299Y32550D02*
Y28550D01*
X388699D01*
G01X391516Y24050D02*
Y26550D01*
X392557D01*
X392891Y26425D01*
X393099Y26258D01*
X393182Y25925D01*
X393099Y25592D01*
X392849Y25383D01*
X392557Y25258D01*
X391516D01*
G01X392557D02*
X393182Y24050D01*
G01X394532Y24550D02*
X394782Y24258D01*
X395116Y24092D01*
X395491Y24050D01*
X395824Y24092D01*
X396157Y24300D01*
X396366Y24550D01*
X396407Y24800D01*
X396324Y25092D01*
X396032Y25300D01*
X395741Y25383D01*
X395366D01*
G01X395741D02*
X395991Y25508D01*
X396199Y25717D01*
X396282Y25967D01*
X396199Y26217D01*
X395991Y26425D01*
X395616Y26550D01*
X395241Y26508D01*
X394866Y26342D01*
G01X398549Y26550D02*
X398216Y26467D01*
X397966Y26258D01*
X397799Y26008D01*
X397674Y25675D01*
X397632Y25300D01*
X397674Y24925D01*
X397799Y24592D01*
X397966Y24342D01*
X398216Y24133D01*
X398549Y24050D01*
X398882Y24133D01*
X399132Y24342D01*
X399299Y24592D01*
X399424Y24925D01*
X399466Y25300D01*
X399424Y25675D01*
X399299Y26008D01*
X399132Y26258D01*
X398882Y26467D01*
X398549Y26550D01*
G01X401566Y24050D02*
X401649Y24592D01*
X401774Y25050D01*
X401941Y25467D01*
X402149Y25925D01*
X402482Y26550D01*
X400816D01*
G01X381299Y28050D02*
Y24050D01*
X388699D01*
G01X401999Y44750D02*
X397999D01*
Y37350D01*
G01X408017Y48500D02*
Y51000D01*
X409058D01*
X409392Y50875D01*
X409600Y50708D01*
X409683Y50375D01*
X409600Y50042D01*
X409350Y49833D01*
X409058Y49708D01*
X408017D01*
G01X409058D02*
X409683Y48500D01*
G01X411033Y49000D02*
X411283Y48708D01*
X411617Y48542D01*
X411992Y48500D01*
X412325Y48542D01*
X412658Y48750D01*
X412867Y49000D01*
X412908Y49250D01*
X412825Y49542D01*
X412533Y49750D01*
X412242Y49833D01*
X411867D01*
G01X412242D02*
X412492Y49958D01*
X412700Y50167D01*
X412783Y50417D01*
X412700Y50667D01*
X412492Y50875D01*
X412117Y51000D01*
X411742Y50958D01*
X411367Y50792D01*
G01X415050Y51000D02*
X414717Y50917D01*
X414467Y50708D01*
X414300Y50458D01*
X414175Y50125D01*
X414133Y49750D01*
X414175Y49375D01*
X414300Y49042D01*
X414467Y48792D01*
X414717Y48583D01*
X415050Y48500D01*
X415383Y48583D01*
X415633Y48792D01*
X415800Y49042D01*
X415925Y49375D01*
X415967Y49750D01*
X415925Y50125D01*
X415800Y50458D01*
X415633Y50708D01*
X415383Y50917D01*
X415050Y51000D01*
G01X417442Y48792D02*
X417733Y48583D01*
X418067Y48500D01*
X418400Y48583D01*
X418692Y48833D01*
X418900Y49208D01*
X418983Y49583D01*
Y50042D01*
X418900Y50417D01*
X418692Y50750D01*
X418442Y50917D01*
X418150Y51000D01*
X417817Y50917D01*
X417567Y50750D01*
X417400Y50500D01*
X417317Y50167D01*
X417400Y49875D01*
X417608Y49583D01*
X417858Y49417D01*
X418150Y49375D01*
X418483Y49458D01*
X418733Y49667D01*
X418983Y50042D01*
G01X398799Y53050D02*
Y49050D01*
X406199D01*
G01X371516Y60550D02*
Y63050D01*
X372557D01*
X372891Y62925D01*
X373099Y62758D01*
X373182Y62425D01*
X373099Y62092D01*
X372849Y61883D01*
X372557Y61758D01*
X371516D01*
G01X372557D02*
X373182Y60550D01*
G01X375949D02*
Y63050D01*
X374407Y61258D01*
X376491D01*
G01X378466Y60550D02*
X378549Y61092D01*
X378674Y61550D01*
X378841Y61967D01*
X379049Y62425D01*
X379382Y63050D01*
X377716D01*
G01X380857Y61592D02*
X381149Y61883D01*
X381399Y62050D01*
X381732Y62133D01*
X382024Y62050D01*
X382232Y61883D01*
X382399Y61633D01*
X382441Y61342D01*
X382399Y61092D01*
X382232Y60842D01*
X381982Y60633D01*
X381691Y60550D01*
X381357Y60633D01*
X381066Y60883D01*
X380899Y61258D01*
X380857Y61675D01*
X380941Y62217D01*
X381066Y62508D01*
X381274Y62800D01*
X381566Y63008D01*
X381857Y63050D01*
X382149Y62967D01*
X382357Y62758D01*
G01X373299Y55050D02*
Y51050D01*
X380699D01*
G01X371516Y64550D02*
Y67050D01*
X372557D01*
X372891Y66925D01*
X373099Y66758D01*
X373182Y66425D01*
X373099Y66092D01*
X372849Y65883D01*
X372557Y65758D01*
X371516D01*
G01X372557D02*
X373182Y64550D01*
G01X375949D02*
Y67050D01*
X374407Y65258D01*
X376491D01*
G01X378466Y64550D02*
X378549Y65092D01*
X378674Y65550D01*
X378841Y65967D01*
X379049Y66425D01*
X379382Y67050D01*
X377716D01*
G01X381566Y64550D02*
X381649Y65092D01*
X381774Y65550D01*
X381941Y65967D01*
X382149Y66425D01*
X382482Y67050D01*
X380816D01*
G01X373299Y59050D02*
Y55050D01*
X380699D01*
G01X423000Y33517D02*
X420500D01*
Y34558D01*
X420625Y34892D01*
X420792Y35100D01*
X421125Y35183D01*
X421458Y35100D01*
X421667Y34850D01*
X421792Y34558D01*
Y33517D01*
G01Y34558D02*
X423000Y35183D01*
G01Y37950D02*
X420500D01*
X422292Y36408D01*
Y38492D01*
G01X423000Y40550D02*
X422958Y40842D01*
X422833Y41175D01*
X422625Y41383D01*
X422333Y41467D01*
X422042Y41383D01*
X421792Y41133D01*
X421667Y40758D01*
Y40342D01*
X421583Y40092D01*
X421375Y39883D01*
X421083Y39800D01*
X420792Y39925D01*
X420583Y40217D01*
X420500Y40550D01*
X420583Y40883D01*
X420792Y41175D01*
X421083Y41300D01*
X421375Y41217D01*
X421583Y41008D01*
X421667Y40758D01*
Y40342D01*
X421792Y39967D01*
X422042Y39717D01*
X422333Y39633D01*
X422625Y39717D01*
X422833Y39925D01*
X422958Y40258D01*
X423000Y40550D01*
G01X420500Y43650D02*
X420583Y43317D01*
X420792Y43067D01*
X421042Y42900D01*
X421375Y42775D01*
X421750Y42733D01*
X422125Y42775D01*
X422458Y42900D01*
X422708Y43067D01*
X422917Y43317D01*
X423000Y43650D01*
X422917Y43983D01*
X422708Y44233D01*
X422458Y44400D01*
X422125Y44525D01*
X421750Y44567D01*
X421375Y44525D01*
X421042Y44400D01*
X420792Y44233D01*
X420583Y43983D01*
X420500Y43650D01*
G01X380800Y40300D02*
Y44300D01*
X373400D01*
G01X357699Y59550D02*
X344299D01*
G01X357699Y69550D02*
Y59550D01*
G01X344299D02*
Y69550D01*
G01X385983Y64500D02*
Y62708D01*
X386150Y62333D01*
X386483Y62083D01*
X386900Y62000D01*
X387317Y62083D01*
X387650Y62333D01*
X387817Y62708D01*
Y64500D01*
G01X390500Y62000D02*
Y64500D01*
X388958Y62708D01*
X391042D01*
G01X392183Y62375D02*
X392433Y62167D01*
X392725Y62042D01*
X393100Y62000D01*
X393475Y62083D01*
X393767Y62250D01*
X393975Y62542D01*
X394017Y62875D01*
X393933Y63208D01*
X393725Y63417D01*
X393433Y63583D01*
X393142Y63625D01*
X392850Y63583D01*
X392475Y63417D01*
X392600Y64500D01*
X393725D01*
G01X397699Y48550D02*
X384299D01*
G01X397699Y58550D02*
Y48550D01*
G01X384299Y58550D02*
X397699D01*
G01X384299Y48550D02*
Y58550D01*
G01X368483Y15500D02*
Y13708D01*
X368650Y13333D01*
X368983Y13083D01*
X369400Y13000D01*
X369817Y13083D01*
X370150Y13333D01*
X370317Y13708D01*
Y15500D01*
G01X373000Y13000D02*
Y15500D01*
X371458Y13708D01*
X373542D01*
G01X376100Y13000D02*
Y15500D01*
X374558Y13708D01*
X376642D01*
G01X364499Y18250D02*
X366499Y20250D01*
X368499Y18250D01*
G01X372099D02*
Y37450D01*
X360899D01*
Y18250D01*
X372099D01*
G01X369708Y88767D02*
X369583Y88517D01*
X369500Y88225D01*
Y87892D01*
X369625Y87517D01*
X369833Y87225D01*
X370083Y87017D01*
X370500Y86850D01*
X370875Y86808D01*
X371250Y86892D01*
X371500Y87017D01*
X371750Y87267D01*
X371917Y87558D01*
X372000Y87850D01*
Y88142D01*
X371917Y88433D01*
X371792Y88683D01*
X371625Y88892D01*
G01X371500Y90033D02*
X371792Y90283D01*
X371958Y90617D01*
X372000Y90992D01*
X371958Y91325D01*
X371750Y91658D01*
X371500Y91867D01*
X371250Y91908D01*
X370958Y91825D01*
X370750Y91533D01*
X370667Y91242D01*
Y90867D01*
G01Y91242D02*
X370542Y91492D01*
X370333Y91700D01*
X370083Y91783D01*
X369833Y91700D01*
X369625Y91492D01*
X369500Y91117D01*
X369542Y90742D01*
X369708Y90367D01*
G01X372000Y93967D02*
X371458Y94050D01*
X371000Y94175D01*
X370583Y94342D01*
X370125Y94550D01*
X369500Y94883D01*
Y93217D01*
G01X372000Y97150D02*
X371958Y97442D01*
X371833Y97775D01*
X371625Y97983D01*
X371333Y98067D01*
X371042Y97983D01*
X370792Y97733D01*
X370667Y97358D01*
Y96942D01*
X370583Y96692D01*
X370375Y96483D01*
X370083Y96400D01*
X369792Y96525D01*
X369583Y96817D01*
X369500Y97150D01*
X369583Y97483D01*
X369792Y97775D01*
X370083Y97900D01*
X370375Y97817D01*
X370583Y97608D01*
X370667Y97358D01*
Y96942D01*
X370792Y96567D01*
X371042Y96317D01*
X371333Y96233D01*
X371625Y96317D01*
X371833Y96525D01*
X371958Y96858D01*
X372000Y97150D01*
G01X382208Y72767D02*
X382083Y72517D01*
X382000Y72225D01*
Y71892D01*
X382125Y71517D01*
X382333Y71225D01*
X382583Y71017D01*
X383000Y70850D01*
X383375Y70808D01*
X383750Y70892D01*
X384000Y71017D01*
X384250Y71267D01*
X384417Y71558D01*
X384500Y71850D01*
Y72142D01*
X384417Y72433D01*
X384292Y72683D01*
X384125Y72892D01*
G01X384000Y74033D02*
X384292Y74283D01*
X384458Y74617D01*
X384500Y74992D01*
X384458Y75325D01*
X384250Y75658D01*
X384000Y75867D01*
X383750Y75908D01*
X383458Y75825D01*
X383250Y75533D01*
X383167Y75242D01*
Y74867D01*
G01Y75242D02*
X383042Y75492D01*
X382833Y75700D01*
X382583Y75783D01*
X382333Y75700D01*
X382125Y75492D01*
X382000Y75117D01*
X382042Y74742D01*
X382208Y74367D01*
G01X384000Y77133D02*
X384292Y77383D01*
X384458Y77717D01*
X384500Y78092D01*
X384458Y78425D01*
X384250Y78758D01*
X384000Y78967D01*
X383750Y79008D01*
X383458Y78925D01*
X383250Y78633D01*
X383167Y78342D01*
Y77967D01*
G01Y78342D02*
X383042Y78592D01*
X382833Y78800D01*
X382583Y78883D01*
X382333Y78800D01*
X382125Y78592D01*
X382000Y78217D01*
X382042Y77842D01*
X382208Y77467D01*
G01X384208Y80442D02*
X384417Y80733D01*
X384500Y81067D01*
X384417Y81400D01*
X384167Y81692D01*
X383792Y81900D01*
X383417Y81983D01*
X382958D01*
X382583Y81900D01*
X382250Y81692D01*
X382083Y81442D01*
X382000Y81150D01*
X382083Y80817D01*
X382250Y80567D01*
X382500Y80400D01*
X382833Y80317D01*
X383125Y80400D01*
X383417Y80608D01*
X383583Y80858D01*
X383625Y81150D01*
X383542Y81483D01*
X383333Y81733D01*
X382958Y81983D01*
G01X372708Y72267D02*
X372583Y72017D01*
X372500Y71725D01*
Y71392D01*
X372625Y71017D01*
X372833Y70725D01*
X373083Y70517D01*
X373500Y70350D01*
X373875Y70308D01*
X374250Y70392D01*
X374500Y70517D01*
X374750Y70767D01*
X374917Y71058D01*
X375000Y71350D01*
Y71642D01*
X374917Y71933D01*
X374792Y72183D01*
X374625Y72392D01*
G01X374500Y73533D02*
X374792Y73783D01*
X374958Y74117D01*
X375000Y74492D01*
X374958Y74825D01*
X374750Y75158D01*
X374500Y75367D01*
X374250Y75408D01*
X373958Y75325D01*
X373750Y75033D01*
X373667Y74742D01*
Y74367D01*
G01Y74742D02*
X373542Y74992D01*
X373333Y75200D01*
X373083Y75283D01*
X372833Y75200D01*
X372625Y74992D01*
X372500Y74617D01*
X372542Y74242D01*
X372708Y73867D01*
G01X372917Y76758D02*
X372667Y77008D01*
X372542Y77300D01*
X372500Y77633D01*
X372583Y78050D01*
X372792Y78342D01*
X373042Y78425D01*
X373292Y78383D01*
X373500Y78217D01*
X373917Y77383D01*
X374208Y77008D01*
X374625Y76758D01*
X375000Y76675D01*
Y78425D01*
G01Y81150D02*
X372500D01*
X374292Y79608D01*
Y81692D01*
G01X349400Y113500D02*
X349067Y113542D01*
X348775Y113708D01*
X348525Y113958D01*
X348358Y114250D01*
X348275Y114583D01*
Y114917D01*
X348358Y115250D01*
X348525Y115542D01*
X348775Y115792D01*
X349067Y115958D01*
X349400Y116000D01*
X349733Y115958D01*
X350025Y115792D01*
X350275Y115542D01*
X350442Y115250D01*
X350525Y114917D01*
Y114583D01*
X350442Y114250D01*
X350275Y113958D01*
X350025Y113708D01*
X349733Y113542D01*
X349400Y113500D01*
G01X349733Y114167D02*
X350233Y113500D01*
G01X351708Y115583D02*
X351958Y115833D01*
X352250Y115958D01*
X352583Y116000D01*
X353000Y115917D01*
X353292Y115708D01*
X353375Y115458D01*
X353333Y115208D01*
X353167Y115000D01*
X352333Y114583D01*
X351958Y114292D01*
X351708Y113875D01*
X351625Y113500D01*
X353375D01*
G01X354892Y113792D02*
X355183Y113583D01*
X355517Y113500D01*
X355850Y113583D01*
X356142Y113833D01*
X356350Y114208D01*
X356433Y114583D01*
Y115042D01*
X356350Y115417D01*
X356142Y115750D01*
X355892Y115917D01*
X355600Y116000D01*
X355267Y115917D01*
X355017Y115750D01*
X354850Y115500D01*
X354767Y115167D01*
X354850Y114875D01*
X355058Y114583D01*
X355308Y114417D01*
X355600Y114375D01*
X355933Y114458D01*
X356183Y114667D01*
X356433Y115042D01*
G01X353983Y75000D02*
Y73208D01*
X354150Y72833D01*
X354483Y72583D01*
X354900Y72500D01*
X355317Y72583D01*
X355650Y72833D01*
X355817Y73208D01*
Y75000D01*
G01X358500Y72500D02*
Y75000D01*
X356958Y73208D01*
X359042D01*
G01X360183Y73000D02*
X360433Y72708D01*
X360767Y72542D01*
X361142Y72500D01*
X361475Y72542D01*
X361808Y72750D01*
X362017Y73000D01*
X362058Y73250D01*
X361975Y73542D01*
X361683Y73750D01*
X361392Y73833D01*
X361017D01*
G01X361392D02*
X361642Y73958D01*
X361850Y74167D01*
X361933Y74417D01*
X361850Y74667D01*
X361642Y74875D01*
X361267Y75000D01*
X360892Y74958D01*
X360517Y74792D01*
G01X344299Y69550D02*
X357699D01*
G01X351608Y351267D02*
X351483Y351017D01*
X351400Y350725D01*
Y350392D01*
X351525Y350017D01*
X351733Y349725D01*
X351983Y349517D01*
X352400Y349350D01*
X352775Y349308D01*
X353150Y349392D01*
X353400Y349517D01*
X353650Y349767D01*
X353817Y350058D01*
X353900Y350350D01*
Y350642D01*
X353817Y350933D01*
X353692Y351183D01*
X353525Y351392D01*
G01X353400Y352533D02*
X353692Y352783D01*
X353858Y353117D01*
X353900Y353492D01*
X353858Y353825D01*
X353650Y354158D01*
X353400Y354367D01*
X353150Y354408D01*
X352858Y354325D01*
X352650Y354033D01*
X352567Y353742D01*
Y353367D01*
G01Y353742D02*
X352442Y353992D01*
X352233Y354200D01*
X351983Y354283D01*
X351733Y354200D01*
X351525Y353992D01*
X351400Y353617D01*
X351442Y353242D01*
X351608Y352867D01*
G01X353900Y356467D02*
X353358Y356550D01*
X352900Y356675D01*
X352483Y356842D01*
X352025Y357050D01*
X351400Y357383D01*
Y355717D01*
G01X353400Y358733D02*
X353692Y358983D01*
X353858Y359317D01*
X353900Y359692D01*
X353858Y360025D01*
X353650Y360358D01*
X353400Y360567D01*
X353150Y360608D01*
X352858Y360525D01*
X352650Y360233D01*
X352567Y359942D01*
Y359567D01*
G01Y359942D02*
X352442Y360192D01*
X352233Y360400D01*
X351983Y360483D01*
X351733Y360400D01*
X351525Y360192D01*
X351400Y359817D01*
X351442Y359442D01*
X351608Y359067D01*
G01X349400Y352400D02*
X349358Y352067D01*
X349192Y351775D01*
X348942Y351525D01*
X348650Y351358D01*
X348317Y351275D01*
X347983D01*
X347650Y351358D01*
X347358Y351525D01*
X347108Y351775D01*
X346942Y352067D01*
X346900Y352400D01*
X346942Y352733D01*
X347108Y353025D01*
X347358Y353275D01*
X347650Y353442D01*
X347983Y353525D01*
X348317D01*
X348650Y353442D01*
X348942Y353275D01*
X349192Y353025D01*
X349358Y352733D01*
X349400Y352400D01*
G01X348733Y352733D02*
X349400Y353233D01*
G01X347317Y354708D02*
X347067Y354958D01*
X346942Y355250D01*
X346900Y355583D01*
X346983Y356000D01*
X347192Y356292D01*
X347442Y356375D01*
X347692Y356333D01*
X347900Y356167D01*
X348317Y355333D01*
X348608Y354958D01*
X349025Y354708D01*
X349400Y354625D01*
Y356375D01*
G01X346900Y358600D02*
X346983Y358267D01*
X347192Y358017D01*
X347442Y357850D01*
X347775Y357725D01*
X348150Y357683D01*
X348525Y357725D01*
X348858Y357850D01*
X349108Y358017D01*
X349317Y358267D01*
X349400Y358600D01*
X349317Y358933D01*
X349108Y359183D01*
X348858Y359350D01*
X348525Y359475D01*
X348150Y359517D01*
X347775Y359475D01*
X347442Y359350D01*
X347192Y359183D01*
X346983Y358933D01*
X346900Y358600D01*
G01X357516Y743550D02*
Y746050D01*
X358557D01*
X358891Y745925D01*
X359099Y745758D01*
X359182Y745425D01*
X359099Y745092D01*
X358849Y744883D01*
X358557Y744758D01*
X357516D01*
G01X358557D02*
X359182Y743550D01*
G01X361949D02*
Y746050D01*
X360407Y744258D01*
X362491D01*
G01X363632Y743925D02*
X363882Y743717D01*
X364174Y743592D01*
X364549Y743550D01*
X364924Y743633D01*
X365216Y743800D01*
X365424Y744092D01*
X365466Y744425D01*
X365382Y744758D01*
X365174Y744967D01*
X364882Y745133D01*
X364591Y745175D01*
X364299Y745133D01*
X363924Y744967D01*
X364049Y746050D01*
X365174D01*
G01X368149Y743550D02*
Y746050D01*
X366607Y744258D01*
X368691D01*
G01X357516Y739550D02*
Y742050D01*
X358557D01*
X358891Y741925D01*
X359099Y741758D01*
X359182Y741425D01*
X359099Y741092D01*
X358849Y740883D01*
X358557Y740758D01*
X357516D01*
G01X358557D02*
X359182Y739550D01*
G01X361949D02*
Y742050D01*
X360407Y740258D01*
X362491D01*
G01X363632Y739925D02*
X363882Y739717D01*
X364174Y739592D01*
X364549Y739550D01*
X364924Y739633D01*
X365216Y739800D01*
X365424Y740092D01*
X365466Y740425D01*
X365382Y740758D01*
X365174Y740967D01*
X364882Y741133D01*
X364591Y741175D01*
X364299Y741133D01*
X363924Y740967D01*
X364049Y742050D01*
X365174D01*
G01X366732Y739925D02*
X366982Y739717D01*
X367274Y739592D01*
X367649Y739550D01*
X368024Y739633D01*
X368316Y739800D01*
X368524Y740092D01*
X368566Y740425D01*
X368482Y740758D01*
X368274Y740967D01*
X367982Y741133D01*
X367691Y741175D01*
X367399Y741133D01*
X367024Y740967D01*
X367149Y742050D01*
X368274D01*
G01X352000Y738983D02*
X353792D01*
X354167Y739150D01*
X354417Y739483D01*
X354500Y739900D01*
X354417Y740317D01*
X354167Y740650D01*
X353792Y740817D01*
X352000D01*
G01X352417Y742208D02*
X352167Y742458D01*
X352042Y742750D01*
X352000Y743083D01*
X352083Y743500D01*
X352292Y743792D01*
X352542Y743875D01*
X352792Y743833D01*
X353000Y743667D01*
X353417Y742833D01*
X353708Y742458D01*
X354125Y742208D01*
X354500Y742125D01*
Y743875D01*
G01Y746017D02*
X353958Y746100D01*
X353500Y746225D01*
X353083Y746392D01*
X352625Y746600D01*
X352000Y746933D01*
Y745267D01*
G01X400999Y1283050D02*
Y1293050D01*
G01X407999D02*
Y1283050D01*
G01Y1288050D02*
X400999D01*
G01X415099Y1283050D02*
X414099Y1283217D01*
X413099Y1283883D01*
X412432Y1285050D01*
X412099Y1286383D01*
X412432Y1287717D01*
X413099Y1288883D01*
X414099Y1289550D01*
X415099Y1289716D01*
X416099Y1289550D01*
X417099Y1288883D01*
X417766Y1287717D01*
X417932Y1286383D01*
X417766Y1285050D01*
X417099Y1283883D01*
X416099Y1283217D01*
X415099Y1283050D01*
G01X422866D02*
Y1289716D01*
G01Y1288050D02*
X423532Y1288883D01*
X424532Y1289550D01*
X425866Y1289716D01*
X427032Y1289550D01*
X428032Y1288883D01*
X428532Y1287717D01*
Y1283050D01*
G01X433799Y1287550D02*
X439132D01*
X438632Y1288717D01*
X437799Y1289383D01*
X436632Y1289716D01*
X435466Y1289550D01*
X434466Y1289050D01*
X433799Y1287883D01*
X433466Y1286883D01*
Y1285883D01*
X433799Y1284883D01*
X434632Y1283883D01*
X435632Y1283217D01*
X436799Y1283050D01*
X437966Y1283383D01*
X439132Y1284383D01*
G01X443399Y1280050D02*
X444399Y1279717D01*
X445732Y1280050D01*
X446566Y1280717D01*
X447232Y1281550D01*
X448232Y1284216D01*
X450399Y1289716D01*
G01X445066D02*
X448232Y1284216D01*
G01X469432Y1288383D02*
X470099Y1288883D01*
X470599Y1289716D01*
X470932Y1290883D01*
X470599Y1291883D01*
X469932Y1292550D01*
X468766Y1293050D01*
X464266D01*
Y1283050D01*
X469766D01*
X470932Y1283717D01*
X471599Y1284717D01*
X471932Y1285883D01*
X471599Y1287050D01*
X470599Y1288050D01*
X469432Y1288383D01*
X464266D01*
G01X481699Y1283050D02*
Y1289716D01*
G01Y1288550D02*
X481032Y1289217D01*
X480032Y1289550D01*
X478866Y1289716D01*
X477699Y1289383D01*
X476699Y1288717D01*
X476032Y1287717D01*
X475699Y1286383D01*
X476032Y1285050D01*
X476699Y1284050D01*
X477699Y1283383D01*
X478866Y1283050D01*
X480032Y1283217D01*
X481032Y1283717D01*
X481699Y1284383D01*
G01X492299Y1293050D02*
Y1283050D01*
G01Y1284550D02*
X491632Y1283717D01*
X490632Y1283217D01*
X489466Y1283050D01*
X488132Y1283383D01*
X487132Y1284216D01*
X486466Y1285217D01*
X486299Y1286383D01*
X486466Y1287550D01*
X487132Y1288550D01*
X488132Y1289383D01*
X489466Y1289716D01*
X490632Y1289550D01*
X491466Y1289217D01*
X492299Y1288550D01*
G01X497566Y1280550D02*
X498732Y1279883D01*
X500066Y1279717D01*
X501232Y1279883D01*
X502232Y1280717D01*
X502899Y1281883D01*
Y1289716D01*
G01Y1288383D02*
X502232Y1289050D01*
X501232Y1289550D01*
X500066Y1289716D01*
X498732Y1289383D01*
X497899Y1288717D01*
X497232Y1287550D01*
X496899Y1286383D01*
X497066Y1285383D01*
X497732Y1284216D01*
X498732Y1283383D01*
X500066Y1283050D01*
X501066Y1283217D01*
X502232Y1283883D01*
X502899Y1284550D01*
G01X507999Y1287550D02*
X513332D01*
X512832Y1288717D01*
X511999Y1289383D01*
X510832Y1289716D01*
X509666Y1289550D01*
X508666Y1289050D01*
X507999Y1287883D01*
X507666Y1286883D01*
Y1285883D01*
X507999Y1284883D01*
X508832Y1283883D01*
X509832Y1283217D01*
X510999Y1283050D01*
X512166Y1283383D01*
X513332Y1284383D01*
G01X518766Y1283050D02*
Y1289716D01*
G01Y1288383D02*
X519599Y1289050D01*
X520432Y1289550D01*
X521599Y1289716D01*
X522432Y1289550D01*
X523432Y1289050D01*
G01X538632Y1283050D02*
Y1293050D01*
X541966D01*
X543299Y1292550D01*
X544299Y1291883D01*
X545132Y1290883D01*
X545799Y1289716D01*
X545966Y1288050D01*
X545799Y1286383D01*
X545132Y1285217D01*
X544299Y1284216D01*
X543299Y1283550D01*
X541966Y1283050D01*
X538632D01*
G01X549566D02*
Y1293050D01*
X553566D01*
X554899Y1292550D01*
X555899Y1291383D01*
X556232Y1290050D01*
X555899Y1288717D01*
X555066Y1287717D01*
X553566Y1287216D01*
X549566D01*
G01X564832Y1288383D02*
X565499Y1288883D01*
X565999Y1289716D01*
X566332Y1290883D01*
X565999Y1291883D01*
X565332Y1292550D01*
X564166Y1293050D01*
X559666D01*
Y1283050D01*
X565166D01*
X566332Y1283717D01*
X566999Y1284717D01*
X567332Y1285883D01*
X566999Y1287050D01*
X565999Y1288050D01*
X564832Y1288383D01*
X559666D01*
G01X581366Y1293050D02*
Y1283050D01*
X588032D01*
G01X595299D02*
X594299Y1283217D01*
X593299Y1283883D01*
X592632Y1285050D01*
X592299Y1286383D01*
X592632Y1287717D01*
X593299Y1288883D01*
X594299Y1289550D01*
X595299Y1289716D01*
X596299Y1289550D01*
X597299Y1288883D01*
X597966Y1287717D01*
X598132Y1286383D01*
X597966Y1285050D01*
X597299Y1283883D01*
X596299Y1283217D01*
X595299Y1283050D01*
G01X601732Y1289716D02*
X603732Y1283050D01*
X605899Y1289716D01*
X608066Y1283050D01*
X610066Y1289716D01*
G01X623766Y1293050D02*
Y1283050D01*
X630432D01*
G01X637699D02*
X636699Y1283217D01*
X635699Y1283883D01*
X635032Y1285050D01*
X634699Y1286383D01*
X635032Y1287717D01*
X635699Y1288883D01*
X636699Y1289550D01*
X637699Y1289716D01*
X638699Y1289550D01*
X639699Y1288883D01*
X640366Y1287717D01*
X640532Y1286383D01*
X640366Y1285050D01*
X639699Y1283883D01*
X638699Y1283217D01*
X637699Y1283050D01*
G01X645799Y1284216D02*
X646632Y1283550D01*
X647799Y1283050D01*
X648799D01*
X649799Y1283383D01*
X650466Y1283883D01*
X650799Y1284550D01*
X650632Y1285550D01*
X649966Y1286050D01*
X646965Y1287050D01*
X646299Y1288217D01*
X646632Y1289050D01*
X647299Y1289550D01*
X648299Y1289716D01*
X649299Y1289550D01*
X650299Y1289050D01*
G01X656399Y1284216D02*
X657232Y1283550D01*
X658399Y1283050D01*
X659399D01*
X660399Y1283383D01*
X661066Y1283883D01*
X661399Y1284550D01*
X661232Y1285550D01*
X660566Y1286050D01*
X657565Y1287050D01*
X656899Y1288217D01*
X657232Y1289050D01*
X657899Y1289550D01*
X658899Y1289716D01*
X659899Y1289550D01*
X660899Y1289050D01*
G01X402499Y1268050D02*
Y1278050D01*
X400499Y1276050D01*
G01Y1268050D02*
X404499D01*
G01X415099D02*
Y1278050D01*
X408932Y1270883D01*
X417266D01*
G01X420032Y1269550D02*
X421032Y1268717D01*
X422199Y1268217D01*
X423699Y1268050D01*
X425199Y1268383D01*
X426366Y1269050D01*
X427199Y1270217D01*
X427366Y1271550D01*
X427032Y1272883D01*
X426199Y1273717D01*
X425032Y1274383D01*
X423866Y1274550D01*
X422699Y1274383D01*
X421199Y1273717D01*
X421699Y1278050D01*
X426199D01*
G01X436299Y1268050D02*
Y1278050D01*
X430132Y1270883D01*
X438466D01*
G01X441232Y1269550D02*
X442232Y1268717D01*
X443399Y1268217D01*
X444899Y1268050D01*
X446399Y1268383D01*
X447566Y1269050D01*
X448399Y1270217D01*
X448566Y1271550D01*
X448232Y1272883D01*
X447399Y1273717D01*
X446232Y1274383D01*
X445066Y1274550D01*
X443899Y1274383D01*
X442399Y1273717D01*
X442899Y1278050D01*
X447399D01*
G01X453332Y1271383D02*
X457666D01*
G01X462599Y1269383D02*
X463932Y1268550D01*
X465432Y1268050D01*
X466766D01*
X468099Y1268550D01*
X469099Y1269383D01*
X469599Y1270550D01*
X469266Y1271716D01*
X468432Y1272717D01*
X466932Y1273383D01*
X464932Y1273717D01*
X463766Y1274383D01*
X463266Y1275550D01*
X463599Y1276717D01*
X464432Y1277550D01*
X465599Y1278050D01*
X466766D01*
X467932Y1277717D01*
X468932Y1276883D01*
G01X472532Y1268050D02*
X476699Y1278050D01*
X480866Y1268050D01*
G01X479366Y1271550D02*
X474032D01*
G01X406400Y1253100D02*
Y1263100D01*
X400233Y1255933D01*
X408567D01*
G01X415000Y1253100D02*
X416167Y1253267D01*
X417500Y1253767D01*
X418333Y1254600D01*
X418667Y1255767D01*
X418333Y1256933D01*
X417333Y1257933D01*
X415833Y1258433D01*
X414167D01*
X413167Y1258767D01*
X412333Y1259600D01*
X412000Y1260767D01*
X412500Y1261933D01*
X413666Y1262767D01*
X415000Y1263100D01*
X416333Y1262767D01*
X417500Y1261933D01*
X418000Y1260767D01*
X417667Y1259600D01*
X416833Y1258767D01*
X415833Y1258433D01*
X414167D01*
X412667Y1257933D01*
X411667Y1256933D01*
X411333Y1255767D01*
X411667Y1254600D01*
X412500Y1253767D01*
X413833Y1253267D01*
X415000Y1253100D01*
G01X425600Y1252767D02*
X425267Y1252933D01*
Y1253267D01*
X425600Y1253433D01*
X425933Y1253267D01*
Y1252933D01*
X425600Y1252767D01*
G01X437533Y1258433D02*
X438200Y1258933D01*
X438700Y1259766D01*
X439033Y1260933D01*
X438700Y1261933D01*
X438033Y1262600D01*
X436867Y1263100D01*
X432367D01*
Y1253100D01*
X437867D01*
X439033Y1253767D01*
X439700Y1254767D01*
X440033Y1255933D01*
X439700Y1257100D01*
X438700Y1258100D01*
X437533Y1258433D01*
X432367D01*
G01X446800Y1263100D02*
X445466Y1262767D01*
X444467Y1261933D01*
X443800Y1260933D01*
X443300Y1259600D01*
X443133Y1258100D01*
X443300Y1256600D01*
X443800Y1255267D01*
X444467Y1254266D01*
X445466Y1253433D01*
X446800Y1253100D01*
X448133Y1253433D01*
X449133Y1254266D01*
X449800Y1255267D01*
X450300Y1256600D01*
X450467Y1258100D01*
X450300Y1259600D01*
X449800Y1260933D01*
X449133Y1261933D01*
X448133Y1262767D01*
X446800Y1263100D01*
G01X457067Y1253100D02*
X457400Y1255267D01*
X457900Y1257100D01*
X458567Y1258767D01*
X459400Y1260600D01*
X460733Y1263100D01*
X454067D01*
G01X470000Y1253100D02*
Y1263100D01*
X463833Y1255933D01*
X472167D01*
G01X475433Y1261433D02*
X476433Y1262433D01*
X477600Y1262933D01*
X478933Y1263100D01*
X480600Y1262767D01*
X481767Y1261933D01*
X482100Y1260933D01*
X481933Y1259933D01*
X481267Y1259100D01*
X477933Y1257433D01*
X476433Y1256267D01*
X475433Y1254600D01*
X475100Y1253100D01*
X482100D01*
G01X489200Y1252767D02*
X488867Y1252933D01*
Y1253267D01*
X489200Y1253433D01*
X489533Y1253267D01*
Y1252933D01*
X489200Y1252767D01*
G01X499800Y1263100D02*
X498466Y1262767D01*
X497467Y1261933D01*
X496800Y1260933D01*
X496300Y1259600D01*
X496133Y1258100D01*
X496300Y1256600D01*
X496800Y1255267D01*
X497467Y1254266D01*
X498466Y1253433D01*
X499800Y1253100D01*
X501133Y1253433D01*
X502133Y1254266D01*
X502800Y1255267D01*
X503300Y1256600D01*
X503467Y1258100D01*
X503300Y1259600D01*
X502800Y1260933D01*
X502133Y1261933D01*
X501133Y1262767D01*
X499800Y1263100D01*
G01X506900Y1254433D02*
X508233Y1253600D01*
X509733Y1253100D01*
X511067D01*
X512400Y1253600D01*
X513400Y1254433D01*
X513900Y1255600D01*
X513567Y1256766D01*
X512733Y1257767D01*
X511233Y1258433D01*
X509233Y1258767D01*
X508067Y1259433D01*
X507567Y1260600D01*
X507900Y1261767D01*
X508733Y1262600D01*
X509900Y1263100D01*
X511067D01*
X512233Y1262767D01*
X513233Y1261933D01*
G01X516833Y1253100D02*
X521000Y1263100D01*
X525167Y1253100D01*
G01X523667Y1256600D02*
X518333D01*
G01X400166Y1238050D02*
Y1248050D01*
X404499Y1239717D01*
X408832Y1248050D01*
Y1238050D01*
G01X410932D02*
X415099Y1248050D01*
X419266Y1238050D01*
G01X417766Y1241550D02*
X412432D01*
G01X422032Y1238050D02*
Y1248050D01*
X425366D01*
X426699Y1247550D01*
X427699Y1246883D01*
X428532Y1245883D01*
X429199Y1244716D01*
X429366Y1243050D01*
X429199Y1241383D01*
X428532Y1240217D01*
X427699Y1239216D01*
X426699Y1238550D01*
X425366Y1238050D01*
X422032D01*
G01X439632D02*
X432966D01*
Y1248050D01*
X439632D01*
G01X436966Y1243217D02*
X432966D01*
G01X455499Y1248050D02*
X459499D01*
G01X457499D02*
Y1238050D01*
G01X455499D02*
X459499D01*
G01X464266D02*
Y1248050D01*
X471932Y1238050D01*
Y1248050D01*
G01X489299D02*
Y1238050D01*
G01X485466Y1248050D02*
X493132D01*
G01X495732Y1238050D02*
X499899Y1248050D01*
X504066Y1238050D01*
G01X502566Y1241550D02*
X497232D01*
G01X508499Y1248050D02*
X512499D01*
G01X510499D02*
Y1238050D01*
G01X508499D02*
X512499D01*
G01X516099Y1248050D02*
X518432Y1238050D01*
X521099Y1248050D01*
X523766Y1238050D01*
X526099Y1248050D01*
G01X527532Y1238050D02*
X531699Y1248050D01*
X535866Y1238050D01*
G01X534366Y1241550D02*
X529032D01*
G01X538466Y1238050D02*
Y1248050D01*
X546132Y1238050D01*
Y1248050D01*
G01X353016Y1554050D02*
Y1556550D01*
X354057D01*
X354391Y1556425D01*
X354599Y1556258D01*
X354682Y1555925D01*
X354599Y1555592D01*
X354349Y1555383D01*
X354057Y1555258D01*
X353016D01*
G01X354057D02*
X354682Y1554050D01*
G01X357449D02*
Y1556550D01*
X355907Y1554758D01*
X357991D01*
G01X360549Y1554050D02*
Y1556550D01*
X359007Y1554758D01*
X361091D01*
G01X362441Y1554342D02*
X362732Y1554133D01*
X363066Y1554050D01*
X363399Y1554133D01*
X363691Y1554383D01*
X363899Y1554758D01*
X363982Y1555133D01*
Y1555592D01*
X363899Y1555967D01*
X363691Y1556300D01*
X363441Y1556467D01*
X363149Y1556550D01*
X362816Y1556467D01*
X362566Y1556300D01*
X362399Y1556050D01*
X362316Y1555717D01*
X362399Y1555425D01*
X362607Y1555133D01*
X362857Y1554967D01*
X363149Y1554925D01*
X363482Y1555008D01*
X363732Y1555217D01*
X363982Y1555592D01*
G01X348499Y1553533D02*
X350291D01*
X350666Y1553700D01*
X350916Y1554033D01*
X350999Y1554450D01*
X350916Y1554867D01*
X350666Y1555200D01*
X350291Y1555367D01*
X348499D01*
G01X348916Y1556758D02*
X348666Y1557008D01*
X348541Y1557300D01*
X348499Y1557633D01*
X348582Y1558050D01*
X348791Y1558342D01*
X349041Y1558425D01*
X349291Y1558383D01*
X349499Y1558217D01*
X349916Y1557383D01*
X350207Y1557008D01*
X350624Y1556758D01*
X350999Y1556675D01*
Y1558425D01*
G01Y1560650D02*
X348499D01*
X348999Y1560150D01*
G01X350999D02*
Y1561150D01*
G01X348208Y1569567D02*
X348083Y1569317D01*
X348000Y1569025D01*
Y1568692D01*
X348125Y1568317D01*
X348333Y1568025D01*
X348583Y1567817D01*
X349000Y1567650D01*
X349375Y1567608D01*
X349750Y1567692D01*
X350000Y1567817D01*
X350250Y1568067D01*
X350417Y1568358D01*
X350500Y1568650D01*
Y1568942D01*
X350417Y1569233D01*
X350292Y1569483D01*
X350125Y1569692D01*
G01X350000Y1570833D02*
X350292Y1571083D01*
X350458Y1571417D01*
X350500Y1571792D01*
X350458Y1572125D01*
X350250Y1572458D01*
X350000Y1572667D01*
X349750Y1572708D01*
X349458Y1572625D01*
X349250Y1572333D01*
X349167Y1572042D01*
Y1571667D01*
G01Y1572042D02*
X349042Y1572292D01*
X348833Y1572500D01*
X348583Y1572583D01*
X348333Y1572500D01*
X348125Y1572292D01*
X348000Y1571917D01*
X348042Y1571542D01*
X348208Y1571167D01*
G01X350500Y1574767D02*
X349958Y1574850D01*
X349500Y1574975D01*
X349083Y1575142D01*
X348625Y1575350D01*
X348000Y1575683D01*
Y1574017D01*
G01Y1577950D02*
X348083Y1577617D01*
X348292Y1577367D01*
X348542Y1577200D01*
X348875Y1577075D01*
X349250Y1577033D01*
X349625Y1577075D01*
X349958Y1577200D01*
X350208Y1577367D01*
X350417Y1577617D01*
X350500Y1577950D01*
X350417Y1578283D01*
X350208Y1578533D01*
X349958Y1578700D01*
X349625Y1578825D01*
X349250Y1578867D01*
X348875Y1578825D01*
X348542Y1578700D01*
X348292Y1578533D01*
X348083Y1578283D01*
X348000Y1577950D01*
G01X353016Y1558050D02*
Y1560550D01*
X354057D01*
X354391Y1560425D01*
X354599Y1560258D01*
X354682Y1559925D01*
X354599Y1559592D01*
X354349Y1559383D01*
X354057Y1559258D01*
X353016D01*
G01X354057D02*
X354682Y1558050D01*
G01X357449D02*
Y1560550D01*
X355907Y1558758D01*
X357991D01*
G01X360549Y1558050D02*
Y1560550D01*
X359007Y1558758D01*
X361091D01*
G01X363149Y1558050D02*
X363441Y1558092D01*
X363774Y1558217D01*
X363982Y1558425D01*
X364066Y1558717D01*
X363982Y1559008D01*
X363732Y1559258D01*
X363357Y1559383D01*
X362941D01*
X362691Y1559467D01*
X362482Y1559675D01*
X362399Y1559967D01*
X362524Y1560258D01*
X362816Y1560467D01*
X363149Y1560550D01*
X363482Y1560467D01*
X363774Y1560258D01*
X363899Y1559967D01*
X363816Y1559675D01*
X363607Y1559467D01*
X363357Y1559383D01*
X362941D01*
X362566Y1559258D01*
X362316Y1559008D01*
X362232Y1558717D01*
X362316Y1558425D01*
X362524Y1558217D01*
X362857Y1558092D01*
X363149Y1558050D01*
G01X384500Y1960983D02*
X382000D01*
Y1961817D01*
X382125Y1962150D01*
X382292Y1962400D01*
X382542Y1962608D01*
X382833Y1962775D01*
X383250Y1962817D01*
X383667Y1962775D01*
X383958Y1962608D01*
X384208Y1962400D01*
X384375Y1962150D01*
X384500Y1961817D01*
Y1960983D01*
G01X382417Y1964208D02*
X382167Y1964458D01*
X382042Y1964750D01*
X382000Y1965083D01*
X382083Y1965500D01*
X382292Y1965792D01*
X382542Y1965875D01*
X382792Y1965833D01*
X383000Y1965667D01*
X383417Y1964833D01*
X383708Y1964458D01*
X384125Y1964208D01*
X384500Y1964125D01*
Y1965875D01*
G01X382000Y1968100D02*
X382083Y1967767D01*
X382292Y1967517D01*
X382542Y1967350D01*
X382875Y1967225D01*
X383250Y1967183D01*
X383625Y1967225D01*
X383958Y1967350D01*
X384208Y1967517D01*
X384417Y1967767D01*
X384500Y1968100D01*
X384417Y1968433D01*
X384208Y1968683D01*
X383958Y1968850D01*
X383625Y1968975D01*
X383250Y1969017D01*
X382875Y1968975D01*
X382542Y1968850D01*
X382292Y1968683D01*
X382083Y1968433D01*
X382000Y1968100D01*
G01X363500Y1954900D02*
X363458Y1954567D01*
X363292Y1954275D01*
X363042Y1954025D01*
X362750Y1953858D01*
X362417Y1953775D01*
X362083D01*
X361750Y1953858D01*
X361458Y1954025D01*
X361208Y1954275D01*
X361042Y1954567D01*
X361000Y1954900D01*
X361042Y1955233D01*
X361208Y1955525D01*
X361458Y1955775D01*
X361750Y1955942D01*
X362083Y1956025D01*
X362417D01*
X362750Y1955942D01*
X363042Y1955775D01*
X363292Y1955525D01*
X363458Y1955233D01*
X363500Y1954900D01*
G01X362833Y1955233D02*
X363500Y1955733D01*
G01Y1958000D02*
X361000D01*
X361500Y1957500D01*
G01X363500D02*
Y1958500D01*
G01X361417Y1960308D02*
X361167Y1960558D01*
X361042Y1960850D01*
X361000Y1961183D01*
X361083Y1961600D01*
X361292Y1961892D01*
X361542Y1961975D01*
X361792Y1961933D01*
X362000Y1961767D01*
X362417Y1960933D01*
X362708Y1960558D01*
X363125Y1960308D01*
X363500Y1960225D01*
Y1961975D01*
G01X379500Y1959517D02*
X377000D01*
Y1960558D01*
X377125Y1960892D01*
X377292Y1961100D01*
X377625Y1961183D01*
X377958Y1961100D01*
X378167Y1960850D01*
X378292Y1960558D01*
Y1959517D01*
G01Y1960558D02*
X379500Y1961183D01*
G01X379125Y1962533D02*
X379333Y1962783D01*
X379458Y1963075D01*
X379500Y1963450D01*
X379417Y1963825D01*
X379250Y1964117D01*
X378958Y1964325D01*
X378625Y1964367D01*
X378292Y1964283D01*
X378083Y1964075D01*
X377917Y1963783D01*
X377875Y1963492D01*
X377917Y1963200D01*
X378083Y1962825D01*
X377000Y1962950D01*
Y1964075D01*
G01X378458Y1965758D02*
X378167Y1966050D01*
X378000Y1966300D01*
X377917Y1966633D01*
X378000Y1966925D01*
X378167Y1967133D01*
X378417Y1967300D01*
X378708Y1967342D01*
X378958Y1967300D01*
X379208Y1967133D01*
X379417Y1966883D01*
X379500Y1966592D01*
X379417Y1966258D01*
X379167Y1965967D01*
X378792Y1965800D01*
X378375Y1965758D01*
X377833Y1965842D01*
X377542Y1965967D01*
X377250Y1966175D01*
X377042Y1966467D01*
X377000Y1966758D01*
X377083Y1967050D01*
X377292Y1967258D01*
G01X379500Y1969650D02*
X379458Y1969942D01*
X379333Y1970275D01*
X379125Y1970483D01*
X378833Y1970567D01*
X378542Y1970483D01*
X378292Y1970233D01*
X378167Y1969858D01*
Y1969442D01*
X378083Y1969192D01*
X377875Y1968983D01*
X377583Y1968900D01*
X377292Y1969025D01*
X377083Y1969317D01*
X377000Y1969650D01*
X377083Y1969983D01*
X377292Y1970275D01*
X377583Y1970400D01*
X377875Y1970317D01*
X378083Y1970108D01*
X378167Y1969858D01*
Y1969442D01*
X378292Y1969067D01*
X378542Y1968817D01*
X378833Y1968733D01*
X379125Y1968817D01*
X379333Y1969025D01*
X379458Y1969358D01*
X379500Y1969650D01*
G01X347517Y1953000D02*
Y1955500D01*
X348558D01*
X348892Y1955375D01*
X349100Y1955208D01*
X349183Y1954875D01*
X349100Y1954542D01*
X348850Y1954333D01*
X348558Y1954208D01*
X347517D01*
G01X348558D02*
X349183Y1953000D01*
G01X351450D02*
Y1955500D01*
X350950Y1955000D01*
G01Y1953000D02*
X351950D01*
G01X354467D02*
X354550Y1953542D01*
X354675Y1954000D01*
X354842Y1954417D01*
X355050Y1954875D01*
X355383Y1955500D01*
X353717D01*
G01X356942Y1953292D02*
X357233Y1953083D01*
X357567Y1953000D01*
X357900Y1953083D01*
X358192Y1953333D01*
X358400Y1953708D01*
X358483Y1954083D01*
Y1954542D01*
X358400Y1954917D01*
X358192Y1955250D01*
X357942Y1955417D01*
X357650Y1955500D01*
X357317Y1955417D01*
X357067Y1955250D01*
X356900Y1955000D01*
X356817Y1954667D01*
X356900Y1954375D01*
X357108Y1954083D01*
X357358Y1953917D01*
X357650Y1953875D01*
X357983Y1953958D01*
X358233Y1954167D01*
X358483Y1954542D01*
G01X347517Y1969000D02*
Y1971500D01*
X348558D01*
X348892Y1971375D01*
X349100Y1971208D01*
X349183Y1970875D01*
X349100Y1970542D01*
X348850Y1970333D01*
X348558Y1970208D01*
X347517D01*
G01X348558D02*
X349183Y1969000D01*
G01X351450D02*
Y1971500D01*
X350950Y1971000D01*
G01Y1969000D02*
X351950D01*
G01X354550D02*
X354842Y1969042D01*
X355175Y1969167D01*
X355383Y1969375D01*
X355467Y1969667D01*
X355383Y1969958D01*
X355133Y1970208D01*
X354758Y1970333D01*
X354342D01*
X354092Y1970417D01*
X353883Y1970625D01*
X353800Y1970917D01*
X353925Y1971208D01*
X354217Y1971417D01*
X354550Y1971500D01*
X354883Y1971417D01*
X355175Y1971208D01*
X355300Y1970917D01*
X355217Y1970625D01*
X355008Y1970417D01*
X354758Y1970333D01*
X354342D01*
X353967Y1970208D01*
X353717Y1969958D01*
X353633Y1969667D01*
X353717Y1969375D01*
X353925Y1969167D01*
X354258Y1969042D01*
X354550Y1969000D01*
G01X357650Y1971500D02*
X357317Y1971417D01*
X357067Y1971208D01*
X356900Y1970958D01*
X356775Y1970625D01*
X356733Y1970250D01*
X356775Y1969875D01*
X356900Y1969542D01*
X357067Y1969292D01*
X357317Y1969083D01*
X357650Y1969000D01*
X357983Y1969083D01*
X358233Y1969292D01*
X358400Y1969542D01*
X358525Y1969875D01*
X358567Y1970250D01*
X358525Y1970625D01*
X358400Y1970958D01*
X358233Y1971208D01*
X357983Y1971417D01*
X357650Y1971500D01*
G01X347517Y1965000D02*
Y1967500D01*
X348558D01*
X348892Y1967375D01*
X349100Y1967208D01*
X349183Y1966875D01*
X349100Y1966542D01*
X348850Y1966333D01*
X348558Y1966208D01*
X347517D01*
G01X348558D02*
X349183Y1965000D01*
G01X351450D02*
Y1967500D01*
X350950Y1967000D01*
G01Y1965000D02*
X351950D01*
G01X354550D02*
X354842Y1965042D01*
X355175Y1965167D01*
X355383Y1965375D01*
X355467Y1965667D01*
X355383Y1965958D01*
X355133Y1966208D01*
X354758Y1966333D01*
X354342D01*
X354092Y1966417D01*
X353883Y1966625D01*
X353800Y1966917D01*
X353925Y1967208D01*
X354217Y1967417D01*
X354550Y1967500D01*
X354883Y1967417D01*
X355175Y1967208D01*
X355300Y1966917D01*
X355217Y1966625D01*
X355008Y1966417D01*
X354758Y1966333D01*
X354342D01*
X353967Y1966208D01*
X353717Y1965958D01*
X353633Y1965667D01*
X353717Y1965375D01*
X353925Y1965167D01*
X354258Y1965042D01*
X354550Y1965000D01*
G01X357650D02*
Y1967500D01*
X357150Y1967000D01*
G01Y1965000D02*
X358150D01*
G01X347517Y1961000D02*
Y1963500D01*
X348558D01*
X348892Y1963375D01*
X349100Y1963208D01*
X349183Y1962875D01*
X349100Y1962542D01*
X348850Y1962333D01*
X348558Y1962208D01*
X347517D01*
G01X348558D02*
X349183Y1961000D01*
G01X351450D02*
Y1963500D01*
X350950Y1963000D01*
G01Y1961000D02*
X351950D01*
G01X354550D02*
X354842Y1961042D01*
X355175Y1961167D01*
X355383Y1961375D01*
X355467Y1961667D01*
X355383Y1961958D01*
X355133Y1962208D01*
X354758Y1962333D01*
X354342D01*
X354092Y1962417D01*
X353883Y1962625D01*
X353800Y1962917D01*
X353925Y1963208D01*
X354217Y1963417D01*
X354550Y1963500D01*
X354883Y1963417D01*
X355175Y1963208D01*
X355300Y1962917D01*
X355217Y1962625D01*
X355008Y1962417D01*
X354758Y1962333D01*
X354342D01*
X353967Y1962208D01*
X353717Y1961958D01*
X353633Y1961667D01*
X353717Y1961375D01*
X353925Y1961167D01*
X354258Y1961042D01*
X354550Y1961000D01*
G01X356858Y1963083D02*
X357108Y1963333D01*
X357400Y1963458D01*
X357733Y1963500D01*
X358150Y1963417D01*
X358442Y1963208D01*
X358525Y1962958D01*
X358483Y1962708D01*
X358317Y1962500D01*
X357483Y1962083D01*
X357108Y1961792D01*
X356858Y1961375D01*
X356775Y1961000D01*
X358525D01*
G01X347517Y1957000D02*
Y1959500D01*
X348558D01*
X348892Y1959375D01*
X349100Y1959208D01*
X349183Y1958875D01*
X349100Y1958542D01*
X348850Y1958333D01*
X348558Y1958208D01*
X347517D01*
G01X348558D02*
X349183Y1957000D01*
G01X351450D02*
Y1959500D01*
X350950Y1959000D01*
G01Y1957000D02*
X351950D01*
G01X354550D02*
X354842Y1957042D01*
X355175Y1957167D01*
X355383Y1957375D01*
X355467Y1957667D01*
X355383Y1957958D01*
X355133Y1958208D01*
X354758Y1958333D01*
X354342D01*
X354092Y1958417D01*
X353883Y1958625D01*
X353800Y1958917D01*
X353925Y1959208D01*
X354217Y1959417D01*
X354550Y1959500D01*
X354883Y1959417D01*
X355175Y1959208D01*
X355300Y1958917D01*
X355217Y1958625D01*
X355008Y1958417D01*
X354758Y1958333D01*
X354342D01*
X353967Y1958208D01*
X353717Y1957958D01*
X353633Y1957667D01*
X353717Y1957375D01*
X353925Y1957167D01*
X354258Y1957042D01*
X354550Y1957000D01*
G01X356733Y1957500D02*
X356983Y1957208D01*
X357317Y1957042D01*
X357692Y1957000D01*
X358025Y1957042D01*
X358358Y1957250D01*
X358567Y1957500D01*
X358608Y1957750D01*
X358525Y1958042D01*
X358233Y1958250D01*
X357942Y1958333D01*
X357567D01*
G01X357942D02*
X358192Y1958458D01*
X358400Y1958667D01*
X358483Y1958917D01*
X358400Y1959167D01*
X358192Y1959375D01*
X357817Y1959500D01*
X357442Y1959458D01*
X357067Y1959292D01*
G01X362017Y1966500D02*
Y1969000D01*
X363058D01*
X363392Y1968875D01*
X363600Y1968708D01*
X363683Y1968375D01*
X363600Y1968042D01*
X363350Y1967833D01*
X363058Y1967708D01*
X362017D01*
G01X363058D02*
X363683Y1966500D01*
G01X366450D02*
Y1969000D01*
X364908Y1967208D01*
X366992D01*
G01X369050Y1966500D02*
Y1969000D01*
X368550Y1968500D01*
G01Y1966500D02*
X369550D01*
G01X371233Y1967000D02*
X371483Y1966708D01*
X371817Y1966542D01*
X372192Y1966500D01*
X372525Y1966542D01*
X372858Y1966750D01*
X373067Y1967000D01*
X373108Y1967250D01*
X373025Y1967542D01*
X372733Y1967750D01*
X372442Y1967833D01*
X372067D01*
G01X372442D02*
X372692Y1967958D01*
X372900Y1968167D01*
X372983Y1968417D01*
X372900Y1968667D01*
X372692Y1968875D01*
X372317Y1969000D01*
X371942Y1968958D01*
X371567Y1968792D01*
G01X349267Y1979792D02*
X349017Y1979917D01*
X348725Y1980000D01*
X348392D01*
X348017Y1979875D01*
X347725Y1979667D01*
X347517Y1979417D01*
X347350Y1979000D01*
X347308Y1978625D01*
X347392Y1978250D01*
X347517Y1978000D01*
X347767Y1977750D01*
X348058Y1977583D01*
X348350Y1977500D01*
X348642D01*
X348933Y1977583D01*
X349183Y1977708D01*
X349392Y1977875D01*
G01X350533Y1978000D02*
X350783Y1977708D01*
X351117Y1977542D01*
X351492Y1977500D01*
X351825Y1977542D01*
X352158Y1977750D01*
X352367Y1978000D01*
X352408Y1978250D01*
X352325Y1978542D01*
X352033Y1978750D01*
X351742Y1978833D01*
X351367D01*
G01X351742D02*
X351992Y1978958D01*
X352200Y1979167D01*
X352283Y1979417D01*
X352200Y1979667D01*
X351992Y1979875D01*
X351617Y1980000D01*
X351242Y1979958D01*
X350867Y1979792D01*
G01X354550Y1977500D02*
X354842Y1977542D01*
X355175Y1977667D01*
X355383Y1977875D01*
X355467Y1978167D01*
X355383Y1978458D01*
X355133Y1978708D01*
X354758Y1978833D01*
X354342D01*
X354092Y1978917D01*
X353883Y1979125D01*
X353800Y1979417D01*
X353925Y1979708D01*
X354217Y1979917D01*
X354550Y1980000D01*
X354883Y1979917D01*
X355175Y1979708D01*
X355300Y1979417D01*
X355217Y1979125D01*
X355008Y1978917D01*
X354758Y1978833D01*
X354342D01*
X353967Y1978708D01*
X353717Y1978458D01*
X353633Y1978167D01*
X353717Y1977875D01*
X353925Y1977667D01*
X354258Y1977542D01*
X354550Y1977500D01*
G01X358150D02*
Y1980000D01*
X356608Y1978208D01*
X358692D01*
G01X347517Y1973500D02*
Y1976000D01*
X348558D01*
X348892Y1975875D01*
X349100Y1975708D01*
X349183Y1975375D01*
X349100Y1975042D01*
X348850Y1974833D01*
X348558Y1974708D01*
X347517D01*
G01X348558D02*
X349183Y1973500D01*
G01X350533Y1973875D02*
X350783Y1973667D01*
X351075Y1973542D01*
X351450Y1973500D01*
X351825Y1973583D01*
X352117Y1973750D01*
X352325Y1974042D01*
X352367Y1974375D01*
X352283Y1974708D01*
X352075Y1974917D01*
X351783Y1975083D01*
X351492Y1975125D01*
X351200Y1975083D01*
X350825Y1974917D01*
X350950Y1976000D01*
X352075D01*
G01X353633Y1973875D02*
X353883Y1973667D01*
X354175Y1973542D01*
X354550Y1973500D01*
X354925Y1973583D01*
X355217Y1973750D01*
X355425Y1974042D01*
X355467Y1974375D01*
X355383Y1974708D01*
X355175Y1974917D01*
X354883Y1975083D01*
X354592Y1975125D01*
X354300Y1975083D01*
X353925Y1974917D01*
X354050Y1976000D01*
X355175D01*
G01X358150Y1973500D02*
Y1976000D01*
X356608Y1974208D01*
X358692D01*
G01X432500Y34517D02*
X430000D01*
Y35558D01*
X430125Y35892D01*
X430292Y36100D01*
X430625Y36183D01*
X430958Y36100D01*
X431167Y35850D01*
X431292Y35558D01*
Y34517D01*
G01Y35558D02*
X432500Y36183D01*
G01X432000Y37533D02*
X432292Y37783D01*
X432458Y38117D01*
X432500Y38492D01*
X432458Y38825D01*
X432250Y39158D01*
X432000Y39367D01*
X431750Y39408D01*
X431458Y39325D01*
X431250Y39033D01*
X431167Y38742D01*
Y38367D01*
G01Y38742D02*
X431042Y38992D01*
X430833Y39200D01*
X430583Y39283D01*
X430333Y39200D01*
X430125Y38992D01*
X430000Y38617D01*
X430042Y38242D01*
X430208Y37867D01*
G01X430000Y41550D02*
X430083Y41217D01*
X430292Y40967D01*
X430542Y40800D01*
X430875Y40675D01*
X431250Y40633D01*
X431625Y40675D01*
X431958Y40800D01*
X432208Y40967D01*
X432417Y41217D01*
X432500Y41550D01*
X432417Y41883D01*
X432208Y42133D01*
X431958Y42300D01*
X431625Y42425D01*
X431250Y42467D01*
X430875Y42425D01*
X430542Y42300D01*
X430292Y42133D01*
X430083Y41883D01*
X430000Y41550D01*
G01X432500Y44650D02*
X432458Y44942D01*
X432333Y45275D01*
X432125Y45483D01*
X431833Y45567D01*
X431542Y45483D01*
X431292Y45233D01*
X431167Y44858D01*
Y44442D01*
X431083Y44192D01*
X430875Y43983D01*
X430583Y43900D01*
X430292Y44025D01*
X430083Y44317D01*
X430000Y44650D01*
X430083Y44983D01*
X430292Y45275D01*
X430583Y45400D01*
X430875Y45317D01*
X431083Y45108D01*
X431167Y44858D01*
Y44442D01*
X431292Y44067D01*
X431542Y43817D01*
X431833Y43733D01*
X432125Y43817D01*
X432333Y44025D01*
X432458Y44358D01*
X432500Y44650D01*
G01X492967Y1174100D02*
Y1184100D01*
X497133D01*
X498467Y1183600D01*
X499300Y1182933D01*
X499633Y1181600D01*
X499300Y1180267D01*
X498300Y1179433D01*
X497133Y1178933D01*
X492967D01*
G01X497133D02*
X499633Y1174100D01*
G01X506900D02*
X505566Y1174267D01*
X504400Y1174933D01*
X503400Y1175933D01*
X502733Y1177100D01*
X502400Y1178433D01*
Y1179767D01*
X502733Y1181100D01*
X503400Y1182267D01*
X504400Y1183267D01*
X505566Y1183933D01*
X506900Y1184100D01*
X508233Y1183933D01*
X509400Y1183267D01*
X510400Y1182267D01*
X511067Y1181100D01*
X511400Y1179767D01*
Y1178433D01*
X511067Y1177100D01*
X510400Y1175933D01*
X509400Y1174933D01*
X508233Y1174267D01*
X506900Y1174100D01*
G01X514000D02*
Y1184100D01*
G01X521000D02*
Y1174100D01*
G01Y1179100D02*
X514000D01*
G01X524600Y1175433D02*
X525933Y1174600D01*
X527433Y1174100D01*
X528767D01*
X530100Y1174600D01*
X531100Y1175433D01*
X531600Y1176600D01*
X531267Y1177766D01*
X530433Y1178767D01*
X528933Y1179433D01*
X526933Y1179767D01*
X525767Y1180433D01*
X525267Y1181600D01*
X525600Y1182767D01*
X526433Y1183600D01*
X527600Y1184100D01*
X528767D01*
X529933Y1183767D01*
X530933Y1182933D01*
G01X551967Y1179933D02*
X550800Y1180600D01*
X549800Y1180766D01*
X548467Y1180433D01*
X547467Y1179767D01*
X546800Y1178600D01*
X546633Y1177433D01*
X546800Y1176267D01*
X547467Y1175266D01*
X548467Y1174433D01*
X549800Y1174100D01*
X550967Y1174433D01*
X551967Y1175100D01*
G01X559900Y1174100D02*
X558900Y1174267D01*
X557900Y1174933D01*
X557233Y1176100D01*
X556900Y1177433D01*
X557233Y1178767D01*
X557900Y1179933D01*
X558900Y1180600D01*
X559900Y1180766D01*
X560900Y1180600D01*
X561900Y1179933D01*
X562567Y1178767D01*
X562733Y1177433D01*
X562567Y1176100D01*
X561900Y1174933D01*
X560900Y1174267D01*
X559900Y1174100D01*
G01X565500D02*
Y1180766D01*
G01Y1178933D02*
X566000Y1179767D01*
X566833Y1180433D01*
X568000Y1180766D01*
X569166Y1180433D01*
X570000Y1179767D01*
X570500Y1178933D01*
Y1174100D01*
G01Y1178933D02*
X571000Y1179767D01*
X571833Y1180433D01*
X573000Y1180766D01*
X574167Y1180433D01*
X575000Y1179767D01*
X575500Y1178767D01*
Y1174100D01*
G01X578100Y1170767D02*
Y1180766D01*
G01Y1179267D02*
X578933Y1180100D01*
X579766Y1180600D01*
X581100Y1180766D01*
X582267Y1180600D01*
X583433Y1179767D01*
X583933Y1178600D01*
X584100Y1177433D01*
X583933Y1176267D01*
X583433Y1175100D01*
X582433Y1174433D01*
X581100Y1174100D01*
X579933Y1174267D01*
X578767Y1174767D01*
X578100Y1175433D01*
G01X591700Y1174100D02*
Y1184100D01*
G01X602300Y1180766D02*
Y1174100D01*
G01Y1183433D02*
X601967Y1183600D01*
Y1183933D01*
X602300Y1184100D01*
X602633Y1183933D01*
Y1183600D01*
X602300Y1183433D01*
G01X615900Y1174100D02*
Y1180766D01*
G01Y1179600D02*
X615233Y1180267D01*
X614233Y1180600D01*
X613067Y1180766D01*
X611900Y1180433D01*
X610900Y1179767D01*
X610233Y1178767D01*
X609900Y1177433D01*
X610233Y1176100D01*
X610900Y1175100D01*
X611900Y1174433D01*
X613067Y1174100D01*
X614233Y1174267D01*
X615233Y1174767D01*
X615900Y1175433D01*
G01X620667Y1174100D02*
Y1180766D01*
G01Y1179100D02*
X621333Y1179933D01*
X622333Y1180600D01*
X623667Y1180766D01*
X624833Y1180600D01*
X625833Y1179933D01*
X626333Y1178767D01*
Y1174100D01*
G01X636767Y1179933D02*
X635600Y1180600D01*
X634600Y1180766D01*
X633267Y1180433D01*
X632267Y1179767D01*
X631600Y1178600D01*
X631433Y1177433D01*
X631600Y1176267D01*
X632267Y1175266D01*
X633267Y1174433D01*
X634600Y1174100D01*
X635767Y1174433D01*
X636767Y1175100D01*
G01X642200Y1178600D02*
X647533D01*
X647033Y1179767D01*
X646200Y1180433D01*
X645033Y1180766D01*
X643867Y1180600D01*
X642867Y1180100D01*
X642200Y1178933D01*
X641867Y1177933D01*
Y1176933D01*
X642200Y1175933D01*
X643033Y1174933D01*
X644033Y1174267D01*
X645200Y1174100D01*
X646367Y1174433D01*
X647533Y1175433D01*
G01X427585Y1173280D02*
X429835D01*
G01X427585Y1167400D02*
Y1173280D01*
G01X429835Y1167400D02*
X427585D01*
G01X428935Y1170435D02*
X427585D01*
G01X433335Y1169070D02*
Y1173280D01*
G01X433105Y1168185D02*
X433335Y1169070D01*
G01X432655Y1167600D02*
X433105Y1168185D01*
G01X432090Y1167400D02*
X432655Y1167600D01*
G01X431525D02*
X432090Y1167400D01*
G01X431075Y1168185D02*
X431525Y1167600D01*
G01X430850Y1169070D02*
X431075Y1168185D01*
G01X430850Y1173280D02*
Y1169070D01*
G01X439300Y1167495D02*
X438855Y1167400D01*
G01X439700Y1167890D02*
X439300Y1167495D01*
G01X440035Y1168480D02*
X439700Y1167890D01*
G01X440265Y1169165D02*
X440035Y1168480D01*
G01X440375Y1169950D02*
X440265Y1169165D01*
G01X440375Y1170730D02*
Y1169950D01*
G01X440265Y1171515D02*
X440375Y1170730D01*
G01X440035Y1172200D02*
X440265Y1171515D01*
G01X439700Y1172790D02*
X440035Y1172200D01*
G01X439300Y1173185D02*
X439700Y1172790D01*
G01X438855Y1173280D02*
X439300Y1173185D01*
G01X438405D02*
X438855Y1173280D01*
G01X438005Y1172790D02*
X438405Y1173185D01*
G01X437670Y1172200D02*
X438005Y1172790D01*
G01X437440Y1171515D02*
X437670Y1172200D01*
G01X437330Y1170730D02*
X437440Y1171515D01*
G01X437330Y1169950D02*
Y1170730D01*
G01X437440Y1169165D02*
X437330Y1169950D01*
G01X437670Y1168480D02*
X437440Y1169165D01*
G01X438005Y1167890D02*
X437670Y1168480D01*
G01X438405Y1167495D02*
X438005Y1167890D01*
G01X438855Y1167400D02*
X438405Y1167495D01*
G01X441280Y1167400D02*
Y1171320D01*
G01X443190Y1170140D02*
Y1167400D01*
G01X443020Y1170830D02*
X443190Y1170140D01*
G01X442680Y1171220D02*
X443020Y1170830D01*
G01X442290Y1171320D02*
X442680Y1171220D01*
G01X441835D02*
X442290Y1171320D01*
G01X441500Y1170830D02*
X441835Y1171220D01*
G01X441280Y1170340D02*
X441500Y1170830D01*
G01X445615Y1167400D02*
Y1173280D01*
G01X449445Y1168085D02*
X450180Y1171320D01*
G01X449105Y1166520D02*
X449445Y1168085D01*
G01X448885Y1166025D02*
X449105Y1166520D01*
G01X448600Y1165635D02*
X448885Y1166025D01*
G01X448150Y1165440D02*
X448600Y1165635D01*
G01X447810D02*
X448150Y1165440D01*
G01X448380Y1171320D02*
X449445Y1168085D01*
G01X659208Y1776767D02*
X659083Y1776517D01*
X659000Y1776225D01*
Y1775892D01*
X659125Y1775517D01*
X659333Y1775225D01*
X659583Y1775017D01*
X660000Y1774850D01*
X660375Y1774808D01*
X660750Y1774892D01*
X661000Y1775017D01*
X661250Y1775267D01*
X661417Y1775558D01*
X661500Y1775850D01*
Y1776142D01*
X661417Y1776433D01*
X661292Y1776683D01*
X661125Y1776892D01*
G01X661000Y1778033D02*
X661292Y1778283D01*
X661458Y1778617D01*
X661500Y1778992D01*
X661458Y1779325D01*
X661250Y1779658D01*
X661000Y1779867D01*
X660750Y1779908D01*
X660458Y1779825D01*
X660250Y1779533D01*
X660167Y1779242D01*
Y1778867D01*
G01Y1779242D02*
X660042Y1779492D01*
X659833Y1779700D01*
X659583Y1779783D01*
X659333Y1779700D01*
X659125Y1779492D01*
X659000Y1779117D01*
X659042Y1778742D01*
X659208Y1778367D01*
G01X661125Y1781133D02*
X661333Y1781383D01*
X661458Y1781675D01*
X661500Y1782050D01*
X661417Y1782425D01*
X661250Y1782717D01*
X660958Y1782925D01*
X660625Y1782967D01*
X660292Y1782883D01*
X660083Y1782675D01*
X659917Y1782383D01*
X659875Y1782092D01*
X659917Y1781800D01*
X660083Y1781425D01*
X659000Y1781550D01*
Y1782675D01*
G01X661500Y1785650D02*
X659000D01*
X660792Y1784108D01*
Y1786192D01*
G01X659257Y1790401D02*
X659132Y1790151D01*
X659049Y1789859D01*
Y1789526D01*
X659174Y1789151D01*
X659382Y1788859D01*
X659632Y1788651D01*
X660049Y1788484D01*
X660424Y1788442D01*
X660799Y1788526D01*
X661049Y1788651D01*
X661299Y1788901D01*
X661466Y1789192D01*
X661549Y1789484D01*
Y1789776D01*
X661466Y1790067D01*
X661341Y1790317D01*
X661174Y1790526D01*
G01X661049Y1791667D02*
X661341Y1791917D01*
X661507Y1792251D01*
X661549Y1792626D01*
X661507Y1792959D01*
X661299Y1793292D01*
X661049Y1793501D01*
X660799Y1793542D01*
X660507Y1793459D01*
X660299Y1793167D01*
X660216Y1792876D01*
Y1792501D01*
G01Y1792876D02*
X660091Y1793126D01*
X659882Y1793334D01*
X659632Y1793417D01*
X659382Y1793334D01*
X659174Y1793126D01*
X659049Y1792751D01*
X659091Y1792376D01*
X659257Y1792001D01*
G01X661174Y1794767D02*
X661382Y1795017D01*
X661507Y1795309D01*
X661549Y1795684D01*
X661466Y1796059D01*
X661299Y1796351D01*
X661007Y1796559D01*
X660674Y1796601D01*
X660341Y1796517D01*
X660132Y1796309D01*
X659966Y1796017D01*
X659924Y1795726D01*
X659966Y1795434D01*
X660132Y1795059D01*
X659049Y1795184D01*
Y1796309D01*
G01X661049Y1797867D02*
X661341Y1798117D01*
X661507Y1798451D01*
X661549Y1798826D01*
X661507Y1799159D01*
X661299Y1799492D01*
X661049Y1799701D01*
X660799Y1799742D01*
X660507Y1799659D01*
X660299Y1799367D01*
X660216Y1799076D01*
Y1798701D01*
G01Y1799076D02*
X660091Y1799326D01*
X659882Y1799534D01*
X659632Y1799617D01*
X659382Y1799534D01*
X659174Y1799326D01*
X659049Y1798951D01*
X659091Y1798576D01*
X659257Y1798201D01*
G01X644566Y1785634D02*
Y1788134D01*
X645607D01*
X645941Y1788009D01*
X646149Y1787842D01*
X646232Y1787509D01*
X646149Y1787176D01*
X645899Y1786967D01*
X645607Y1786842D01*
X644566D01*
G01X645607D02*
X646232Y1785634D01*
G01X647582Y1786134D02*
X647832Y1785842D01*
X648166Y1785676D01*
X648541Y1785634D01*
X648874Y1785676D01*
X649207Y1785884D01*
X649416Y1786134D01*
X649457Y1786384D01*
X649374Y1786676D01*
X649082Y1786884D01*
X648791Y1786967D01*
X648416D01*
G01X648791D02*
X649041Y1787092D01*
X649249Y1787301D01*
X649332Y1787551D01*
X649249Y1787801D01*
X649041Y1788009D01*
X648666Y1788134D01*
X648291Y1788092D01*
X647916Y1787926D01*
G01X651516Y1785634D02*
X651599Y1786176D01*
X651724Y1786634D01*
X651891Y1787051D01*
X652099Y1787509D01*
X652432Y1788134D01*
X650766D01*
G01X653782Y1786134D02*
X654032Y1785842D01*
X654366Y1785676D01*
X654741Y1785634D01*
X655074Y1785676D01*
X655407Y1785884D01*
X655616Y1786134D01*
X655657Y1786384D01*
X655574Y1786676D01*
X655282Y1786884D01*
X654991Y1786967D01*
X654616D01*
G01X654991D02*
X655241Y1787092D01*
X655449Y1787301D01*
X655532Y1787551D01*
X655449Y1787801D01*
X655241Y1788009D01*
X654866Y1788134D01*
X654491Y1788092D01*
X654116Y1787926D01*
G01X646349Y1805634D02*
Y1801634D01*
X653749D01*
G01X644566Y1781634D02*
Y1784134D01*
X645607D01*
X645941Y1784009D01*
X646149Y1783842D01*
X646232Y1783509D01*
X646149Y1783176D01*
X645899Y1782967D01*
X645607Y1782842D01*
X644566D01*
G01X645607D02*
X646232Y1781634D01*
G01X647582Y1782134D02*
X647832Y1781842D01*
X648166Y1781676D01*
X648541Y1781634D01*
X648874Y1781676D01*
X649207Y1781884D01*
X649416Y1782134D01*
X649457Y1782384D01*
X649374Y1782676D01*
X649082Y1782884D01*
X648791Y1782967D01*
X648416D01*
G01X648791D02*
X649041Y1783092D01*
X649249Y1783301D01*
X649332Y1783551D01*
X649249Y1783801D01*
X649041Y1784009D01*
X648666Y1784134D01*
X648291Y1784092D01*
X647916Y1783926D01*
G01X651599Y1781634D02*
X651891Y1781676D01*
X652224Y1781801D01*
X652432Y1782009D01*
X652516Y1782301D01*
X652432Y1782592D01*
X652182Y1782842D01*
X651807Y1782967D01*
X651391D01*
X651141Y1783051D01*
X650932Y1783259D01*
X650849Y1783551D01*
X650974Y1783842D01*
X651266Y1784051D01*
X651599Y1784134D01*
X651932Y1784051D01*
X652224Y1783842D01*
X652349Y1783551D01*
X652266Y1783259D01*
X652057Y1783051D01*
X651807Y1782967D01*
X651391D01*
X651016Y1782842D01*
X650766Y1782592D01*
X650682Y1782301D01*
X650766Y1782009D01*
X650974Y1781801D01*
X651307Y1781676D01*
X651599Y1781634D01*
G01X654699Y1784134D02*
X654366Y1784051D01*
X654116Y1783842D01*
X653949Y1783592D01*
X653824Y1783259D01*
X653782Y1782884D01*
X653824Y1782509D01*
X653949Y1782176D01*
X654116Y1781926D01*
X654366Y1781717D01*
X654699Y1781634D01*
X655032Y1781717D01*
X655282Y1781926D01*
X655449Y1782176D01*
X655574Y1782509D01*
X655616Y1782884D01*
X655574Y1783259D01*
X655449Y1783592D01*
X655282Y1783842D01*
X655032Y1784051D01*
X654699Y1784134D01*
G01X646349Y1798134D02*
Y1794134D01*
X653749D01*
G01X627049Y1802151D02*
X624549D01*
Y1803192D01*
X624674Y1803526D01*
X624841Y1803734D01*
X625174Y1803817D01*
X625507Y1803734D01*
X625716Y1803484D01*
X625841Y1803192D01*
Y1802151D01*
G01Y1803192D02*
X627049Y1803817D01*
G01X626549Y1805167D02*
X626841Y1805417D01*
X627007Y1805751D01*
X627049Y1806126D01*
X627007Y1806459D01*
X626799Y1806792D01*
X626549Y1807001D01*
X626299Y1807042D01*
X626007Y1806959D01*
X625799Y1806667D01*
X625716Y1806376D01*
Y1806001D01*
G01Y1806376D02*
X625591Y1806626D01*
X625382Y1806834D01*
X625132Y1806917D01*
X624882Y1806834D01*
X624674Y1806626D01*
X624549Y1806251D01*
X624591Y1805876D01*
X624757Y1805501D01*
G01X627049Y1809184D02*
X627007Y1809476D01*
X626882Y1809809D01*
X626674Y1810017D01*
X626382Y1810101D01*
X626091Y1810017D01*
X625841Y1809767D01*
X625716Y1809392D01*
Y1808976D01*
X625632Y1808726D01*
X625424Y1808517D01*
X625132Y1808434D01*
X624841Y1808559D01*
X624632Y1808851D01*
X624549Y1809184D01*
X624632Y1809517D01*
X624841Y1809809D01*
X625132Y1809934D01*
X625424Y1809851D01*
X625632Y1809642D01*
X625716Y1809392D01*
Y1808976D01*
X625841Y1808601D01*
X626091Y1808351D01*
X626382Y1808267D01*
X626674Y1808351D01*
X626882Y1808559D01*
X627007Y1808892D01*
X627049Y1809184D01*
G01Y1812284D02*
X627007Y1812576D01*
X626882Y1812909D01*
X626674Y1813117D01*
X626382Y1813201D01*
X626091Y1813117D01*
X625841Y1812867D01*
X625716Y1812492D01*
Y1812076D01*
X625632Y1811826D01*
X625424Y1811617D01*
X625132Y1811534D01*
X624841Y1811659D01*
X624632Y1811951D01*
X624549Y1812284D01*
X624632Y1812617D01*
X624841Y1812909D01*
X625132Y1813034D01*
X625424Y1812951D01*
X625632Y1812742D01*
X625716Y1812492D01*
Y1812076D01*
X625841Y1811701D01*
X626091Y1811451D01*
X626382Y1811367D01*
X626674Y1811451D01*
X626882Y1811659D01*
X627007Y1811992D01*
X627049Y1812284D01*
G01X642049Y1809334D02*
X638049D01*
Y1801934D01*
G01X631049Y1802151D02*
X628549D01*
Y1803192D01*
X628674Y1803526D01*
X628841Y1803734D01*
X629174Y1803817D01*
X629507Y1803734D01*
X629716Y1803484D01*
X629841Y1803192D01*
Y1802151D01*
G01Y1803192D02*
X631049Y1803817D01*
G01X630549Y1805167D02*
X630841Y1805417D01*
X631007Y1805751D01*
X631049Y1806126D01*
X631007Y1806459D01*
X630799Y1806792D01*
X630549Y1807001D01*
X630299Y1807042D01*
X630007Y1806959D01*
X629799Y1806667D01*
X629716Y1806376D01*
Y1806001D01*
G01Y1806376D02*
X629591Y1806626D01*
X629382Y1806834D01*
X629132Y1806917D01*
X628882Y1806834D01*
X628674Y1806626D01*
X628549Y1806251D01*
X628591Y1805876D01*
X628757Y1805501D01*
G01X630757Y1808476D02*
X630966Y1808767D01*
X631049Y1809101D01*
X630966Y1809434D01*
X630716Y1809726D01*
X630341Y1809934D01*
X629966Y1810017D01*
X629507D01*
X629132Y1809934D01*
X628799Y1809726D01*
X628632Y1809476D01*
X628549Y1809184D01*
X628632Y1808851D01*
X628799Y1808601D01*
X629049Y1808434D01*
X629382Y1808351D01*
X629674Y1808434D01*
X629966Y1808642D01*
X630132Y1808892D01*
X630174Y1809184D01*
X630091Y1809517D01*
X629882Y1809767D01*
X629507Y1810017D01*
G01X628549Y1812284D02*
X628632Y1811951D01*
X628841Y1811701D01*
X629091Y1811534D01*
X629424Y1811409D01*
X629799Y1811367D01*
X630174Y1811409D01*
X630507Y1811534D01*
X630757Y1811701D01*
X630966Y1811951D01*
X631049Y1812284D01*
X630966Y1812617D01*
X630757Y1812867D01*
X630507Y1813034D01*
X630174Y1813159D01*
X629799Y1813201D01*
X629424Y1813159D01*
X629091Y1813034D01*
X628841Y1812867D01*
X628632Y1812617D01*
X628549Y1812284D01*
G01X642049Y1801934D02*
X646049D01*
Y1809334D01*
G01X627049Y1786151D02*
X624549D01*
Y1787192D01*
X624674Y1787526D01*
X624841Y1787734D01*
X625174Y1787817D01*
X625507Y1787734D01*
X625716Y1787484D01*
X625841Y1787192D01*
Y1786151D01*
G01Y1787192D02*
X627049Y1787817D01*
G01Y1790584D02*
X624549D01*
X626341Y1789042D01*
Y1791126D01*
G01X627049Y1793184D02*
X627007Y1793476D01*
X626882Y1793809D01*
X626674Y1794017D01*
X626382Y1794101D01*
X626091Y1794017D01*
X625841Y1793767D01*
X625716Y1793392D01*
Y1792976D01*
X625632Y1792726D01*
X625424Y1792517D01*
X625132Y1792434D01*
X624841Y1792559D01*
X624632Y1792851D01*
X624549Y1793184D01*
X624632Y1793517D01*
X624841Y1793809D01*
X625132Y1793934D01*
X625424Y1793851D01*
X625632Y1793642D01*
X625716Y1793392D01*
Y1792976D01*
X625841Y1792601D01*
X626091Y1792351D01*
X626382Y1792267D01*
X626674Y1792351D01*
X626882Y1792559D01*
X627007Y1792892D01*
X627049Y1793184D01*
G01X624966Y1795492D02*
X624716Y1795742D01*
X624591Y1796034D01*
X624549Y1796367D01*
X624632Y1796784D01*
X624841Y1797076D01*
X625091Y1797159D01*
X625341Y1797117D01*
X625549Y1796951D01*
X625966Y1796117D01*
X626257Y1795742D01*
X626674Y1795492D01*
X627049Y1795409D01*
Y1797159D01*
G01X642049Y1798334D02*
X638049D01*
Y1790934D01*
G01X631049Y1786151D02*
X628549D01*
Y1787192D01*
X628674Y1787526D01*
X628841Y1787734D01*
X629174Y1787817D01*
X629507Y1787734D01*
X629716Y1787484D01*
X629841Y1787192D01*
Y1786151D01*
G01Y1787192D02*
X631049Y1787817D01*
G01Y1790584D02*
X628549D01*
X630341Y1789042D01*
Y1791126D01*
G01X631049Y1793184D02*
X631007Y1793476D01*
X630882Y1793809D01*
X630674Y1794017D01*
X630382Y1794101D01*
X630091Y1794017D01*
X629841Y1793767D01*
X629716Y1793392D01*
Y1792976D01*
X629632Y1792726D01*
X629424Y1792517D01*
X629132Y1792434D01*
X628841Y1792559D01*
X628632Y1792851D01*
X628549Y1793184D01*
X628632Y1793517D01*
X628841Y1793809D01*
X629132Y1793934D01*
X629424Y1793851D01*
X629632Y1793642D01*
X629716Y1793392D01*
Y1792976D01*
X629841Y1792601D01*
X630091Y1792351D01*
X630382Y1792267D01*
X630674Y1792351D01*
X630882Y1792559D01*
X631007Y1792892D01*
X631049Y1793184D01*
G01X630549Y1795367D02*
X630841Y1795617D01*
X631007Y1795951D01*
X631049Y1796326D01*
X631007Y1796659D01*
X630799Y1796992D01*
X630549Y1797201D01*
X630299Y1797242D01*
X630007Y1797159D01*
X629799Y1796867D01*
X629716Y1796576D01*
Y1796201D01*
G01Y1796576D02*
X629591Y1796826D01*
X629382Y1797034D01*
X629132Y1797117D01*
X628882Y1797034D01*
X628674Y1796826D01*
X628549Y1796451D01*
X628591Y1796076D01*
X628757Y1795701D01*
G01X642049Y1790934D02*
X646049D01*
Y1798334D01*
G01X643049Y1811151D02*
X640549D01*
Y1812192D01*
X640674Y1812526D01*
X640841Y1812734D01*
X641174Y1812817D01*
X641507Y1812734D01*
X641716Y1812484D01*
X641841Y1812192D01*
Y1811151D01*
G01Y1812192D02*
X643049Y1812817D01*
G01X642549Y1814167D02*
X642841Y1814417D01*
X643007Y1814751D01*
X643049Y1815126D01*
X643007Y1815459D01*
X642799Y1815792D01*
X642549Y1816001D01*
X642299Y1816042D01*
X642007Y1815959D01*
X641799Y1815667D01*
X641716Y1815376D01*
Y1815001D01*
G01Y1815376D02*
X641591Y1815626D01*
X641382Y1815834D01*
X641132Y1815917D01*
X640882Y1815834D01*
X640674Y1815626D01*
X640549Y1815251D01*
X640591Y1814876D01*
X640757Y1814501D01*
G01X642007Y1817392D02*
X641716Y1817684D01*
X641549Y1817934D01*
X641466Y1818267D01*
X641549Y1818559D01*
X641716Y1818767D01*
X641966Y1818934D01*
X642257Y1818976D01*
X642507Y1818934D01*
X642757Y1818767D01*
X642966Y1818517D01*
X643049Y1818226D01*
X642966Y1817892D01*
X642716Y1817601D01*
X642341Y1817434D01*
X641924Y1817392D01*
X641382Y1817476D01*
X641091Y1817601D01*
X640799Y1817809D01*
X640591Y1818101D01*
X640549Y1818392D01*
X640632Y1818684D01*
X640841Y1818892D01*
G01X640966Y1820492D02*
X640716Y1820742D01*
X640591Y1821034D01*
X640549Y1821367D01*
X640632Y1821784D01*
X640841Y1822076D01*
X641091Y1822159D01*
X641341Y1822117D01*
X641549Y1821951D01*
X641966Y1821117D01*
X642257Y1820742D01*
X642674Y1820492D01*
X643049Y1820409D01*
Y1822159D01*
G01X651049Y1816334D02*
X647049D01*
Y1808934D01*
G01X650049Y1822651D02*
X647549D01*
Y1823692D01*
X647674Y1824026D01*
X647841Y1824234D01*
X648174Y1824317D01*
X648507Y1824234D01*
X648716Y1823984D01*
X648841Y1823692D01*
Y1822651D01*
G01Y1823692D02*
X650049Y1824317D01*
G01X649549Y1825667D02*
X649841Y1825917D01*
X650007Y1826251D01*
X650049Y1826626D01*
X650007Y1826959D01*
X649799Y1827292D01*
X649549Y1827501D01*
X649299Y1827542D01*
X649007Y1827459D01*
X648799Y1827167D01*
X648716Y1826876D01*
Y1826501D01*
G01Y1826876D02*
X648591Y1827126D01*
X648382Y1827334D01*
X648132Y1827417D01*
X647882Y1827334D01*
X647674Y1827126D01*
X647549Y1826751D01*
X647591Y1826376D01*
X647757Y1826001D01*
G01X649007Y1828892D02*
X648716Y1829184D01*
X648549Y1829434D01*
X648466Y1829767D01*
X648549Y1830059D01*
X648716Y1830267D01*
X648966Y1830434D01*
X649257Y1830476D01*
X649507Y1830434D01*
X649757Y1830267D01*
X649966Y1830017D01*
X650049Y1829726D01*
X649966Y1829392D01*
X649716Y1829101D01*
X649341Y1828934D01*
X648924Y1828892D01*
X648382Y1828976D01*
X648091Y1829101D01*
X647799Y1829309D01*
X647591Y1829601D01*
X647549Y1829892D01*
X647632Y1830184D01*
X647841Y1830392D01*
G01X650049Y1833284D02*
X647549D01*
X649341Y1831742D01*
Y1833826D01*
G01X645849Y1820634D02*
Y1816634D01*
X653249D01*
G01X656549Y1822651D02*
X654049D01*
Y1823692D01*
X654174Y1824026D01*
X654341Y1824234D01*
X654674Y1824317D01*
X655007Y1824234D01*
X655216Y1823984D01*
X655341Y1823692D01*
Y1822651D01*
G01Y1823692D02*
X656549Y1824317D01*
G01X656049Y1825667D02*
X656341Y1825917D01*
X656507Y1826251D01*
X656549Y1826626D01*
X656507Y1826959D01*
X656299Y1827292D01*
X656049Y1827501D01*
X655799Y1827542D01*
X655507Y1827459D01*
X655299Y1827167D01*
X655216Y1826876D01*
Y1826501D01*
G01Y1826876D02*
X655091Y1827126D01*
X654882Y1827334D01*
X654632Y1827417D01*
X654382Y1827334D01*
X654174Y1827126D01*
X654049Y1826751D01*
X654091Y1826376D01*
X654257Y1826001D01*
G01X656549Y1829684D02*
X656507Y1829976D01*
X656382Y1830309D01*
X656174Y1830517D01*
X655882Y1830601D01*
X655591Y1830517D01*
X655341Y1830267D01*
X655216Y1829892D01*
Y1829476D01*
X655132Y1829226D01*
X654924Y1829017D01*
X654632Y1828934D01*
X654341Y1829059D01*
X654132Y1829351D01*
X654049Y1829684D01*
X654132Y1830017D01*
X654341Y1830309D01*
X654632Y1830434D01*
X654924Y1830351D01*
X655132Y1830142D01*
X655216Y1829892D01*
Y1829476D01*
X655341Y1829101D01*
X655591Y1828851D01*
X655882Y1828767D01*
X656174Y1828851D01*
X656382Y1829059D01*
X656507Y1829392D01*
X656549Y1829684D01*
G01Y1832784D02*
X654049D01*
X654549Y1832284D01*
G01X656549D02*
Y1833284D01*
G01X657549Y1820834D02*
X653549D01*
Y1813434D01*
G01X659199Y1826250D02*
X661699D01*
G01X659199Y1825292D02*
Y1827208D01*
G01X661699Y1828517D02*
X659199D01*
Y1829517D01*
X659324Y1829850D01*
X659616Y1830100D01*
X659949Y1830183D01*
X660282Y1830100D01*
X660532Y1829892D01*
X660657Y1829517D01*
Y1828517D01*
G01X661699Y1832450D02*
X659199D01*
X659699Y1831950D01*
G01X661699D02*
Y1832950D01*
G01X661324Y1834633D02*
X661532Y1834883D01*
X661657Y1835175D01*
X661699Y1835550D01*
X661616Y1835925D01*
X661449Y1836217D01*
X661157Y1836425D01*
X660824Y1836467D01*
X660491Y1836383D01*
X660282Y1836175D01*
X660116Y1835883D01*
X660074Y1835592D01*
X660116Y1835300D01*
X660282Y1834925D01*
X659199Y1835050D01*
Y1836175D01*
G01Y1838650D02*
X659282Y1838317D01*
X659491Y1838067D01*
X659741Y1837900D01*
X660074Y1837775D01*
X660449Y1837733D01*
X660824Y1837775D01*
X661157Y1837900D01*
X661407Y1838067D01*
X661616Y1838317D01*
X661699Y1838650D01*
X661616Y1838983D01*
X661407Y1839233D01*
X661157Y1839400D01*
X660824Y1839525D01*
X660449Y1839567D01*
X660074Y1839525D01*
X659741Y1839400D01*
X659491Y1839233D01*
X659282Y1838983D01*
X659199Y1838650D01*
G01X671032Y1823634D02*
Y1821842D01*
X671199Y1821467D01*
X671532Y1821217D01*
X671949Y1821134D01*
X672366Y1821217D01*
X672699Y1821467D01*
X672866Y1821842D01*
Y1823634D01*
G01X674132Y1821509D02*
X674382Y1821301D01*
X674674Y1821176D01*
X675049Y1821134D01*
X675424Y1821217D01*
X675716Y1821384D01*
X675924Y1821676D01*
X675966Y1822009D01*
X675882Y1822342D01*
X675674Y1822551D01*
X675382Y1822717D01*
X675091Y1822759D01*
X674799Y1822717D01*
X674424Y1822551D01*
X674549Y1823634D01*
X675674D01*
G01X677232Y1821634D02*
X677482Y1821342D01*
X677816Y1821176D01*
X678191Y1821134D01*
X678524Y1821176D01*
X678857Y1821384D01*
X679066Y1821634D01*
X679107Y1821884D01*
X679024Y1822176D01*
X678732Y1822384D01*
X678441Y1822467D01*
X678066D01*
G01X678441D02*
X678691Y1822592D01*
X678899Y1822801D01*
X678982Y1823051D01*
X678899Y1823301D01*
X678691Y1823509D01*
X678316Y1823634D01*
X677941Y1823592D01*
X677566Y1823426D01*
G01X670549Y1818534D02*
X678549D01*
Y1806134D01*
X670549D01*
Y1818534D01*
G01X674549Y1816834D02*
X676049Y1818334D01*
G01X674549Y1816834D02*
X673049Y1818334D01*
G01X686499Y198050D02*
Y188050D01*
G01X682666Y198050D02*
X690332D01*
G01X700432Y188050D02*
X693766D01*
Y198050D01*
X700432D01*
G01X697766Y193217D02*
X693766D01*
G01X703366Y188050D02*
Y198050D01*
X707699Y189717D01*
X712032Y198050D01*
Y188050D01*
G01X714966D02*
Y198050D01*
X718966D01*
X720299Y197550D01*
X721299Y196383D01*
X721632Y195050D01*
X721299Y193717D01*
X720466Y192717D01*
X718966Y192216D01*
X714966D01*
G01X723899Y184717D02*
X733899D01*
G01X735999Y189383D02*
X737332Y188550D01*
X738832Y188050D01*
X740166D01*
X741499Y188550D01*
X742499Y189383D01*
X742999Y190550D01*
X742666Y191716D01*
X741832Y192717D01*
X740332Y193383D01*
X738332Y193717D01*
X737166Y194383D01*
X736666Y195550D01*
X736999Y196717D01*
X737832Y197550D01*
X738999Y198050D01*
X740166D01*
X741332Y197717D01*
X742332Y196883D01*
G01X753432Y188050D02*
X746766D01*
Y198050D01*
X753432D01*
G01X750766Y193217D02*
X746766D01*
G01X756866Y188050D02*
Y198050D01*
X764532Y188050D01*
Y198050D01*
G01X767799Y189383D02*
X769132Y188550D01*
X770632Y188050D01*
X771966D01*
X773299Y188550D01*
X774299Y189383D01*
X774799Y190550D01*
X774466Y191716D01*
X773632Y192717D01*
X772132Y193383D01*
X770132Y193717D01*
X768966Y194383D01*
X768466Y195550D01*
X768799Y196717D01*
X769632Y197550D01*
X770799Y198050D01*
X771966D01*
X773132Y197717D01*
X774132Y196883D01*
G01X781899Y188050D02*
X780565Y188217D01*
X779399Y188883D01*
X778399Y189883D01*
X777732Y191050D01*
X777399Y192383D01*
Y193717D01*
X777732Y195050D01*
X778399Y196217D01*
X779399Y197217D01*
X780565Y197883D01*
X781899Y198050D01*
X783232Y197883D01*
X784399Y197217D01*
X785399Y196217D01*
X786066Y195050D01*
X786399Y193717D01*
Y192383D01*
X786066Y191050D01*
X785399Y189883D01*
X784399Y188883D01*
X783232Y188217D01*
X781899Y188050D01*
G01X789166D02*
Y198050D01*
X793332D01*
X794666Y197550D01*
X795499Y196883D01*
X795832Y195550D01*
X795499Y194217D01*
X794499Y193383D01*
X793332Y192883D01*
X789166D01*
G01X793332D02*
X795832Y188050D01*
G01X805099D02*
Y198050D01*
X798932Y190883D01*
X807266D01*
G01X752983Y368500D02*
Y371000D01*
X753817D01*
X754150Y370875D01*
X754400Y370708D01*
X754608Y370458D01*
X754775Y370167D01*
X754817Y369750D01*
X754775Y369333D01*
X754608Y369042D01*
X754400Y368792D01*
X754150Y368625D01*
X753817Y368500D01*
X752983D01*
G01X757000D02*
Y371000D01*
X756500Y370500D01*
G01Y368500D02*
X757500D01*
G01X759392Y368792D02*
X759683Y368583D01*
X760017Y368500D01*
X760350Y368583D01*
X760642Y368833D01*
X760850Y369208D01*
X760933Y369583D01*
Y370042D01*
X760850Y370417D01*
X760642Y370750D01*
X760392Y370917D01*
X760100Y371000D01*
X759767Y370917D01*
X759517Y370750D01*
X759350Y370500D01*
X759267Y370167D01*
X759350Y369875D01*
X759558Y369583D01*
X759808Y369417D01*
X760100Y369375D01*
X760433Y369458D01*
X760683Y369667D01*
X760933Y370042D01*
G01X766000Y359000D02*
X749900D01*
G01Y366000D02*
X766000D01*
G01X749900Y359000D02*
Y366000D01*
G01X740608Y353767D02*
X740483Y353517D01*
X740400Y353225D01*
Y352892D01*
X740525Y352517D01*
X740733Y352225D01*
X740983Y352017D01*
X741400Y351850D01*
X741775Y351808D01*
X742150Y351892D01*
X742400Y352017D01*
X742650Y352267D01*
X742817Y352558D01*
X742900Y352850D01*
Y353142D01*
X742817Y353433D01*
X742692Y353683D01*
X742525Y353892D01*
G01X742400Y355033D02*
X742692Y355283D01*
X742858Y355617D01*
X742900Y355992D01*
X742858Y356325D01*
X742650Y356658D01*
X742400Y356867D01*
X742150Y356908D01*
X741858Y356825D01*
X741650Y356533D01*
X741567Y356242D01*
Y355867D01*
G01Y356242D02*
X741442Y356492D01*
X741233Y356700D01*
X740983Y356783D01*
X740733Y356700D01*
X740525Y356492D01*
X740400Y356117D01*
X740442Y355742D01*
X740608Y355367D01*
G01X742900Y359050D02*
X742858Y359342D01*
X742733Y359675D01*
X742525Y359883D01*
X742233Y359967D01*
X741942Y359883D01*
X741692Y359633D01*
X741567Y359258D01*
Y358842D01*
X741483Y358592D01*
X741275Y358383D01*
X740983Y358300D01*
X740692Y358425D01*
X740483Y358717D01*
X740400Y359050D01*
X740483Y359383D01*
X740692Y359675D01*
X740983Y359800D01*
X741275Y359717D01*
X741483Y359508D01*
X741567Y359258D01*
Y358842D01*
X741692Y358467D01*
X741942Y358217D01*
X742233Y358133D01*
X742525Y358217D01*
X742733Y358425D01*
X742858Y358758D01*
X742900Y359050D01*
G01X742400Y361233D02*
X742692Y361483D01*
X742858Y361817D01*
X742900Y362192D01*
X742858Y362525D01*
X742650Y362858D01*
X742400Y363067D01*
X742150Y363108D01*
X741858Y363025D01*
X741650Y362733D01*
X741567Y362442D01*
Y362067D01*
G01Y362442D02*
X741442Y362692D01*
X741233Y362900D01*
X740983Y362983D01*
X740733Y362900D01*
X740525Y362692D01*
X740400Y362317D01*
X740442Y361942D01*
X740608Y361567D01*
G01X739500Y334350D02*
X739458Y334017D01*
X739292Y333725D01*
X739042Y333475D01*
X738750Y333308D01*
X738417Y333225D01*
X738083D01*
X737750Y333308D01*
X737458Y333475D01*
X737208Y333725D01*
X737042Y334017D01*
X737000Y334350D01*
X737042Y334683D01*
X737208Y334975D01*
X737458Y335225D01*
X737750Y335392D01*
X738083Y335475D01*
X738417D01*
X738750Y335392D01*
X739042Y335225D01*
X739292Y334975D01*
X739458Y334683D01*
X739500Y334350D01*
G01X738833Y334683D02*
X739500Y335183D01*
G01Y337450D02*
X737000D01*
X737500Y336950D01*
G01X739500D02*
Y337950D01*
G01X737000Y340550D02*
X737083Y340217D01*
X737292Y339967D01*
X737542Y339800D01*
X737875Y339675D01*
X738250Y339633D01*
X738625Y339675D01*
X738958Y339800D01*
X739208Y339967D01*
X739417Y340217D01*
X739500Y340550D01*
X739417Y340883D01*
X739208Y341133D01*
X738958Y341300D01*
X738625Y341425D01*
X738250Y341467D01*
X737875Y341425D01*
X737542Y341300D01*
X737292Y341133D01*
X737083Y340883D01*
X737000Y340550D01*
G01X755778Y345124D02*
Y333724D01*
G01X769178Y345124D02*
X755778D01*
G01Y333724D02*
X769178D01*
G01X738900Y352017D02*
X736400D01*
Y353058D01*
X736525Y353392D01*
X736692Y353600D01*
X737025Y353683D01*
X737358Y353600D01*
X737567Y353350D01*
X737692Y353058D01*
Y352017D01*
G01Y353058D02*
X738900Y353683D01*
G01X738525Y355033D02*
X738733Y355283D01*
X738858Y355575D01*
X738900Y355950D01*
X738817Y356325D01*
X738650Y356617D01*
X738358Y356825D01*
X738025Y356867D01*
X737692Y356783D01*
X737483Y356575D01*
X737317Y356283D01*
X737275Y355992D01*
X737317Y355700D01*
X737483Y355325D01*
X736400Y355450D01*
Y356575D01*
G01X737858Y358258D02*
X737567Y358550D01*
X737400Y358800D01*
X737317Y359133D01*
X737400Y359425D01*
X737567Y359633D01*
X737817Y359800D01*
X738108Y359842D01*
X738358Y359800D01*
X738608Y359633D01*
X738817Y359383D01*
X738900Y359092D01*
X738817Y358758D01*
X738567Y358467D01*
X738192Y358300D01*
X737775Y358258D01*
X737233Y358342D01*
X736942Y358467D01*
X736650Y358675D01*
X736442Y358967D01*
X736400Y359258D01*
X736483Y359550D01*
X736692Y359758D01*
G01X738900Y362067D02*
X738358Y362150D01*
X737900Y362275D01*
X737483Y362442D01*
X737025Y362650D01*
X736400Y362983D01*
Y361317D01*
G01X722717Y357700D02*
Y360200D01*
X723758D01*
X724092Y360075D01*
X724300Y359908D01*
X724383Y359575D01*
X724300Y359242D01*
X724050Y359033D01*
X723758Y358908D01*
X722717D01*
G01X723758D02*
X724383Y357700D01*
G01X725733Y358075D02*
X725983Y357867D01*
X726275Y357742D01*
X726650Y357700D01*
X727025Y357783D01*
X727317Y357950D01*
X727525Y358242D01*
X727567Y358575D01*
X727483Y358908D01*
X727275Y359117D01*
X726983Y359283D01*
X726692Y359325D01*
X726400Y359283D01*
X726025Y359117D01*
X726150Y360200D01*
X727275D01*
G01X728833Y358075D02*
X729083Y357867D01*
X729375Y357742D01*
X729750Y357700D01*
X730125Y357783D01*
X730417Y357950D01*
X730625Y358242D01*
X730667Y358575D01*
X730583Y358908D01*
X730375Y359117D01*
X730083Y359283D01*
X729792Y359325D01*
X729500Y359283D01*
X729125Y359117D01*
X729250Y360200D01*
X730375D01*
G01X731933Y358200D02*
X732183Y357908D01*
X732517Y357742D01*
X732892Y357700D01*
X733225Y357742D01*
X733558Y357950D01*
X733767Y358200D01*
X733808Y358450D01*
X733725Y358742D01*
X733433Y358950D01*
X733142Y359033D01*
X732767D01*
G01X733142D02*
X733392Y359158D01*
X733600Y359367D01*
X733683Y359617D01*
X733600Y359867D01*
X733392Y360075D01*
X733017Y360200D01*
X732642Y360158D01*
X732267Y359992D01*
G01X755300Y357500D02*
Y353500D01*
X762700D01*
G01X714622Y323186D02*
Y325686D01*
X715663D01*
X715997Y325561D01*
X716205Y325394D01*
X716288Y325061D01*
X716205Y324728D01*
X715955Y324519D01*
X715663Y324394D01*
X714622D01*
G01X715663D02*
X716288Y323186D01*
G01X718555D02*
Y325686D01*
X718055Y325186D01*
G01Y323186D02*
X719055D01*
G01X720863Y324228D02*
X721155Y324519D01*
X721405Y324686D01*
X721738Y324769D01*
X722030Y324686D01*
X722238Y324519D01*
X722405Y324269D01*
X722447Y323978D01*
X722405Y323728D01*
X722238Y323478D01*
X721988Y323269D01*
X721697Y323186D01*
X721363Y323269D01*
X721072Y323519D01*
X720905Y323894D01*
X720863Y324311D01*
X720947Y324853D01*
X721072Y325144D01*
X721280Y325436D01*
X721572Y325644D01*
X721863Y325686D01*
X722155Y325603D01*
X722363Y325394D01*
G01X725255Y323186D02*
Y325686D01*
X723713Y323894D01*
X725797D01*
G01X756678Y321924D02*
Y325924D01*
X749278D01*
G01X721817Y351800D02*
Y354300D01*
X722858D01*
X723192Y354175D01*
X723400Y354008D01*
X723483Y353675D01*
X723400Y353342D01*
X723150Y353133D01*
X722858Y353008D01*
X721817D01*
G01X722858D02*
X723483Y351800D01*
G01X725750D02*
Y354300D01*
X725250Y353800D01*
G01Y351800D02*
X726250D01*
G01X728058Y352842D02*
X728350Y353133D01*
X728600Y353300D01*
X728933Y353383D01*
X729225Y353300D01*
X729433Y353133D01*
X729600Y352883D01*
X729642Y352592D01*
X729600Y352342D01*
X729433Y352092D01*
X729183Y351883D01*
X728892Y351800D01*
X728558Y351883D01*
X728267Y352133D01*
X728100Y352508D01*
X728058Y352925D01*
X728142Y353467D01*
X728267Y353758D01*
X728475Y354050D01*
X728767Y354258D01*
X729058Y354300D01*
X729350Y354217D01*
X729558Y354008D01*
G01X731033Y352175D02*
X731283Y351967D01*
X731575Y351842D01*
X731950Y351800D01*
X732325Y351883D01*
X732617Y352050D01*
X732825Y352342D01*
X732867Y352675D01*
X732783Y353008D01*
X732575Y353217D01*
X732283Y353383D01*
X731992Y353425D01*
X731700Y353383D01*
X731325Y353217D01*
X731450Y354300D01*
X732575D01*
G01X751800Y353500D02*
Y349500D01*
X759200D01*
G01X719000Y349317D02*
X716500D01*
Y350358D01*
X716625Y350692D01*
X716792Y350900D01*
X717125Y350983D01*
X717458Y350900D01*
X717667Y350650D01*
X717792Y350358D01*
Y349317D01*
G01Y350358D02*
X719000Y350983D01*
G01Y353250D02*
X716500D01*
X717000Y352750D01*
G01X719000D02*
Y353750D01*
G01X717958Y355558D02*
X717667Y355850D01*
X717500Y356100D01*
X717417Y356433D01*
X717500Y356725D01*
X717667Y356933D01*
X717917Y357100D01*
X718208Y357142D01*
X718458Y357100D01*
X718708Y356933D01*
X718917Y356683D01*
X719000Y356392D01*
X718917Y356058D01*
X718667Y355767D01*
X718292Y355600D01*
X717875Y355558D01*
X717333Y355642D01*
X717042Y355767D01*
X716750Y355975D01*
X716542Y356267D01*
X716500Y356558D01*
X716583Y356850D01*
X716792Y357058D01*
G01X717958Y358658D02*
X717667Y358950D01*
X717500Y359200D01*
X717417Y359533D01*
X717500Y359825D01*
X717667Y360033D01*
X717917Y360200D01*
X718208Y360242D01*
X718458Y360200D01*
X718708Y360033D01*
X718917Y359783D01*
X719000Y359492D01*
X718917Y359158D01*
X718667Y358867D01*
X718292Y358700D01*
X717875Y358658D01*
X717333Y358742D01*
X717042Y358867D01*
X716750Y359075D01*
X716542Y359367D01*
X716500Y359658D01*
X716583Y359950D01*
X716792Y360158D01*
G01X751500Y353700D02*
X747500D01*
Y346300D01*
G01X735500Y333517D02*
X733000D01*
Y334558D01*
X733125Y334892D01*
X733292Y335100D01*
X733625Y335183D01*
X733958Y335100D01*
X734167Y334850D01*
X734292Y334558D01*
Y333517D01*
G01Y334558D02*
X735500Y335183D01*
G01Y337450D02*
X733000D01*
X733500Y336950D01*
G01X735500D02*
Y337950D01*
G01X734458Y339758D02*
X734167Y340050D01*
X734000Y340300D01*
X733917Y340633D01*
X734000Y340925D01*
X734167Y341133D01*
X734417Y341300D01*
X734708Y341342D01*
X734958Y341300D01*
X735208Y341133D01*
X735417Y340883D01*
X735500Y340592D01*
X735417Y340258D01*
X735167Y339967D01*
X734792Y339800D01*
X734375Y339758D01*
X733833Y339842D01*
X733542Y339967D01*
X733250Y340175D01*
X733042Y340467D01*
X733000Y340758D01*
X733083Y341050D01*
X733292Y341258D01*
G01X735500Y343650D02*
X735458Y343942D01*
X735333Y344275D01*
X735125Y344483D01*
X734833Y344567D01*
X734542Y344483D01*
X734292Y344233D01*
X734167Y343858D01*
Y343442D01*
X734083Y343192D01*
X733875Y342983D01*
X733583Y342900D01*
X733292Y343025D01*
X733083Y343317D01*
X733000Y343650D01*
X733083Y343983D01*
X733292Y344275D01*
X733583Y344400D01*
X733875Y344317D01*
X734083Y344108D01*
X734167Y343858D01*
Y343442D01*
X734292Y343067D01*
X734542Y342817D01*
X734833Y342733D01*
X735125Y342817D01*
X735333Y343025D01*
X735458Y343358D01*
X735500Y343650D01*
G01X750978Y333724D02*
X754978D01*
Y341124D01*
G01X714643Y327312D02*
Y329812D01*
X715684D01*
X716018Y329687D01*
X716226Y329520D01*
X716309Y329187D01*
X716226Y328854D01*
X715976Y328645D01*
X715684Y328520D01*
X714643D01*
G01X715684D02*
X716309Y327312D01*
G01X718576D02*
Y329812D01*
X718076Y329312D01*
G01Y327312D02*
X719076D01*
G01X720884Y328354D02*
X721176Y328645D01*
X721426Y328812D01*
X721759Y328895D01*
X722051Y328812D01*
X722259Y328645D01*
X722426Y328395D01*
X722468Y328104D01*
X722426Y327854D01*
X722259Y327604D01*
X722009Y327395D01*
X721718Y327312D01*
X721384Y327395D01*
X721093Y327645D01*
X720926Y328020D01*
X720884Y328437D01*
X720968Y328979D01*
X721093Y329270D01*
X721301Y329562D01*
X721593Y329770D01*
X721884Y329812D01*
X722176Y329729D01*
X722384Y329520D01*
G01X724068Y327604D02*
X724359Y327395D01*
X724693Y327312D01*
X725026Y327395D01*
X725318Y327645D01*
X725526Y328020D01*
X725609Y328395D01*
Y328854D01*
X725526Y329229D01*
X725318Y329562D01*
X725068Y329729D01*
X724776Y329812D01*
X724443Y329729D01*
X724193Y329562D01*
X724026Y329312D01*
X723943Y328979D01*
X724026Y328687D01*
X724234Y328395D01*
X724484Y328229D01*
X724776Y328187D01*
X725109Y328270D01*
X725359Y328479D01*
X725609Y328854D01*
G01X756678Y326924D02*
Y330924D01*
X749278D01*
G01X733143Y327312D02*
Y329812D01*
X734184D01*
X734518Y329687D01*
X734726Y329520D01*
X734809Y329187D01*
X734726Y328854D01*
X734476Y328645D01*
X734184Y328520D01*
X733143D01*
G01X734184D02*
X734809Y327312D01*
G01X737576D02*
Y329812D01*
X736034Y328020D01*
X738118D01*
G01X740676Y327312D02*
Y329812D01*
X739134Y328020D01*
X741218D01*
G01X743276Y329812D02*
X742943Y329729D01*
X742693Y329520D01*
X742526Y329270D01*
X742401Y328937D01*
X742359Y328562D01*
X742401Y328187D01*
X742526Y327854D01*
X742693Y327604D01*
X742943Y327395D01*
X743276Y327312D01*
X743609Y327395D01*
X743859Y327604D01*
X744026Y327854D01*
X744151Y328187D01*
X744193Y328562D01*
X744151Y328937D01*
X744026Y329270D01*
X743859Y329520D01*
X743609Y329729D01*
X743276Y329812D01*
G01X733143Y323312D02*
Y325812D01*
X734184D01*
X734518Y325687D01*
X734726Y325520D01*
X734809Y325187D01*
X734726Y324854D01*
X734476Y324645D01*
X734184Y324520D01*
X733143D01*
G01X734184D02*
X734809Y323312D01*
G01X737576D02*
Y325812D01*
X736034Y324020D01*
X738118D01*
G01X740676Y323312D02*
Y325812D01*
X739134Y324020D01*
X741218D01*
G01X743276Y323312D02*
Y325812D01*
X742776Y325312D01*
G01Y323312D02*
X743776D01*
G01X743500Y333517D02*
X741000D01*
Y334558D01*
X741125Y334892D01*
X741292Y335100D01*
X741625Y335183D01*
X741958Y335100D01*
X742167Y334850D01*
X742292Y334558D01*
Y333517D01*
G01Y334558D02*
X743500Y335183D01*
G01Y337950D02*
X741000D01*
X742792Y336408D01*
Y338492D01*
G01X743500Y340550D02*
X741000D01*
X741500Y340050D01*
G01X743500D02*
Y341050D01*
G01X741417Y342858D02*
X741167Y343108D01*
X741042Y343400D01*
X741000Y343733D01*
X741083Y344150D01*
X741292Y344442D01*
X741542Y344525D01*
X741792Y344483D01*
X742000Y344317D01*
X742417Y343483D01*
X742708Y343108D01*
X743125Y342858D01*
X743500Y342775D01*
Y344525D01*
G01X728626Y323295D02*
X730418D01*
X730793Y323462D01*
X731043Y323795D01*
X731126Y324212D01*
X731043Y324629D01*
X730793Y324962D01*
X730418Y325129D01*
X728626D01*
G01X731126Y327312D02*
X728626D01*
X729126Y326812D01*
G01X731126D02*
Y327812D01*
G01X730751Y329495D02*
X730959Y329745D01*
X731084Y330037D01*
X731126Y330412D01*
X731043Y330787D01*
X730876Y331079D01*
X730584Y331287D01*
X730251Y331329D01*
X729918Y331245D01*
X729709Y331037D01*
X729543Y330745D01*
X729501Y330454D01*
X729543Y330162D01*
X729709Y329787D01*
X728626Y329912D01*
Y331037D01*
G01X749708Y703267D02*
X749583Y703017D01*
X749500Y702725D01*
Y702392D01*
X749625Y702017D01*
X749833Y701725D01*
X750083Y701517D01*
X750500Y701350D01*
X750875Y701308D01*
X751250Y701392D01*
X751500Y701517D01*
X751750Y701767D01*
X751917Y702058D01*
X752000Y702350D01*
Y702642D01*
X751917Y702933D01*
X751792Y703183D01*
X751625Y703392D01*
G01X752000Y705450D02*
X749500D01*
X750000Y704950D01*
G01X752000D02*
Y705950D01*
G01X751625Y707633D02*
X751833Y707883D01*
X751958Y708175D01*
X752000Y708550D01*
X751917Y708925D01*
X751750Y709217D01*
X751458Y709425D01*
X751125Y709467D01*
X750792Y709383D01*
X750583Y709175D01*
X750417Y708883D01*
X750375Y708592D01*
X750417Y708300D01*
X750583Y707925D01*
X749500Y708050D01*
Y709175D01*
G01X752000Y711650D02*
X751958Y711942D01*
X751833Y712275D01*
X751625Y712483D01*
X751333Y712567D01*
X751042Y712483D01*
X750792Y712233D01*
X750667Y711858D01*
Y711442D01*
X750583Y711192D01*
X750375Y710983D01*
X750083Y710900D01*
X749792Y711025D01*
X749583Y711317D01*
X749500Y711650D01*
X749583Y711983D01*
X749792Y712275D01*
X750083Y712400D01*
X750375Y712317D01*
X750583Y712108D01*
X750667Y711858D01*
Y711442D01*
X750792Y711067D01*
X751042Y710817D01*
X751333Y710733D01*
X751625Y710817D01*
X751833Y711025D01*
X751958Y711358D01*
X752000Y711650D01*
G01X730894Y723566D02*
Y726066D01*
X731935D01*
X732269Y725941D01*
X732477Y725774D01*
X732560Y725441D01*
X732477Y725108D01*
X732227Y724899D01*
X731935Y724774D01*
X730894D01*
G01X731935D02*
X732560Y723566D01*
G01X734827D02*
Y726066D01*
X734327Y725566D01*
G01Y723566D02*
X735327D01*
G01X738427D02*
Y726066D01*
X736885Y724274D01*
X738969D01*
G01X740944Y723566D02*
X741027Y724108D01*
X741152Y724566D01*
X741319Y724983D01*
X741527Y725441D01*
X741860Y726066D01*
X740194D01*
G01X755396Y722882D02*
Y726882D01*
X747996D01*
G01X730894Y728566D02*
Y731066D01*
X731935D01*
X732269Y730941D01*
X732477Y730774D01*
X732560Y730441D01*
X732477Y730108D01*
X732227Y729899D01*
X731935Y729774D01*
X730894D01*
G01X731935D02*
X732560Y728566D01*
G01X734827D02*
Y731066D01*
X734327Y730566D01*
G01Y728566D02*
X735327D01*
G01X737010Y728941D02*
X737260Y728733D01*
X737552Y728608D01*
X737927Y728566D01*
X738302Y728649D01*
X738594Y728816D01*
X738802Y729108D01*
X738844Y729441D01*
X738760Y729774D01*
X738552Y729983D01*
X738260Y730149D01*
X737969Y730191D01*
X737677Y730149D01*
X737302Y729983D01*
X737427Y731066D01*
X738552D01*
G01X740110Y728941D02*
X740360Y728733D01*
X740652Y728608D01*
X741027Y728566D01*
X741402Y728649D01*
X741694Y728816D01*
X741902Y729108D01*
X741944Y729441D01*
X741860Y729774D01*
X741652Y729983D01*
X741360Y730149D01*
X741069Y730191D01*
X740777Y730149D01*
X740402Y729983D01*
X740527Y731066D01*
X741652D01*
G01X755396Y727882D02*
Y731882D01*
X747996D01*
G01X753983Y720000D02*
Y718208D01*
X754150Y717833D01*
X754483Y717583D01*
X754900Y717500D01*
X755317Y717583D01*
X755650Y717833D01*
X755817Y718208D01*
Y720000D01*
G01X758000Y717500D02*
Y720000D01*
X757500Y719500D01*
G01Y717500D02*
X758500D01*
G01X760308Y719583D02*
X760558Y719833D01*
X760850Y719958D01*
X761183Y720000D01*
X761600Y719917D01*
X761892Y719708D01*
X761975Y719458D01*
X761933Y719208D01*
X761767Y719000D01*
X760933Y718583D01*
X760558Y718292D01*
X760308Y717875D01*
X760225Y717500D01*
X761975D01*
G01X756996Y722382D02*
Y732382D01*
G01X770396Y722382D02*
X756996D01*
G01X754983Y768000D02*
Y770500D01*
X755817D01*
X756150Y770375D01*
X756400Y770208D01*
X756608Y769958D01*
X756775Y769667D01*
X756817Y769250D01*
X756775Y768833D01*
X756608Y768542D01*
X756400Y768292D01*
X756150Y768125D01*
X755817Y768000D01*
X754983D01*
G01X759000D02*
Y770500D01*
X758500Y770000D01*
G01Y768000D02*
X759500D01*
G01X762100D02*
X762392Y768042D01*
X762725Y768167D01*
X762933Y768375D01*
X763017Y768667D01*
X762933Y768958D01*
X762683Y769208D01*
X762308Y769333D01*
X761892D01*
X761642Y769417D01*
X761433Y769625D01*
X761350Y769917D01*
X761475Y770208D01*
X761767Y770417D01*
X762100Y770500D01*
X762433Y770417D01*
X762725Y770208D01*
X762850Y769917D01*
X762767Y769625D01*
X762558Y769417D01*
X762308Y769333D01*
X761892D01*
X761517Y769208D01*
X761267Y768958D01*
X761183Y768667D01*
X761267Y768375D01*
X761475Y768167D01*
X761808Y768042D01*
X762100Y768000D01*
G01X769000Y758000D02*
X752900D01*
G01Y765000D02*
X769000D01*
G01X752900Y758000D02*
Y765000D01*
G01X743408Y752967D02*
X743283Y752717D01*
X743200Y752425D01*
Y752092D01*
X743325Y751717D01*
X743533Y751425D01*
X743783Y751217D01*
X744200Y751050D01*
X744575Y751008D01*
X744950Y751092D01*
X745200Y751217D01*
X745450Y751467D01*
X745617Y751758D01*
X745700Y752050D01*
Y752342D01*
X745617Y752633D01*
X745492Y752883D01*
X745325Y753092D01*
G01X745200Y754233D02*
X745492Y754483D01*
X745658Y754817D01*
X745700Y755192D01*
X745658Y755525D01*
X745450Y755858D01*
X745200Y756067D01*
X744950Y756108D01*
X744658Y756025D01*
X744450Y755733D01*
X744367Y755442D01*
Y755067D01*
G01Y755442D02*
X744242Y755692D01*
X744033Y755900D01*
X743783Y755983D01*
X743533Y755900D01*
X743325Y755692D01*
X743200Y755317D01*
X743242Y754942D01*
X743408Y754567D01*
G01X745700Y758250D02*
X745658Y758542D01*
X745533Y758875D01*
X745325Y759083D01*
X745033Y759167D01*
X744742Y759083D01*
X744492Y758833D01*
X744367Y758458D01*
Y758042D01*
X744283Y757792D01*
X744075Y757583D01*
X743783Y757500D01*
X743492Y757625D01*
X743283Y757917D01*
X743200Y758250D01*
X743283Y758583D01*
X743492Y758875D01*
X743783Y759000D01*
X744075Y758917D01*
X744283Y758708D01*
X744367Y758458D01*
Y758042D01*
X744492Y757667D01*
X744742Y757417D01*
X745033Y757333D01*
X745325Y757417D01*
X745533Y757625D01*
X745658Y757958D01*
X745700Y758250D01*
G01X743617Y760558D02*
X743367Y760808D01*
X743242Y761100D01*
X743200Y761433D01*
X743283Y761850D01*
X743492Y762142D01*
X743742Y762225D01*
X743992Y762183D01*
X744200Y762017D01*
X744617Y761183D01*
X744908Y760808D01*
X745325Y760558D01*
X745700Y760475D01*
Y762225D01*
G01X737000Y735350D02*
X736958Y735017D01*
X736792Y734725D01*
X736542Y734475D01*
X736250Y734308D01*
X735917Y734225D01*
X735583D01*
X735250Y734308D01*
X734958Y734475D01*
X734708Y734725D01*
X734542Y735017D01*
X734500Y735350D01*
X734542Y735683D01*
X734708Y735975D01*
X734958Y736225D01*
X735250Y736392D01*
X735583Y736475D01*
X735917D01*
X736250Y736392D01*
X736542Y736225D01*
X736792Y735975D01*
X736958Y735683D01*
X737000Y735350D01*
G01X736333Y735683D02*
X737000Y736183D01*
G01Y738450D02*
X736958Y738742D01*
X736833Y739075D01*
X736625Y739283D01*
X736333Y739367D01*
X736042Y739283D01*
X735792Y739033D01*
X735667Y738658D01*
Y738242D01*
X735583Y737992D01*
X735375Y737783D01*
X735083Y737700D01*
X734792Y737825D01*
X734583Y738117D01*
X734500Y738450D01*
X734583Y738783D01*
X734792Y739075D01*
X735083Y739200D01*
X735375Y739117D01*
X735583Y738908D01*
X735667Y738658D01*
Y738242D01*
X735792Y737867D01*
X736042Y737617D01*
X736333Y737533D01*
X736625Y737617D01*
X736833Y737825D01*
X736958Y738158D01*
X737000Y738450D01*
G01X753996Y745582D02*
Y734182D01*
G01X767396Y745582D02*
X753996D01*
G01Y734182D02*
X767396D01*
G01X740900Y751417D02*
X738400D01*
Y752458D01*
X738525Y752792D01*
X738692Y753000D01*
X739025Y753083D01*
X739358Y753000D01*
X739567Y752750D01*
X739692Y752458D01*
Y751417D01*
G01Y752458D02*
X740900Y753083D01*
G01X740525Y754433D02*
X740733Y754683D01*
X740858Y754975D01*
X740900Y755350D01*
X740817Y755725D01*
X740650Y756017D01*
X740358Y756225D01*
X740025Y756267D01*
X739692Y756183D01*
X739483Y755975D01*
X739317Y755683D01*
X739275Y755392D01*
X739317Y755100D01*
X739483Y754725D01*
X738400Y754850D01*
Y755975D01*
G01X739858Y757658D02*
X739567Y757950D01*
X739400Y758200D01*
X739317Y758533D01*
X739400Y758825D01*
X739567Y759033D01*
X739817Y759200D01*
X740108Y759242D01*
X740358Y759200D01*
X740608Y759033D01*
X740817Y758783D01*
X740900Y758492D01*
X740817Y758158D01*
X740567Y757867D01*
X740192Y757700D01*
X739775Y757658D01*
X739233Y757742D01*
X738942Y757867D01*
X738650Y758075D01*
X738442Y758367D01*
X738400Y758658D01*
X738483Y758950D01*
X738692Y759158D01*
G01X739858Y760758D02*
X739567Y761050D01*
X739400Y761300D01*
X739317Y761633D01*
X739400Y761925D01*
X739567Y762133D01*
X739817Y762300D01*
X740108Y762342D01*
X740358Y762300D01*
X740608Y762133D01*
X740817Y761883D01*
X740900Y761592D01*
X740817Y761258D01*
X740567Y760967D01*
X740192Y760800D01*
X739775Y760758D01*
X739233Y760842D01*
X738942Y760967D01*
X738650Y761175D01*
X738442Y761467D01*
X738400Y761758D01*
X738483Y762050D01*
X738692Y762258D01*
G01X726017Y757300D02*
Y759800D01*
X727058D01*
X727392Y759675D01*
X727600Y759508D01*
X727683Y759175D01*
X727600Y758842D01*
X727350Y758633D01*
X727058Y758508D01*
X726017D01*
G01X727058D02*
X727683Y757300D01*
G01X729033Y757675D02*
X729283Y757467D01*
X729575Y757342D01*
X729950Y757300D01*
X730325Y757383D01*
X730617Y757550D01*
X730825Y757842D01*
X730867Y758175D01*
X730783Y758508D01*
X730575Y758717D01*
X730283Y758883D01*
X729992Y758925D01*
X729700Y758883D01*
X729325Y758717D01*
X729450Y759800D01*
X730575D01*
G01X732133Y757675D02*
X732383Y757467D01*
X732675Y757342D01*
X733050Y757300D01*
X733425Y757383D01*
X733717Y757550D01*
X733925Y757842D01*
X733967Y758175D01*
X733883Y758508D01*
X733675Y758717D01*
X733383Y758883D01*
X733092Y758925D01*
X732800Y758883D01*
X732425Y758717D01*
X732550Y759800D01*
X733675D01*
G01X735358Y759383D02*
X735608Y759633D01*
X735900Y759758D01*
X736233Y759800D01*
X736650Y759717D01*
X736942Y759508D01*
X737025Y759258D01*
X736983Y759008D01*
X736817Y758800D01*
X735983Y758383D01*
X735608Y758092D01*
X735358Y757675D01*
X735275Y757300D01*
X737025D01*
G01X756300Y757000D02*
Y753000D01*
X763700D01*
G01X723417Y752900D02*
Y755400D01*
X724458D01*
X724792Y755275D01*
X725000Y755108D01*
X725083Y754775D01*
X725000Y754442D01*
X724750Y754233D01*
X724458Y754108D01*
X723417D01*
G01X724458D02*
X725083Y752900D01*
G01X727350D02*
Y755400D01*
X726850Y754900D01*
G01Y752900D02*
X727850D01*
G01X730950D02*
Y755400D01*
X729408Y753608D01*
X731492D01*
G01X733550Y752900D02*
X733842Y752942D01*
X734175Y753067D01*
X734383Y753275D01*
X734467Y753567D01*
X734383Y753858D01*
X734133Y754108D01*
X733758Y754233D01*
X733342D01*
X733092Y754317D01*
X732883Y754525D01*
X732800Y754817D01*
X732925Y755108D01*
X733217Y755317D01*
X733550Y755400D01*
X733883Y755317D01*
X734175Y755108D01*
X734300Y754817D01*
X734217Y754525D01*
X734008Y754317D01*
X733758Y754233D01*
X733342D01*
X732967Y754108D01*
X732717Y753858D01*
X732633Y753567D01*
X732717Y753275D01*
X732925Y753067D01*
X733258Y752942D01*
X733550Y752900D01*
G01X752800Y753000D02*
Y749000D01*
X760200D01*
G01X719300Y751917D02*
X716800D01*
Y752958D01*
X716925Y753292D01*
X717092Y753500D01*
X717425Y753583D01*
X717758Y753500D01*
X717967Y753250D01*
X718092Y752958D01*
Y751917D01*
G01Y752958D02*
X719300Y753583D01*
G01Y755850D02*
X716800D01*
X717300Y755350D01*
G01X719300D02*
Y756350D01*
G01Y759450D02*
X716800D01*
X718592Y757908D01*
Y759992D01*
G01X719008Y761342D02*
X719217Y761633D01*
X719300Y761967D01*
X719217Y762300D01*
X718967Y762592D01*
X718592Y762800D01*
X718217Y762883D01*
X717758D01*
X717383Y762800D01*
X717050Y762592D01*
X716883Y762342D01*
X716800Y762050D01*
X716883Y761717D01*
X717050Y761467D01*
X717300Y761300D01*
X717633Y761217D01*
X717925Y761300D01*
X718217Y761508D01*
X718383Y761758D01*
X718425Y762050D01*
X718342Y762383D01*
X718133Y762633D01*
X717758Y762883D01*
G01X752500Y753200D02*
X748500D01*
Y745800D01*
G01X733000Y734517D02*
X730500D01*
Y735558D01*
X730625Y735892D01*
X730792Y736100D01*
X731125Y736183D01*
X731458Y736100D01*
X731667Y735850D01*
X731792Y735558D01*
Y734517D01*
G01Y735558D02*
X733000Y736183D01*
G01Y738450D02*
X730500D01*
X731000Y737950D01*
G01X733000D02*
Y738950D01*
G01X732625Y740633D02*
X732833Y740883D01*
X732958Y741175D01*
X733000Y741550D01*
X732917Y741925D01*
X732750Y742217D01*
X732458Y742425D01*
X732125Y742467D01*
X731792Y742383D01*
X731583Y742175D01*
X731417Y741883D01*
X731375Y741592D01*
X731417Y741300D01*
X731583Y740925D01*
X730500Y741050D01*
Y742175D01*
G01X732500Y743733D02*
X732792Y743983D01*
X732958Y744317D01*
X733000Y744692D01*
X732958Y745025D01*
X732750Y745358D01*
X732500Y745567D01*
X732250Y745608D01*
X731958Y745525D01*
X731750Y745233D01*
X731667Y744942D01*
Y744567D01*
G01Y744942D02*
X731542Y745192D01*
X731333Y745400D01*
X731083Y745483D01*
X730833Y745400D01*
X730625Y745192D01*
X730500Y744817D01*
X730542Y744442D01*
X730708Y744067D01*
G01X749196Y733182D02*
X753196D01*
Y740582D01*
G01X741000Y734517D02*
X738500D01*
Y735558D01*
X738625Y735892D01*
X738792Y736100D01*
X739125Y736183D01*
X739458Y736100D01*
X739667Y735850D01*
X739792Y735558D01*
Y734517D01*
G01Y735558D02*
X741000Y736183D01*
G01Y738950D02*
X738500D01*
X740292Y737408D01*
Y739492D01*
G01X741000Y741550D02*
X738500D01*
X739000Y741050D01*
G01X741000D02*
Y742050D01*
G01Y744650D02*
X738500D01*
X739000Y744150D01*
G01X741000D02*
Y745150D01*
G01X756996Y732382D02*
X770396D01*
G01X754708Y1104767D02*
X754583Y1104517D01*
X754500Y1104225D01*
Y1103892D01*
X754625Y1103517D01*
X754833Y1103225D01*
X755083Y1103017D01*
X755500Y1102850D01*
X755875Y1102808D01*
X756250Y1102892D01*
X756500Y1103017D01*
X756750Y1103267D01*
X756917Y1103558D01*
X757000Y1103850D01*
Y1104142D01*
X756917Y1104433D01*
X756792Y1104683D01*
X756625Y1104892D01*
G01X757000Y1106950D02*
X754500D01*
X755000Y1106450D01*
G01X757000D02*
Y1107450D01*
G01Y1110550D02*
X754500D01*
X756292Y1109008D01*
Y1111092D01*
G01X757000Y1113150D02*
X754500D01*
X755000Y1112650D01*
G01X757000D02*
Y1113650D01*
G01X739500Y1136350D02*
X739458Y1136017D01*
X739292Y1135725D01*
X739042Y1135475D01*
X738750Y1135308D01*
X738417Y1135225D01*
X738083D01*
X737750Y1135308D01*
X737458Y1135475D01*
X737208Y1135725D01*
X737042Y1136017D01*
X737000Y1136350D01*
X737042Y1136683D01*
X737208Y1136975D01*
X737458Y1137225D01*
X737750Y1137392D01*
X738083Y1137475D01*
X738417D01*
X738750Y1137392D01*
X739042Y1137225D01*
X739292Y1136975D01*
X739458Y1136683D01*
X739500Y1136350D01*
G01X738833Y1136683D02*
X739500Y1137183D01*
G01X738458Y1138658D02*
X738167Y1138950D01*
X738000Y1139200D01*
X737917Y1139533D01*
X738000Y1139825D01*
X738167Y1140033D01*
X738417Y1140200D01*
X738708Y1140242D01*
X738958Y1140200D01*
X739208Y1140033D01*
X739417Y1139783D01*
X739500Y1139492D01*
X739417Y1139158D01*
X739167Y1138867D01*
X738792Y1138700D01*
X738375Y1138658D01*
X737833Y1138742D01*
X737542Y1138867D01*
X737250Y1139075D01*
X737042Y1139367D01*
X737000Y1139658D01*
X737083Y1139950D01*
X737292Y1140158D01*
G01X753799Y1149750D02*
Y1138350D01*
G01D02*
X767199D01*
G01X713372Y1124234D02*
Y1126734D01*
X714413D01*
X714747Y1126609D01*
X714955Y1126442D01*
X715038Y1126109D01*
X714955Y1125776D01*
X714705Y1125567D01*
X714413Y1125442D01*
X713372D01*
G01X714413D02*
X715038Y1124234D01*
G01X717305D02*
Y1126734D01*
X716805Y1126234D01*
G01Y1124234D02*
X717805D01*
G01X719488Y1124734D02*
X719738Y1124442D01*
X720072Y1124276D01*
X720447Y1124234D01*
X720780Y1124276D01*
X721113Y1124484D01*
X721322Y1124734D01*
X721363Y1124984D01*
X721280Y1125276D01*
X720988Y1125484D01*
X720697Y1125567D01*
X720322D01*
G01X720697D02*
X720947Y1125692D01*
X721155Y1125901D01*
X721238Y1126151D01*
X721155Y1126401D01*
X720947Y1126609D01*
X720572Y1126734D01*
X720197Y1126692D01*
X719822Y1126526D01*
G01X722588Y1124609D02*
X722838Y1124401D01*
X723130Y1124276D01*
X723505Y1124234D01*
X723880Y1124317D01*
X724172Y1124484D01*
X724380Y1124776D01*
X724422Y1125109D01*
X724338Y1125442D01*
X724130Y1125651D01*
X723838Y1125817D01*
X723547Y1125859D01*
X723255Y1125817D01*
X722880Y1125651D01*
X723005Y1126734D01*
X724130D01*
G01X756033Y1124392D02*
Y1128392D01*
X748633D01*
G01X735500Y1135517D02*
X733000D01*
Y1136558D01*
X733125Y1136892D01*
X733292Y1137100D01*
X733625Y1137183D01*
X733958Y1137100D01*
X734167Y1136850D01*
X734292Y1136558D01*
Y1135517D01*
G01Y1136558D02*
X735500Y1137183D01*
G01Y1139450D02*
X733000D01*
X733500Y1138950D01*
G01X735500D02*
Y1139950D01*
G01Y1143050D02*
X733000D01*
X734792Y1141508D01*
Y1143592D01*
G01X733000Y1145650D02*
X733083Y1145317D01*
X733292Y1145067D01*
X733542Y1144900D01*
X733875Y1144775D01*
X734250Y1144733D01*
X734625Y1144775D01*
X734958Y1144900D01*
X735208Y1145067D01*
X735417Y1145317D01*
X735500Y1145650D01*
X735417Y1145983D01*
X735208Y1146233D01*
X734958Y1146400D01*
X734625Y1146525D01*
X734250Y1146567D01*
X733875Y1146525D01*
X733542Y1146400D01*
X733292Y1146233D01*
X733083Y1145983D01*
X733000Y1145650D01*
G01X749499Y1138350D02*
X753499D01*
Y1145750D01*
G01X713538Y1128392D02*
Y1130892D01*
X714579D01*
X714913Y1130767D01*
X715121Y1130600D01*
X715204Y1130267D01*
X715121Y1129934D01*
X714871Y1129725D01*
X714579Y1129600D01*
X713538D01*
G01X714579D02*
X715204Y1128392D01*
G01X717471D02*
Y1130892D01*
X716971Y1130392D01*
G01Y1128392D02*
X717971D01*
G01X721071D02*
Y1130892D01*
X719529Y1129100D01*
X721613D01*
G01X723671Y1128392D02*
Y1130892D01*
X723171Y1130392D01*
G01Y1128392D02*
X724171D01*
G01X756033Y1129392D02*
Y1133392D01*
X748633D01*
G01X731038Y1128392D02*
Y1130892D01*
X732079D01*
X732413Y1130767D01*
X732621Y1130600D01*
X732704Y1130267D01*
X732621Y1129934D01*
X732371Y1129725D01*
X732079Y1129600D01*
X731038D01*
G01X732079D02*
X732704Y1128392D01*
G01X735471D02*
Y1130892D01*
X733929Y1129100D01*
X736013D01*
G01X737154Y1128892D02*
X737404Y1128600D01*
X737738Y1128434D01*
X738113Y1128392D01*
X738446Y1128434D01*
X738779Y1128642D01*
X738988Y1128892D01*
X739029Y1129142D01*
X738946Y1129434D01*
X738654Y1129642D01*
X738363Y1129725D01*
X737988D01*
G01X738363D02*
X738613Y1129850D01*
X738821Y1130059D01*
X738904Y1130309D01*
X738821Y1130559D01*
X738613Y1130767D01*
X738238Y1130892D01*
X737863Y1130850D01*
X737488Y1130684D01*
G01X740379Y1130475D02*
X740629Y1130725D01*
X740921Y1130850D01*
X741254Y1130892D01*
X741671Y1130809D01*
X741963Y1130600D01*
X742046Y1130350D01*
X742004Y1130100D01*
X741838Y1129892D01*
X741004Y1129475D01*
X740629Y1129184D01*
X740379Y1128767D01*
X740296Y1128392D01*
X742046D01*
G01X731038Y1124392D02*
Y1126892D01*
X732079D01*
X732413Y1126767D01*
X732621Y1126600D01*
X732704Y1126267D01*
X732621Y1125934D01*
X732371Y1125725D01*
X732079Y1125600D01*
X731038D01*
G01X732079D02*
X732704Y1124392D01*
G01X735471D02*
Y1126892D01*
X733929Y1125100D01*
X736013D01*
G01X737154Y1124892D02*
X737404Y1124600D01*
X737738Y1124434D01*
X738113Y1124392D01*
X738446Y1124434D01*
X738779Y1124642D01*
X738988Y1124892D01*
X739029Y1125142D01*
X738946Y1125434D01*
X738654Y1125642D01*
X738363Y1125725D01*
X737988D01*
G01X738363D02*
X738613Y1125850D01*
X738821Y1126059D01*
X738904Y1126309D01*
X738821Y1126559D01*
X738613Y1126767D01*
X738238Y1126892D01*
X737863Y1126850D01*
X737488Y1126684D01*
G01X740254Y1124892D02*
X740504Y1124600D01*
X740838Y1124434D01*
X741213Y1124392D01*
X741546Y1124434D01*
X741879Y1124642D01*
X742088Y1124892D01*
X742129Y1125142D01*
X742046Y1125434D01*
X741754Y1125642D01*
X741463Y1125725D01*
X741088D01*
G01X741463D02*
X741713Y1125850D01*
X741921Y1126059D01*
X742004Y1126309D01*
X741921Y1126559D01*
X741713Y1126767D01*
X741338Y1126892D01*
X740963Y1126850D01*
X740588Y1126684D01*
G01X743500Y1135517D02*
X741000D01*
Y1136558D01*
X741125Y1136892D01*
X741292Y1137100D01*
X741625Y1137183D01*
X741958Y1137100D01*
X742167Y1136850D01*
X742292Y1136558D01*
Y1135517D01*
G01Y1136558D02*
X743500Y1137183D01*
G01Y1139950D02*
X741000D01*
X742792Y1138408D01*
Y1140492D01*
G01X743500Y1142550D02*
X741000D01*
X741500Y1142050D01*
G01X743500D02*
Y1143050D01*
G01X741000Y1145650D02*
X741083Y1145317D01*
X741292Y1145067D01*
X741542Y1144900D01*
X741875Y1144775D01*
X742250Y1144733D01*
X742625Y1144775D01*
X742958Y1144900D01*
X743208Y1145067D01*
X743417Y1145317D01*
X743500Y1145650D01*
X743417Y1145983D01*
X743208Y1146233D01*
X742958Y1146400D01*
X742625Y1146525D01*
X742250Y1146567D01*
X741875Y1146525D01*
X741542Y1146400D01*
X741292Y1146233D01*
X741083Y1145983D01*
X741000Y1145650D01*
G01X726521Y1124425D02*
X728313D01*
X728688Y1124592D01*
X728938Y1124925D01*
X729021Y1125342D01*
X728938Y1125759D01*
X728688Y1126092D01*
X728313Y1126259D01*
X726521D01*
G01X728729Y1127734D02*
X728938Y1128025D01*
X729021Y1128359D01*
X728938Y1128692D01*
X728688Y1128984D01*
X728313Y1129192D01*
X727938Y1129275D01*
X727479D01*
X727104Y1129192D01*
X726771Y1128984D01*
X726604Y1128734D01*
X726521Y1128442D01*
X726604Y1128109D01*
X726771Y1127859D01*
X727021Y1127692D01*
X727354Y1127609D01*
X727646Y1127692D01*
X727938Y1127900D01*
X728104Y1128150D01*
X728146Y1128442D01*
X728063Y1128775D01*
X727854Y1129025D01*
X727479Y1129275D01*
G01X757133Y1133892D02*
X770533D01*
G01X757133Y1123892D02*
Y1133892D01*
G01X770533Y1123892D02*
X757133D01*
G01X753383Y1171800D02*
Y1174300D01*
X754217D01*
X754550Y1174175D01*
X754800Y1174008D01*
X755008Y1173758D01*
X755175Y1173467D01*
X755217Y1173050D01*
X755175Y1172633D01*
X755008Y1172342D01*
X754800Y1172092D01*
X754550Y1171925D01*
X754217Y1171800D01*
X753383D01*
G01X757400D02*
Y1174300D01*
X756900Y1173800D01*
G01Y1171800D02*
X757900D01*
G01X760417D02*
X760500Y1172342D01*
X760625Y1172800D01*
X760792Y1173217D01*
X761000Y1173675D01*
X761333Y1174300D01*
X759667D01*
G01X765900Y1161300D02*
X749800D01*
G01Y1168300D02*
X765900D01*
G01X749800Y1161300D02*
Y1168300D01*
G01X738708Y1155067D02*
X738583Y1154817D01*
X738500Y1154525D01*
Y1154192D01*
X738625Y1153817D01*
X738833Y1153525D01*
X739083Y1153317D01*
X739500Y1153150D01*
X739875Y1153108D01*
X740250Y1153192D01*
X740500Y1153317D01*
X740750Y1153567D01*
X740917Y1153858D01*
X741000Y1154150D01*
Y1154442D01*
X740917Y1154733D01*
X740792Y1154983D01*
X740625Y1155192D01*
G01X740500Y1156333D02*
X740792Y1156583D01*
X740958Y1156917D01*
X741000Y1157292D01*
X740958Y1157625D01*
X740750Y1157958D01*
X740500Y1158167D01*
X740250Y1158208D01*
X739958Y1158125D01*
X739750Y1157833D01*
X739667Y1157542D01*
Y1157167D01*
G01Y1157542D02*
X739542Y1157792D01*
X739333Y1158000D01*
X739083Y1158083D01*
X738833Y1158000D01*
X738625Y1157792D01*
X738500Y1157417D01*
X738542Y1157042D01*
X738708Y1156667D01*
G01X741000Y1160350D02*
X740958Y1160642D01*
X740833Y1160975D01*
X740625Y1161183D01*
X740333Y1161267D01*
X740042Y1161183D01*
X739792Y1160933D01*
X739667Y1160558D01*
Y1160142D01*
X739583Y1159892D01*
X739375Y1159683D01*
X739083Y1159600D01*
X738792Y1159725D01*
X738583Y1160017D01*
X738500Y1160350D01*
X738583Y1160683D01*
X738792Y1160975D01*
X739083Y1161100D01*
X739375Y1161017D01*
X739583Y1160808D01*
X739667Y1160558D01*
Y1160142D01*
X739792Y1159767D01*
X740042Y1159517D01*
X740333Y1159433D01*
X740625Y1159517D01*
X740833Y1159725D01*
X740958Y1160058D01*
X741000Y1160350D01*
G01Y1163450D02*
X738500D01*
X739000Y1162950D01*
G01X741000D02*
Y1163950D01*
G01X767199Y1149750D02*
X753799D01*
G01X737000Y1153317D02*
X734500D01*
Y1154358D01*
X734625Y1154692D01*
X734792Y1154900D01*
X735125Y1154983D01*
X735458Y1154900D01*
X735667Y1154650D01*
X735792Y1154358D01*
Y1153317D01*
G01Y1154358D02*
X737000Y1154983D01*
G01X736625Y1156333D02*
X736833Y1156583D01*
X736958Y1156875D01*
X737000Y1157250D01*
X736917Y1157625D01*
X736750Y1157917D01*
X736458Y1158125D01*
X736125Y1158167D01*
X735792Y1158083D01*
X735583Y1157875D01*
X735417Y1157583D01*
X735375Y1157292D01*
X735417Y1157000D01*
X735583Y1156625D01*
X734500Y1156750D01*
Y1157875D01*
G01X735958Y1159558D02*
X735667Y1159850D01*
X735500Y1160100D01*
X735417Y1160433D01*
X735500Y1160725D01*
X735667Y1160933D01*
X735917Y1161100D01*
X736208Y1161142D01*
X736458Y1161100D01*
X736708Y1160933D01*
X736917Y1160683D01*
X737000Y1160392D01*
X736917Y1160058D01*
X736667Y1159767D01*
X736292Y1159600D01*
X735875Y1159558D01*
X735333Y1159642D01*
X735042Y1159767D01*
X734750Y1159975D01*
X734542Y1160267D01*
X734500Y1160558D01*
X734583Y1160850D01*
X734792Y1161058D01*
G01X736625Y1162533D02*
X736833Y1162783D01*
X736958Y1163075D01*
X737000Y1163450D01*
X736917Y1163825D01*
X736750Y1164117D01*
X736458Y1164325D01*
X736125Y1164367D01*
X735792Y1164283D01*
X735583Y1164075D01*
X735417Y1163783D01*
X735375Y1163492D01*
X735417Y1163200D01*
X735583Y1162825D01*
X734500Y1162950D01*
Y1164075D01*
G01X721617Y1158600D02*
Y1161100D01*
X722658D01*
X722992Y1160975D01*
X723200Y1160808D01*
X723283Y1160475D01*
X723200Y1160142D01*
X722950Y1159933D01*
X722658Y1159808D01*
X721617D01*
G01X722658D02*
X723283Y1158600D01*
G01X724633Y1158975D02*
X724883Y1158767D01*
X725175Y1158642D01*
X725550Y1158600D01*
X725925Y1158683D01*
X726217Y1158850D01*
X726425Y1159142D01*
X726467Y1159475D01*
X726383Y1159808D01*
X726175Y1160017D01*
X725883Y1160183D01*
X725592Y1160225D01*
X725300Y1160183D01*
X724925Y1160017D01*
X725050Y1161100D01*
X726175D01*
G01X727733Y1158975D02*
X727983Y1158767D01*
X728275Y1158642D01*
X728650Y1158600D01*
X729025Y1158683D01*
X729317Y1158850D01*
X729525Y1159142D01*
X729567Y1159475D01*
X729483Y1159808D01*
X729275Y1160017D01*
X728983Y1160183D01*
X728692Y1160225D01*
X728400Y1160183D01*
X728025Y1160017D01*
X728150Y1161100D01*
X729275D01*
G01X731750D02*
X731417Y1161017D01*
X731167Y1160808D01*
X731000Y1160558D01*
X730875Y1160225D01*
X730833Y1159850D01*
X730875Y1159475D01*
X731000Y1159142D01*
X731167Y1158892D01*
X731417Y1158683D01*
X731750Y1158600D01*
X732083Y1158683D01*
X732333Y1158892D01*
X732500Y1159142D01*
X732625Y1159475D01*
X732667Y1159850D01*
X732625Y1160225D01*
X732500Y1160558D01*
X732333Y1160808D01*
X732083Y1161017D01*
X731750Y1161100D01*
G01X753300Y1160500D02*
Y1156500D01*
X760700D01*
G01X721217Y1152800D02*
Y1155300D01*
X722258D01*
X722592Y1155175D01*
X722800Y1155008D01*
X722883Y1154675D01*
X722800Y1154342D01*
X722550Y1154133D01*
X722258Y1154008D01*
X721217D01*
G01X722258D02*
X722883Y1152800D01*
G01X725150D02*
Y1155300D01*
X724650Y1154800D01*
G01Y1152800D02*
X725650D01*
G01X727333Y1153300D02*
X727583Y1153008D01*
X727917Y1152842D01*
X728292Y1152800D01*
X728625Y1152842D01*
X728958Y1153050D01*
X729167Y1153300D01*
X729208Y1153550D01*
X729125Y1153842D01*
X728833Y1154050D01*
X728542Y1154133D01*
X728167D01*
G01X728542D02*
X728792Y1154258D01*
X729000Y1154467D01*
X729083Y1154717D01*
X729000Y1154967D01*
X728792Y1155175D01*
X728417Y1155300D01*
X728042Y1155258D01*
X727667Y1155092D01*
G01X730558Y1153842D02*
X730850Y1154133D01*
X731100Y1154300D01*
X731433Y1154383D01*
X731725Y1154300D01*
X731933Y1154133D01*
X732100Y1153883D01*
X732142Y1153592D01*
X732100Y1153342D01*
X731933Y1153092D01*
X731683Y1152883D01*
X731392Y1152800D01*
X731058Y1152883D01*
X730767Y1153133D01*
X730600Y1153508D01*
X730558Y1153925D01*
X730642Y1154467D01*
X730767Y1154758D01*
X730975Y1155050D01*
X731267Y1155258D01*
X731558Y1155300D01*
X731850Y1155217D01*
X732058Y1155008D01*
G01X749800Y1156500D02*
Y1152500D01*
X757200D01*
G01X717100Y1152817D02*
X714600D01*
Y1153858D01*
X714725Y1154192D01*
X714892Y1154400D01*
X715225Y1154483D01*
X715558Y1154400D01*
X715767Y1154150D01*
X715892Y1153858D01*
Y1152817D01*
G01Y1153858D02*
X717100Y1154483D01*
G01Y1156750D02*
X714600D01*
X715100Y1156250D01*
G01X717100D02*
Y1157250D01*
G01X716600Y1158933D02*
X716892Y1159183D01*
X717058Y1159517D01*
X717100Y1159892D01*
X717058Y1160225D01*
X716850Y1160558D01*
X716600Y1160767D01*
X716350Y1160808D01*
X716058Y1160725D01*
X715850Y1160433D01*
X715767Y1160142D01*
Y1159767D01*
G01Y1160142D02*
X715642Y1160392D01*
X715433Y1160600D01*
X715183Y1160683D01*
X714933Y1160600D01*
X714725Y1160392D01*
X714600Y1160017D01*
X714642Y1159642D01*
X714808Y1159267D01*
G01X717100Y1162867D02*
X716558Y1162950D01*
X716100Y1163075D01*
X715683Y1163242D01*
X715225Y1163450D01*
X714600Y1163783D01*
Y1162117D01*
G01X749500Y1157200D02*
X745500D01*
Y1149800D01*
G01X756208Y1510767D02*
X756083Y1510517D01*
X756000Y1510225D01*
Y1509892D01*
X756125Y1509517D01*
X756333Y1509225D01*
X756583Y1509017D01*
X757000Y1508850D01*
X757375Y1508808D01*
X757750Y1508892D01*
X758000Y1509017D01*
X758250Y1509267D01*
X758417Y1509558D01*
X758500Y1509850D01*
Y1510142D01*
X758417Y1510433D01*
X758292Y1510683D01*
X758125Y1510892D01*
G01X758500Y1512950D02*
X756000D01*
X756500Y1512450D01*
G01X758500D02*
Y1513450D01*
G01Y1516050D02*
X756000D01*
X756500Y1515550D01*
G01X758500D02*
Y1516550D01*
G01Y1519067D02*
X757958Y1519150D01*
X757500Y1519275D01*
X757083Y1519442D01*
X756625Y1519650D01*
X756000Y1519983D01*
Y1518317D01*
G01X741500Y1544350D02*
X741458Y1544017D01*
X741292Y1543725D01*
X741042Y1543475D01*
X740750Y1543308D01*
X740417Y1543225D01*
X740083D01*
X739750Y1543308D01*
X739458Y1543475D01*
X739208Y1543725D01*
X739042Y1544017D01*
X739000Y1544350D01*
X739042Y1544683D01*
X739208Y1544975D01*
X739458Y1545225D01*
X739750Y1545392D01*
X740083Y1545475D01*
X740417D01*
X740750Y1545392D01*
X741042Y1545225D01*
X741292Y1544975D01*
X741458Y1544683D01*
X741500Y1544350D01*
G01X740833Y1544683D02*
X741500Y1545183D01*
G01Y1547950D02*
X739000D01*
X740792Y1546408D01*
Y1548492D01*
G01X756127Y1552496D02*
Y1541096D01*
G01X769527Y1552496D02*
X756127D01*
G01Y1541096D02*
X769527D01*
G01X718630Y1534191D02*
Y1536691D01*
X719671D01*
X720005Y1536566D01*
X720213Y1536399D01*
X720296Y1536066D01*
X720213Y1535733D01*
X719963Y1535524D01*
X719671Y1535399D01*
X718630D01*
G01X719671D02*
X720296Y1534191D01*
G01X722563D02*
Y1536691D01*
X722063Y1536191D01*
G01Y1534191D02*
X723063D01*
G01X725663D02*
Y1536691D01*
X725163Y1536191D01*
G01Y1534191D02*
X726163D01*
G01X728055Y1534483D02*
X728346Y1534274D01*
X728680Y1534191D01*
X729013Y1534274D01*
X729305Y1534524D01*
X729513Y1534899D01*
X729596Y1535274D01*
Y1535733D01*
X729513Y1536108D01*
X729305Y1536441D01*
X729055Y1536608D01*
X728763Y1536691D01*
X728430Y1536608D01*
X728180Y1536441D01*
X728013Y1536191D01*
X727930Y1535858D01*
X728013Y1535566D01*
X728221Y1535274D01*
X728471Y1535108D01*
X728763Y1535066D01*
X729096Y1535149D01*
X729346Y1535358D01*
X729596Y1535733D01*
G01X759027Y1529296D02*
Y1533296D01*
X751627D01*
G01X753300Y1558500D02*
Y1554500D01*
X760700D01*
G01X753000Y1559200D02*
X749000D01*
Y1551800D01*
G01X737500Y1543517D02*
X735000D01*
Y1544558D01*
X735125Y1544892D01*
X735292Y1545100D01*
X735625Y1545183D01*
X735958Y1545100D01*
X736167Y1544850D01*
X736292Y1544558D01*
Y1543517D01*
G01Y1544558D02*
X737500Y1545183D01*
G01Y1547450D02*
X735000D01*
X735500Y1546950D01*
G01X737500D02*
Y1547950D01*
G01X735417Y1549758D02*
X735167Y1550008D01*
X735042Y1550300D01*
X735000Y1550633D01*
X735083Y1551050D01*
X735292Y1551342D01*
X735542Y1551425D01*
X735792Y1551383D01*
X736000Y1551217D01*
X736417Y1550383D01*
X736708Y1550008D01*
X737125Y1549758D01*
X737500Y1549675D01*
Y1551425D01*
G01X736458Y1552858D02*
X736167Y1553150D01*
X736000Y1553400D01*
X735917Y1553733D01*
X736000Y1554025D01*
X736167Y1554233D01*
X736417Y1554400D01*
X736708Y1554442D01*
X736958Y1554400D01*
X737208Y1554233D01*
X737417Y1553983D01*
X737500Y1553692D01*
X737417Y1553358D01*
X737167Y1553067D01*
X736792Y1552900D01*
X736375Y1552858D01*
X735833Y1552942D01*
X735542Y1553067D01*
X735250Y1553275D01*
X735042Y1553567D01*
X735000Y1553858D01*
X735083Y1554150D01*
X735292Y1554358D01*
G01X751827Y1541596D02*
X755827D01*
Y1548996D01*
G01X718630Y1539191D02*
Y1541691D01*
X719671D01*
X720005Y1541566D01*
X720213Y1541399D01*
X720296Y1541066D01*
X720213Y1540733D01*
X719963Y1540524D01*
X719671Y1540399D01*
X718630D01*
G01X719671D02*
X720296Y1539191D01*
G01X722563D02*
Y1541691D01*
X722063Y1541191D01*
G01Y1539191D02*
X723063D01*
G01X724871Y1541274D02*
X725121Y1541524D01*
X725413Y1541649D01*
X725746Y1541691D01*
X726163Y1541608D01*
X726455Y1541399D01*
X726538Y1541149D01*
X726496Y1540899D01*
X726330Y1540691D01*
X725496Y1540274D01*
X725121Y1539983D01*
X724871Y1539566D01*
X724788Y1539191D01*
X726538D01*
G01X728680D02*
X728763Y1539733D01*
X728888Y1540191D01*
X729055Y1540608D01*
X729263Y1541066D01*
X729596Y1541691D01*
X727930D01*
G01X759027Y1534296D02*
Y1538296D01*
X751627D01*
G01X735484Y1534288D02*
Y1536788D01*
X736525D01*
X736859Y1536663D01*
X737067Y1536496D01*
X737150Y1536163D01*
X737067Y1535830D01*
X736817Y1535621D01*
X736525Y1535496D01*
X735484D01*
G01X736525D02*
X737150Y1534288D01*
G01X739917D02*
Y1536788D01*
X738375Y1534996D01*
X740459D01*
G01X741725Y1536371D02*
X741975Y1536621D01*
X742267Y1536746D01*
X742600Y1536788D01*
X743017Y1536705D01*
X743309Y1536496D01*
X743392Y1536246D01*
X743350Y1535996D01*
X743184Y1535788D01*
X742350Y1535371D01*
X741975Y1535080D01*
X741725Y1534663D01*
X741642Y1534288D01*
X743392D01*
G01X745617D02*
X745909Y1534330D01*
X746242Y1534455D01*
X746450Y1534663D01*
X746534Y1534955D01*
X746450Y1535246D01*
X746200Y1535496D01*
X745825Y1535621D01*
X745409D01*
X745159Y1535705D01*
X744950Y1535913D01*
X744867Y1536205D01*
X744992Y1536496D01*
X745284Y1536705D01*
X745617Y1536788D01*
X745950Y1536705D01*
X746242Y1536496D01*
X746367Y1536205D01*
X746284Y1535913D01*
X746075Y1535705D01*
X745825Y1535621D01*
X745409D01*
X745034Y1535496D01*
X744784Y1535246D01*
X744700Y1534955D01*
X744784Y1534663D01*
X744992Y1534455D01*
X745325Y1534330D01*
X745617Y1534288D01*
G01X735484Y1538288D02*
Y1540788D01*
X736525D01*
X736859Y1540663D01*
X737067Y1540496D01*
X737150Y1540163D01*
X737067Y1539830D01*
X736817Y1539621D01*
X736525Y1539496D01*
X735484D01*
G01X736525D02*
X737150Y1538288D01*
G01X739917D02*
Y1540788D01*
X738375Y1538996D01*
X740459D01*
G01X741725Y1540371D02*
X741975Y1540621D01*
X742267Y1540746D01*
X742600Y1540788D01*
X743017Y1540705D01*
X743309Y1540496D01*
X743392Y1540246D01*
X743350Y1539996D01*
X743184Y1539788D01*
X742350Y1539371D01*
X741975Y1539080D01*
X741725Y1538663D01*
X741642Y1538288D01*
X743392D01*
G01X744909Y1538580D02*
X745200Y1538371D01*
X745534Y1538288D01*
X745867Y1538371D01*
X746159Y1538621D01*
X746367Y1538996D01*
X746450Y1539371D01*
Y1539830D01*
X746367Y1540205D01*
X746159Y1540538D01*
X745909Y1540705D01*
X745617Y1540788D01*
X745284Y1540705D01*
X745034Y1540538D01*
X744867Y1540288D01*
X744784Y1539955D01*
X744867Y1539663D01*
X745075Y1539371D01*
X745325Y1539205D01*
X745617Y1539163D01*
X745950Y1539246D01*
X746200Y1539455D01*
X746450Y1539830D01*
G01X745500Y1543517D02*
X743000D01*
Y1544558D01*
X743125Y1544892D01*
X743292Y1545100D01*
X743625Y1545183D01*
X743958Y1545100D01*
X744167Y1544850D01*
X744292Y1544558D01*
Y1543517D01*
G01Y1544558D02*
X745500Y1545183D01*
G01Y1547950D02*
X743000D01*
X744792Y1546408D01*
Y1548492D01*
G01X743000Y1550550D02*
X743083Y1550217D01*
X743292Y1549967D01*
X743542Y1549800D01*
X743875Y1549675D01*
X744250Y1549633D01*
X744625Y1549675D01*
X744958Y1549800D01*
X745208Y1549967D01*
X745417Y1550217D01*
X745500Y1550550D01*
X745417Y1550883D01*
X745208Y1551133D01*
X744958Y1551300D01*
X744625Y1551425D01*
X744250Y1551467D01*
X743875Y1551425D01*
X743542Y1551300D01*
X743292Y1551133D01*
X743083Y1550883D01*
X743000Y1550550D01*
G01X745208Y1552942D02*
X745417Y1553233D01*
X745500Y1553567D01*
X745417Y1553900D01*
X745167Y1554192D01*
X744792Y1554400D01*
X744417Y1554483D01*
X743958D01*
X743583Y1554400D01*
X743250Y1554192D01*
X743083Y1553942D01*
X743000Y1553650D01*
X743083Y1553317D01*
X743250Y1553067D01*
X743500Y1552900D01*
X743833Y1552817D01*
X744125Y1552900D01*
X744417Y1553108D01*
X744583Y1553358D01*
X744625Y1553650D01*
X744542Y1553983D01*
X744333Y1554233D01*
X743958Y1554483D01*
G01X731285Y1534478D02*
X733077D01*
X733452Y1534645D01*
X733702Y1534978D01*
X733785Y1535395D01*
X733702Y1535812D01*
X733452Y1536145D01*
X733077Y1536312D01*
X731285D01*
G01X732743Y1537703D02*
X732452Y1537995D01*
X732285Y1538245D01*
X732202Y1538578D01*
X732285Y1538870D01*
X732452Y1539078D01*
X732702Y1539245D01*
X732993Y1539287D01*
X733243Y1539245D01*
X733493Y1539078D01*
X733702Y1538828D01*
X733785Y1538537D01*
X733702Y1538203D01*
X733452Y1537912D01*
X733077Y1537745D01*
X732660Y1537703D01*
X732118Y1537787D01*
X731827Y1537912D01*
X731535Y1538120D01*
X731327Y1538412D01*
X731285Y1538703D01*
X731368Y1538995D01*
X731577Y1539203D01*
G01X756483Y1574500D02*
Y1577000D01*
X757317D01*
X757650Y1576875D01*
X757900Y1576708D01*
X758108Y1576458D01*
X758275Y1576167D01*
X758317Y1575750D01*
X758275Y1575333D01*
X758108Y1575042D01*
X757900Y1574792D01*
X757650Y1574625D01*
X757317Y1574500D01*
X756483D01*
G01X760500D02*
Y1577000D01*
X760000Y1576500D01*
G01Y1574500D02*
X761000D01*
G01X762808Y1575542D02*
X763100Y1575833D01*
X763350Y1576000D01*
X763683Y1576083D01*
X763975Y1576000D01*
X764183Y1575833D01*
X764350Y1575583D01*
X764392Y1575292D01*
X764350Y1575042D01*
X764183Y1574792D01*
X763933Y1574583D01*
X763642Y1574500D01*
X763308Y1574583D01*
X763017Y1574833D01*
X762850Y1575208D01*
X762808Y1575625D01*
X762892Y1576167D01*
X763017Y1576458D01*
X763225Y1576750D01*
X763517Y1576958D01*
X763808Y1577000D01*
X764100Y1576917D01*
X764308Y1576708D01*
G01X768500Y1564500D02*
X752400D01*
G01Y1571500D02*
X768500D01*
G01X752400Y1564500D02*
Y1571500D01*
G01X741108Y1560167D02*
X740983Y1559917D01*
X740900Y1559625D01*
Y1559292D01*
X741025Y1558917D01*
X741233Y1558625D01*
X741483Y1558417D01*
X741900Y1558250D01*
X742275Y1558208D01*
X742650Y1558292D01*
X742900Y1558417D01*
X743150Y1558667D01*
X743317Y1558958D01*
X743400Y1559250D01*
Y1559542D01*
X743317Y1559833D01*
X743192Y1560083D01*
X743025Y1560292D01*
G01X742900Y1561433D02*
X743192Y1561683D01*
X743358Y1562017D01*
X743400Y1562392D01*
X743358Y1562725D01*
X743150Y1563058D01*
X742900Y1563267D01*
X742650Y1563308D01*
X742358Y1563225D01*
X742150Y1562933D01*
X742067Y1562642D01*
Y1562267D01*
G01Y1562642D02*
X741942Y1562892D01*
X741733Y1563100D01*
X741483Y1563183D01*
X741233Y1563100D01*
X741025Y1562892D01*
X740900Y1562517D01*
X740942Y1562142D01*
X741108Y1561767D01*
G01X743400Y1565450D02*
X743358Y1565742D01*
X743233Y1566075D01*
X743025Y1566283D01*
X742733Y1566367D01*
X742442Y1566283D01*
X742192Y1566033D01*
X742067Y1565658D01*
Y1565242D01*
X741983Y1564992D01*
X741775Y1564783D01*
X741483Y1564700D01*
X741192Y1564825D01*
X740983Y1565117D01*
X740900Y1565450D01*
X740983Y1565783D01*
X741192Y1566075D01*
X741483Y1566200D01*
X741775Y1566117D01*
X741983Y1565908D01*
X742067Y1565658D01*
Y1565242D01*
X742192Y1564867D01*
X742442Y1564617D01*
X742733Y1564533D01*
X743025Y1564617D01*
X743233Y1564825D01*
X743358Y1565158D01*
X743400Y1565450D01*
G01X740900Y1568550D02*
X740983Y1568217D01*
X741192Y1567967D01*
X741442Y1567800D01*
X741775Y1567675D01*
X742150Y1567633D01*
X742525Y1567675D01*
X742858Y1567800D01*
X743108Y1567967D01*
X743317Y1568217D01*
X743400Y1568550D01*
X743317Y1568883D01*
X743108Y1569133D01*
X742858Y1569300D01*
X742525Y1569425D01*
X742150Y1569467D01*
X741775Y1569425D01*
X741442Y1569300D01*
X741192Y1569133D01*
X740983Y1568883D01*
X740900Y1568550D01*
G01X739300Y1558417D02*
X736800D01*
Y1559458D01*
X736925Y1559792D01*
X737092Y1560000D01*
X737425Y1560083D01*
X737758Y1560000D01*
X737967Y1559750D01*
X738092Y1559458D01*
Y1558417D01*
G01Y1559458D02*
X739300Y1560083D01*
G01X738925Y1561433D02*
X739133Y1561683D01*
X739258Y1561975D01*
X739300Y1562350D01*
X739217Y1562725D01*
X739050Y1563017D01*
X738758Y1563225D01*
X738425Y1563267D01*
X738092Y1563183D01*
X737883Y1562975D01*
X737717Y1562683D01*
X737675Y1562392D01*
X737717Y1562100D01*
X737883Y1561725D01*
X736800Y1561850D01*
Y1562975D01*
G01X738258Y1564658D02*
X737967Y1564950D01*
X737800Y1565200D01*
X737717Y1565533D01*
X737800Y1565825D01*
X737967Y1566033D01*
X738217Y1566200D01*
X738508Y1566242D01*
X738758Y1566200D01*
X739008Y1566033D01*
X739217Y1565783D01*
X739300Y1565492D01*
X739217Y1565158D01*
X738967Y1564867D01*
X738592Y1564700D01*
X738175Y1564658D01*
X737633Y1564742D01*
X737342Y1564867D01*
X737050Y1565075D01*
X736842Y1565367D01*
X736800Y1565658D01*
X736883Y1565950D01*
X737092Y1566158D01*
G01X739300Y1569050D02*
X736800D01*
X738592Y1567508D01*
Y1569592D01*
G01X722817Y1565400D02*
Y1567900D01*
X723858D01*
X724192Y1567775D01*
X724400Y1567608D01*
X724483Y1567275D01*
X724400Y1566942D01*
X724150Y1566733D01*
X723858Y1566608D01*
X722817D01*
G01X723858D02*
X724483Y1565400D01*
G01X727250D02*
Y1567900D01*
X725708Y1566108D01*
X727792D01*
G01X729767Y1565400D02*
X729850Y1565942D01*
X729975Y1566400D01*
X730142Y1566817D01*
X730350Y1567275D01*
X730683Y1567900D01*
X729017D01*
G01X732242Y1565692D02*
X732533Y1565483D01*
X732867Y1565400D01*
X733200Y1565483D01*
X733492Y1565733D01*
X733700Y1566108D01*
X733783Y1566483D01*
Y1566942D01*
X733700Y1567317D01*
X733492Y1567650D01*
X733242Y1567817D01*
X732950Y1567900D01*
X732617Y1567817D01*
X732367Y1567650D01*
X732200Y1567400D01*
X732117Y1567067D01*
X732200Y1566775D01*
X732408Y1566483D01*
X732658Y1566317D01*
X732950Y1566275D01*
X733283Y1566358D01*
X733533Y1566567D01*
X733783Y1566942D01*
G01X756800Y1563000D02*
Y1559000D01*
X764200D01*
G01X722917Y1561000D02*
Y1563500D01*
X723958D01*
X724292Y1563375D01*
X724500Y1563208D01*
X724583Y1562875D01*
X724500Y1562542D01*
X724250Y1562333D01*
X723958Y1562208D01*
X722917D01*
G01X723958D02*
X724583Y1561000D01*
G01X726850D02*
Y1563500D01*
X726350Y1563000D01*
G01Y1561000D02*
X727350D01*
G01X729158Y1563083D02*
X729408Y1563333D01*
X729700Y1563458D01*
X730033Y1563500D01*
X730450Y1563417D01*
X730742Y1563208D01*
X730825Y1562958D01*
X730783Y1562708D01*
X730617Y1562500D01*
X729783Y1562083D01*
X729408Y1561792D01*
X729158Y1561375D01*
X729075Y1561000D01*
X730825D01*
G01X733050Y1563500D02*
X732717Y1563417D01*
X732467Y1563208D01*
X732300Y1562958D01*
X732175Y1562625D01*
X732133Y1562250D01*
X732175Y1561875D01*
X732300Y1561542D01*
X732467Y1561292D01*
X732717Y1561083D01*
X733050Y1561000D01*
X733383Y1561083D01*
X733633Y1561292D01*
X733800Y1561542D01*
X733925Y1561875D01*
X733967Y1562250D01*
X733925Y1562625D01*
X733800Y1562958D01*
X733633Y1563208D01*
X733383Y1563417D01*
X733050Y1563500D01*
G01X718600Y1560817D02*
X716100D01*
Y1561858D01*
X716225Y1562192D01*
X716392Y1562400D01*
X716725Y1562483D01*
X717058Y1562400D01*
X717267Y1562150D01*
X717392Y1561858D01*
Y1560817D01*
G01Y1561858D02*
X718600Y1562483D01*
G01Y1564750D02*
X716100D01*
X716600Y1564250D01*
G01X718600D02*
Y1565250D01*
G01X716517Y1567058D02*
X716267Y1567308D01*
X716142Y1567600D01*
X716100Y1567933D01*
X716183Y1568350D01*
X716392Y1568642D01*
X716642Y1568725D01*
X716892Y1568683D01*
X717100Y1568517D01*
X717517Y1567683D01*
X717808Y1567308D01*
X718225Y1567058D01*
X718600Y1566975D01*
Y1568725D01*
G01X716517Y1570158D02*
X716267Y1570408D01*
X716142Y1570700D01*
X716100Y1571033D01*
X716183Y1571450D01*
X716392Y1571742D01*
X716642Y1571825D01*
X716892Y1571783D01*
X717100Y1571617D01*
X717517Y1570783D01*
X717808Y1570408D01*
X718225Y1570158D01*
X718600Y1570075D01*
Y1571825D01*
G01X710000Y1753000D02*
Y1743000D01*
G01X706167Y1753000D02*
X713833D01*
G01X723933Y1743000D02*
X717267D01*
Y1753000D01*
X723933D01*
G01X721267Y1748167D02*
X717267D01*
G01X726867Y1743000D02*
Y1753000D01*
X731200Y1744667D01*
X735533Y1753000D01*
Y1743000D01*
G01X738467D02*
Y1753000D01*
X742467D01*
X743800Y1752500D01*
X744800Y1751333D01*
X745133Y1750000D01*
X744800Y1748667D01*
X743967Y1747667D01*
X742467Y1747166D01*
X738467D01*
G01X747400Y1739667D02*
X757400D01*
G01X759500Y1744333D02*
X760833Y1743500D01*
X762333Y1743000D01*
X763667D01*
X765000Y1743500D01*
X766000Y1744333D01*
X766500Y1745500D01*
X766167Y1746666D01*
X765333Y1747667D01*
X763833Y1748333D01*
X761833Y1748667D01*
X760667Y1749333D01*
X760167Y1750500D01*
X760500Y1751667D01*
X761333Y1752500D01*
X762500Y1753000D01*
X763667D01*
X764833Y1752667D01*
X765833Y1751833D01*
G01X776933Y1743000D02*
X770267D01*
Y1753000D01*
X776933D01*
G01X774267Y1748167D02*
X770267D01*
G01X780367Y1743000D02*
Y1753000D01*
X788033Y1743000D01*
Y1753000D01*
G01X791300Y1744333D02*
X792633Y1743500D01*
X794133Y1743000D01*
X795467D01*
X796800Y1743500D01*
X797800Y1744333D01*
X798300Y1745500D01*
X797967Y1746666D01*
X797133Y1747667D01*
X795633Y1748333D01*
X793633Y1748667D01*
X792467Y1749333D01*
X791967Y1750500D01*
X792300Y1751667D01*
X793133Y1752500D01*
X794300Y1753000D01*
X795467D01*
X796633Y1752667D01*
X797633Y1751833D01*
G01X805400Y1743000D02*
X804066Y1743167D01*
X802900Y1743833D01*
X801900Y1744833D01*
X801233Y1746000D01*
X800900Y1747333D01*
Y1748667D01*
X801233Y1750000D01*
X801900Y1751167D01*
X802900Y1752167D01*
X804066Y1752833D01*
X805400Y1753000D01*
X806733Y1752833D01*
X807900Y1752167D01*
X808900Y1751167D01*
X809567Y1750000D01*
X809900Y1748667D01*
Y1747333D01*
X809567Y1746000D01*
X808900Y1744833D01*
X807900Y1743833D01*
X806733Y1743167D01*
X805400Y1743000D01*
G01X812667D02*
Y1753000D01*
X816833D01*
X818167Y1752500D01*
X819000Y1751833D01*
X819333Y1750500D01*
X819000Y1749167D01*
X818000Y1748333D01*
X816833Y1747833D01*
X812667D01*
G01X816833D02*
X819333Y1743000D01*
G01X822933Y1745000D02*
X823933Y1743833D01*
X825266Y1743167D01*
X826767Y1743000D01*
X828100Y1743167D01*
X829433Y1744000D01*
X830267Y1745000D01*
X830433Y1746000D01*
X830100Y1747166D01*
X828933Y1748000D01*
X827767Y1748333D01*
X826267D01*
G01X827767D02*
X828767Y1748833D01*
X829600Y1749666D01*
X829933Y1750667D01*
X829600Y1751667D01*
X828767Y1752500D01*
X827267Y1753000D01*
X825767Y1752833D01*
X824267Y1752167D01*
G01X692208Y1771767D02*
X692083Y1771517D01*
X692000Y1771225D01*
Y1770892D01*
X692125Y1770517D01*
X692333Y1770225D01*
X692583Y1770017D01*
X693000Y1769850D01*
X693375Y1769808D01*
X693750Y1769892D01*
X694000Y1770017D01*
X694250Y1770267D01*
X694417Y1770558D01*
X694500Y1770850D01*
Y1771142D01*
X694417Y1771433D01*
X694292Y1771683D01*
X694125Y1771892D01*
G01X694000Y1773033D02*
X694292Y1773283D01*
X694458Y1773617D01*
X694500Y1773992D01*
X694458Y1774325D01*
X694250Y1774658D01*
X694000Y1774867D01*
X693750Y1774908D01*
X693458Y1774825D01*
X693250Y1774533D01*
X693167Y1774242D01*
Y1773867D01*
G01Y1774242D02*
X693042Y1774492D01*
X692833Y1774700D01*
X692583Y1774783D01*
X692333Y1774700D01*
X692125Y1774492D01*
X692000Y1774117D01*
X692042Y1773742D01*
X692208Y1773367D01*
G01X693458Y1776258D02*
X693167Y1776550D01*
X693000Y1776800D01*
X692917Y1777133D01*
X693000Y1777425D01*
X693167Y1777633D01*
X693417Y1777800D01*
X693708Y1777842D01*
X693958Y1777800D01*
X694208Y1777633D01*
X694417Y1777383D01*
X694500Y1777092D01*
X694417Y1776758D01*
X694167Y1776467D01*
X693792Y1776300D01*
X693375Y1776258D01*
X692833Y1776342D01*
X692542Y1776467D01*
X692250Y1776675D01*
X692042Y1776967D01*
X692000Y1777258D01*
X692083Y1777550D01*
X692292Y1777758D01*
G01X694500Y1780150D02*
X692000D01*
X692500Y1779650D01*
G01X694500D02*
Y1780650D01*
G01X692208Y1784767D02*
X692083Y1784517D01*
X692000Y1784225D01*
Y1783892D01*
X692125Y1783517D01*
X692333Y1783225D01*
X692583Y1783017D01*
X693000Y1782850D01*
X693375Y1782808D01*
X693750Y1782892D01*
X694000Y1783017D01*
X694250Y1783267D01*
X694417Y1783558D01*
X694500Y1783850D01*
Y1784142D01*
X694417Y1784433D01*
X694292Y1784683D01*
X694125Y1784892D01*
G01X694000Y1786033D02*
X694292Y1786283D01*
X694458Y1786617D01*
X694500Y1786992D01*
X694458Y1787325D01*
X694250Y1787658D01*
X694000Y1787867D01*
X693750Y1787908D01*
X693458Y1787825D01*
X693250Y1787533D01*
X693167Y1787242D01*
Y1786867D01*
G01Y1787242D02*
X693042Y1787492D01*
X692833Y1787700D01*
X692583Y1787783D01*
X692333Y1787700D01*
X692125Y1787492D01*
X692000Y1787117D01*
X692042Y1786742D01*
X692208Y1786367D01*
G01X693458Y1789258D02*
X693167Y1789550D01*
X693000Y1789800D01*
X692917Y1790133D01*
X693000Y1790425D01*
X693167Y1790633D01*
X693417Y1790800D01*
X693708Y1790842D01*
X693958Y1790800D01*
X694208Y1790633D01*
X694417Y1790383D01*
X694500Y1790092D01*
X694417Y1789758D01*
X694167Y1789467D01*
X693792Y1789300D01*
X693375Y1789258D01*
X692833Y1789342D01*
X692542Y1789467D01*
X692250Y1789675D01*
X692042Y1789967D01*
X692000Y1790258D01*
X692083Y1790550D01*
X692292Y1790758D01*
G01X692417Y1792358D02*
X692167Y1792608D01*
X692042Y1792900D01*
X692000Y1793233D01*
X692083Y1793650D01*
X692292Y1793942D01*
X692542Y1794025D01*
X692792Y1793983D01*
X693000Y1793817D01*
X693417Y1792983D01*
X693708Y1792608D01*
X694125Y1792358D01*
X694500Y1792275D01*
Y1794025D01*
G01X699816Y1793426D02*
X699566Y1793551D01*
X699274Y1793634D01*
X698941D01*
X698566Y1793509D01*
X698274Y1793301D01*
X698066Y1793051D01*
X697899Y1792634D01*
X697857Y1792259D01*
X697941Y1791884D01*
X698066Y1791634D01*
X698316Y1791384D01*
X698607Y1791217D01*
X698899Y1791134D01*
X699191D01*
X699482Y1791217D01*
X699732Y1791342D01*
X699941Y1791509D01*
G01X701082Y1791634D02*
X701332Y1791342D01*
X701666Y1791176D01*
X702041Y1791134D01*
X702374Y1791176D01*
X702707Y1791384D01*
X702916Y1791634D01*
X702957Y1791884D01*
X702874Y1792176D01*
X702582Y1792384D01*
X702291Y1792467D01*
X701916D01*
G01X702291D02*
X702541Y1792592D01*
X702749Y1792801D01*
X702832Y1793051D01*
X702749Y1793301D01*
X702541Y1793509D01*
X702166Y1793634D01*
X701791Y1793592D01*
X701416Y1793426D01*
G01X704307Y1792176D02*
X704599Y1792467D01*
X704849Y1792634D01*
X705182Y1792717D01*
X705474Y1792634D01*
X705682Y1792467D01*
X705849Y1792217D01*
X705891Y1791926D01*
X705849Y1791676D01*
X705682Y1791426D01*
X705432Y1791217D01*
X705141Y1791134D01*
X704807Y1791217D01*
X704516Y1791467D01*
X704349Y1791842D01*
X704307Y1792259D01*
X704391Y1792801D01*
X704516Y1793092D01*
X704724Y1793384D01*
X705016Y1793592D01*
X705307Y1793634D01*
X705599Y1793551D01*
X705807Y1793342D01*
G01X707282Y1791634D02*
X707532Y1791342D01*
X707866Y1791176D01*
X708241Y1791134D01*
X708574Y1791176D01*
X708907Y1791384D01*
X709116Y1791634D01*
X709157Y1791884D01*
X709074Y1792176D01*
X708782Y1792384D01*
X708491Y1792467D01*
X708116D01*
G01X708491D02*
X708741Y1792592D01*
X708949Y1792801D01*
X709032Y1793051D01*
X708949Y1793301D01*
X708741Y1793509D01*
X708366Y1793634D01*
X707991Y1793592D01*
X707616Y1793426D01*
G01X727566Y1787634D02*
Y1790134D01*
X728607D01*
X728941Y1790009D01*
X729149Y1789842D01*
X729232Y1789509D01*
X729149Y1789176D01*
X728899Y1788967D01*
X728607Y1788842D01*
X727566D01*
G01X728607D02*
X729232Y1787634D01*
G01X730582Y1788134D02*
X730832Y1787842D01*
X731166Y1787676D01*
X731541Y1787634D01*
X731874Y1787676D01*
X732207Y1787884D01*
X732416Y1788134D01*
X732457Y1788384D01*
X732374Y1788676D01*
X732082Y1788884D01*
X731791Y1788967D01*
X731416D01*
G01X731791D02*
X732041Y1789092D01*
X732249Y1789301D01*
X732332Y1789551D01*
X732249Y1789801D01*
X732041Y1790009D01*
X731666Y1790134D01*
X731291Y1790092D01*
X730916Y1789926D01*
G01X735099Y1787634D02*
Y1790134D01*
X733557Y1788342D01*
X735641D01*
G01X736782Y1788009D02*
X737032Y1787801D01*
X737324Y1787676D01*
X737699Y1787634D01*
X738074Y1787717D01*
X738366Y1787884D01*
X738574Y1788176D01*
X738616Y1788509D01*
X738532Y1788842D01*
X738324Y1789051D01*
X738032Y1789217D01*
X737741Y1789259D01*
X737449Y1789217D01*
X737074Y1789051D01*
X737199Y1790134D01*
X738324D01*
G01X727566Y1783634D02*
Y1786134D01*
X728607D01*
X728941Y1786009D01*
X729149Y1785842D01*
X729232Y1785509D01*
X729149Y1785176D01*
X728899Y1784967D01*
X728607Y1784842D01*
X727566D01*
G01X728607D02*
X729232Y1783634D01*
G01X730582Y1784134D02*
X730832Y1783842D01*
X731166Y1783676D01*
X731541Y1783634D01*
X731874Y1783676D01*
X732207Y1783884D01*
X732416Y1784134D01*
X732457Y1784384D01*
X732374Y1784676D01*
X732082Y1784884D01*
X731791Y1784967D01*
X731416D01*
G01X731791D02*
X732041Y1785092D01*
X732249Y1785301D01*
X732332Y1785551D01*
X732249Y1785801D01*
X732041Y1786009D01*
X731666Y1786134D01*
X731291Y1786092D01*
X730916Y1785926D01*
G01X735099Y1783634D02*
Y1786134D01*
X733557Y1784342D01*
X735641D01*
G01X736907Y1784676D02*
X737199Y1784967D01*
X737449Y1785134D01*
X737782Y1785217D01*
X738074Y1785134D01*
X738282Y1784967D01*
X738449Y1784717D01*
X738491Y1784426D01*
X738449Y1784176D01*
X738282Y1783926D01*
X738032Y1783717D01*
X737741Y1783634D01*
X737407Y1783717D01*
X737116Y1783967D01*
X736949Y1784342D01*
X736907Y1784759D01*
X736991Y1785301D01*
X737116Y1785592D01*
X737324Y1785884D01*
X737616Y1786092D01*
X737907Y1786134D01*
X738199Y1786051D01*
X738407Y1785842D01*
G01X734349Y1808634D02*
Y1804634D01*
X741749D01*
G01X727566Y1779634D02*
Y1782134D01*
X728607D01*
X728941Y1782009D01*
X729149Y1781842D01*
X729232Y1781509D01*
X729149Y1781176D01*
X728899Y1780967D01*
X728607Y1780842D01*
X727566D01*
G01X728607D02*
X729232Y1779634D01*
G01X730582Y1780134D02*
X730832Y1779842D01*
X731166Y1779676D01*
X731541Y1779634D01*
X731874Y1779676D01*
X732207Y1779884D01*
X732416Y1780134D01*
X732457Y1780384D01*
X732374Y1780676D01*
X732082Y1780884D01*
X731791Y1780967D01*
X731416D01*
G01X731791D02*
X732041Y1781092D01*
X732249Y1781301D01*
X732332Y1781551D01*
X732249Y1781801D01*
X732041Y1782009D01*
X731666Y1782134D01*
X731291Y1782092D01*
X730916Y1781926D01*
G01X735099Y1779634D02*
Y1782134D01*
X733557Y1780342D01*
X735641D01*
G01X737616Y1779634D02*
X737699Y1780176D01*
X737824Y1780634D01*
X737991Y1781051D01*
X738199Y1781509D01*
X738532Y1782134D01*
X736866D01*
G01X734349Y1800634D02*
Y1796634D01*
X741749D01*
G01X749549Y1797651D02*
X747049D01*
Y1798692D01*
X747174Y1799026D01*
X747341Y1799234D01*
X747674Y1799317D01*
X748007Y1799234D01*
X748216Y1798984D01*
X748341Y1798692D01*
Y1797651D01*
G01Y1798692D02*
X749549Y1799317D01*
G01X749049Y1800667D02*
X749341Y1800917D01*
X749507Y1801251D01*
X749549Y1801626D01*
X749507Y1801959D01*
X749299Y1802292D01*
X749049Y1802501D01*
X748799Y1802542D01*
X748507Y1802459D01*
X748299Y1802167D01*
X748216Y1801876D01*
Y1801501D01*
G01Y1801876D02*
X748091Y1802126D01*
X747882Y1802334D01*
X747632Y1802417D01*
X747382Y1802334D01*
X747174Y1802126D01*
X747049Y1801751D01*
X747091Y1801376D01*
X747257Y1801001D01*
G01X749549Y1805184D02*
X747049D01*
X748841Y1803642D01*
Y1805726D01*
G01X749257Y1807076D02*
X749466Y1807367D01*
X749549Y1807701D01*
X749466Y1808034D01*
X749216Y1808326D01*
X748841Y1808534D01*
X748466Y1808617D01*
X748007D01*
X747632Y1808534D01*
X747299Y1808326D01*
X747132Y1808076D01*
X747049Y1807784D01*
X747132Y1807451D01*
X747299Y1807201D01*
X747549Y1807034D01*
X747882Y1806951D01*
X748174Y1807034D01*
X748466Y1807242D01*
X748632Y1807492D01*
X748674Y1807784D01*
X748591Y1808117D01*
X748382Y1808367D01*
X748007Y1808617D01*
G01X746049Y1808334D02*
X742049D01*
Y1800934D01*
G01X749549Y1783651D02*
X747049D01*
Y1784692D01*
X747174Y1785026D01*
X747341Y1785234D01*
X747674Y1785317D01*
X748007Y1785234D01*
X748216Y1784984D01*
X748341Y1784692D01*
Y1783651D01*
G01Y1784692D02*
X749549Y1785317D01*
G01X749049Y1786667D02*
X749341Y1786917D01*
X749507Y1787251D01*
X749549Y1787626D01*
X749507Y1787959D01*
X749299Y1788292D01*
X749049Y1788501D01*
X748799Y1788542D01*
X748507Y1788459D01*
X748299Y1788167D01*
X748216Y1787876D01*
Y1787501D01*
G01Y1787876D02*
X748091Y1788126D01*
X747882Y1788334D01*
X747632Y1788417D01*
X747382Y1788334D01*
X747174Y1788126D01*
X747049Y1787751D01*
X747091Y1787376D01*
X747257Y1787001D01*
G01X749174Y1789767D02*
X749382Y1790017D01*
X749507Y1790309D01*
X749549Y1790684D01*
X749466Y1791059D01*
X749299Y1791351D01*
X749007Y1791559D01*
X748674Y1791601D01*
X748341Y1791517D01*
X748132Y1791309D01*
X747966Y1791017D01*
X747924Y1790726D01*
X747966Y1790434D01*
X748132Y1790059D01*
X747049Y1790184D01*
Y1791309D01*
G01Y1793784D02*
X747132Y1793451D01*
X747341Y1793201D01*
X747591Y1793034D01*
X747924Y1792909D01*
X748299Y1792867D01*
X748674Y1792909D01*
X749007Y1793034D01*
X749257Y1793201D01*
X749466Y1793451D01*
X749549Y1793784D01*
X749466Y1794117D01*
X749257Y1794367D01*
X749007Y1794534D01*
X748674Y1794659D01*
X748299Y1794701D01*
X747924Y1794659D01*
X747591Y1794534D01*
X747341Y1794367D01*
X747132Y1794117D01*
X747049Y1793784D01*
G01X746049Y1800834D02*
X742049D01*
Y1793434D01*
G01X698066Y1783134D02*
Y1785634D01*
X699107D01*
X699441Y1785509D01*
X699649Y1785342D01*
X699732Y1785009D01*
X699649Y1784676D01*
X699399Y1784467D01*
X699107Y1784342D01*
X698066D01*
G01X699107D02*
X699732Y1783134D01*
G01X701082Y1783634D02*
X701332Y1783342D01*
X701666Y1783176D01*
X702041Y1783134D01*
X702374Y1783176D01*
X702707Y1783384D01*
X702916Y1783634D01*
X702957Y1783884D01*
X702874Y1784176D01*
X702582Y1784384D01*
X702291Y1784467D01*
X701916D01*
G01X702291D02*
X702541Y1784592D01*
X702749Y1784801D01*
X702832Y1785051D01*
X702749Y1785301D01*
X702541Y1785509D01*
X702166Y1785634D01*
X701791Y1785592D01*
X701416Y1785426D01*
G01X704307Y1784176D02*
X704599Y1784467D01*
X704849Y1784634D01*
X705182Y1784717D01*
X705474Y1784634D01*
X705682Y1784467D01*
X705849Y1784217D01*
X705891Y1783926D01*
X705849Y1783676D01*
X705682Y1783426D01*
X705432Y1783217D01*
X705141Y1783134D01*
X704807Y1783217D01*
X704516Y1783467D01*
X704349Y1783842D01*
X704307Y1784259D01*
X704391Y1784801D01*
X704516Y1785092D01*
X704724Y1785384D01*
X705016Y1785592D01*
X705307Y1785634D01*
X705599Y1785551D01*
X705807Y1785342D01*
G01X708199Y1783134D02*
Y1785634D01*
X707699Y1785134D01*
G01Y1783134D02*
X708699D01*
G01X702749Y1799634D02*
Y1803634D01*
X695349D01*
G01X698066Y1787134D02*
Y1789634D01*
X699107D01*
X699441Y1789509D01*
X699649Y1789342D01*
X699732Y1789009D01*
X699649Y1788676D01*
X699399Y1788467D01*
X699107Y1788342D01*
X698066D01*
G01X699107D02*
X699732Y1787134D01*
G01X701082Y1787634D02*
X701332Y1787342D01*
X701666Y1787176D01*
X702041Y1787134D01*
X702374Y1787176D01*
X702707Y1787384D01*
X702916Y1787634D01*
X702957Y1787884D01*
X702874Y1788176D01*
X702582Y1788384D01*
X702291Y1788467D01*
X701916D01*
G01X702291D02*
X702541Y1788592D01*
X702749Y1788801D01*
X702832Y1789051D01*
X702749Y1789301D01*
X702541Y1789509D01*
X702166Y1789634D01*
X701791Y1789592D01*
X701416Y1789426D01*
G01X705099Y1787134D02*
X705391Y1787176D01*
X705724Y1787301D01*
X705932Y1787509D01*
X706016Y1787801D01*
X705932Y1788092D01*
X705682Y1788342D01*
X705307Y1788467D01*
X704891D01*
X704641Y1788551D01*
X704432Y1788759D01*
X704349Y1789051D01*
X704474Y1789342D01*
X704766Y1789551D01*
X705099Y1789634D01*
X705432Y1789551D01*
X705724Y1789342D01*
X705849Y1789051D01*
X705766Y1788759D01*
X705557Y1788551D01*
X705307Y1788467D01*
X704891D01*
X704516Y1788342D01*
X704266Y1788092D01*
X704182Y1787801D01*
X704266Y1787509D01*
X704474Y1787301D01*
X704807Y1787176D01*
X705099Y1787134D01*
G01X707407Y1788176D02*
X707699Y1788467D01*
X707949Y1788634D01*
X708282Y1788717D01*
X708574Y1788634D01*
X708782Y1788467D01*
X708949Y1788217D01*
X708991Y1787926D01*
X708949Y1787676D01*
X708782Y1787426D01*
X708532Y1787217D01*
X708241Y1787134D01*
X707907Y1787217D01*
X707616Y1787467D01*
X707449Y1787842D01*
X707407Y1788259D01*
X707491Y1788801D01*
X707616Y1789092D01*
X707824Y1789384D01*
X708116Y1789592D01*
X708407Y1789634D01*
X708699Y1789551D01*
X708907Y1789342D01*
G01X723433Y1793567D02*
X720933D01*
Y1794608D01*
X721058Y1794942D01*
X721225Y1795150D01*
X721558Y1795233D01*
X721891Y1795150D01*
X722100Y1794900D01*
X722225Y1794608D01*
Y1793567D01*
G01Y1794608D02*
X723433Y1795233D01*
G01Y1798000D02*
X720933D01*
X722725Y1796458D01*
Y1798542D01*
G01X723433Y1800600D02*
X723391Y1800892D01*
X723266Y1801225D01*
X723058Y1801433D01*
X722766Y1801517D01*
X722475Y1801433D01*
X722225Y1801183D01*
X722100Y1800808D01*
Y1800392D01*
X722016Y1800142D01*
X721808Y1799933D01*
X721516Y1799850D01*
X721225Y1799975D01*
X721016Y1800267D01*
X720933Y1800600D01*
X721016Y1800933D01*
X721225Y1801225D01*
X721516Y1801350D01*
X721808Y1801267D01*
X722016Y1801058D01*
X722100Y1800808D01*
Y1800392D01*
X722225Y1800017D01*
X722475Y1799767D01*
X722766Y1799683D01*
X723058Y1799767D01*
X723266Y1799975D01*
X723391Y1800308D01*
X723433Y1800600D01*
G01Y1804200D02*
X720933D01*
X722725Y1802658D01*
Y1804742D01*
G01X708549Y1803334D02*
X704549D01*
Y1795934D01*
G01X728249Y1793651D02*
X725749D01*
Y1794692D01*
X725874Y1795026D01*
X726041Y1795234D01*
X726374Y1795317D01*
X726707Y1795234D01*
X726916Y1794984D01*
X727041Y1794692D01*
Y1793651D01*
G01Y1794692D02*
X728249Y1795317D01*
G01Y1798084D02*
X725749D01*
X727541Y1796542D01*
Y1798626D01*
G01X728249Y1800684D02*
X728207Y1800976D01*
X728082Y1801309D01*
X727874Y1801517D01*
X727582Y1801601D01*
X727291Y1801517D01*
X727041Y1801267D01*
X726916Y1800892D01*
Y1800476D01*
X726832Y1800226D01*
X726624Y1800017D01*
X726332Y1799934D01*
X726041Y1800059D01*
X725832Y1800351D01*
X725749Y1800684D01*
X725832Y1801017D01*
X726041Y1801309D01*
X726332Y1801434D01*
X726624Y1801351D01*
X726832Y1801142D01*
X726916Y1800892D01*
Y1800476D01*
X727041Y1800101D01*
X727291Y1799851D01*
X727582Y1799767D01*
X727874Y1799851D01*
X728082Y1800059D01*
X728207Y1800392D01*
X728249Y1800684D01*
G01X727874Y1802867D02*
X728082Y1803117D01*
X728207Y1803409D01*
X728249Y1803784D01*
X728166Y1804159D01*
X727999Y1804451D01*
X727707Y1804659D01*
X727374Y1804701D01*
X727041Y1804617D01*
X726832Y1804409D01*
X726666Y1804117D01*
X726624Y1803826D01*
X726666Y1803534D01*
X726832Y1803159D01*
X725749Y1803284D01*
Y1804409D01*
G01X708549Y1795934D02*
X712549D01*
Y1803334D01*
G01X687707Y1827817D02*
X687582Y1827567D01*
X687499Y1827275D01*
Y1826942D01*
X687624Y1826567D01*
X687832Y1826275D01*
X688082Y1826067D01*
X688499Y1825900D01*
X688874Y1825858D01*
X689249Y1825942D01*
X689499Y1826067D01*
X689749Y1826317D01*
X689916Y1826608D01*
X689999Y1826900D01*
Y1827192D01*
X689916Y1827483D01*
X689791Y1827733D01*
X689624Y1827942D01*
G01X689499Y1829083D02*
X689791Y1829333D01*
X689957Y1829667D01*
X689999Y1830042D01*
X689957Y1830375D01*
X689749Y1830708D01*
X689499Y1830917D01*
X689249Y1830958D01*
X688957Y1830875D01*
X688749Y1830583D01*
X688666Y1830292D01*
Y1829917D01*
G01Y1830292D02*
X688541Y1830542D01*
X688332Y1830750D01*
X688082Y1830833D01*
X687832Y1830750D01*
X687624Y1830542D01*
X687499Y1830167D01*
X687541Y1829792D01*
X687707Y1829417D01*
G01X689624Y1832183D02*
X689832Y1832433D01*
X689957Y1832725D01*
X689999Y1833100D01*
X689916Y1833475D01*
X689749Y1833767D01*
X689457Y1833975D01*
X689124Y1834017D01*
X688791Y1833933D01*
X688582Y1833725D01*
X688416Y1833433D01*
X688374Y1833142D01*
X688416Y1832850D01*
X688582Y1832475D01*
X687499Y1832600D01*
Y1833725D01*
G01X687916Y1835408D02*
X687666Y1835658D01*
X687541Y1835950D01*
X687499Y1836283D01*
X687582Y1836700D01*
X687791Y1836992D01*
X688041Y1837075D01*
X688291Y1837033D01*
X688499Y1836867D01*
X688916Y1836033D01*
X689207Y1835658D01*
X689624Y1835408D01*
X689999Y1835325D01*
Y1837075D01*
G01X734349Y1816134D02*
Y1812134D01*
X741749D01*
G01X747549Y1818151D02*
X745049D01*
Y1819192D01*
X745174Y1819526D01*
X745341Y1819734D01*
X745674Y1819817D01*
X746007Y1819734D01*
X746216Y1819484D01*
X746341Y1819192D01*
Y1818151D01*
G01Y1819192D02*
X747549Y1819817D01*
G01X747049Y1821167D02*
X747341Y1821417D01*
X747507Y1821751D01*
X747549Y1822126D01*
X747507Y1822459D01*
X747299Y1822792D01*
X747049Y1823001D01*
X746799Y1823042D01*
X746507Y1822959D01*
X746299Y1822667D01*
X746216Y1822376D01*
Y1822001D01*
G01Y1822376D02*
X746091Y1822626D01*
X745882Y1822834D01*
X745632Y1822917D01*
X745382Y1822834D01*
X745174Y1822626D01*
X745049Y1822251D01*
X745091Y1821876D01*
X745257Y1821501D01*
G01X747549Y1825684D02*
X745049D01*
X746841Y1824142D01*
Y1826226D01*
G01X747549Y1828284D02*
X747507Y1828576D01*
X747382Y1828909D01*
X747174Y1829117D01*
X746882Y1829201D01*
X746591Y1829117D01*
X746341Y1828867D01*
X746216Y1828492D01*
Y1828076D01*
X746132Y1827826D01*
X745924Y1827617D01*
X745632Y1827534D01*
X745341Y1827659D01*
X745132Y1827951D01*
X745049Y1828284D01*
X745132Y1828617D01*
X745341Y1828909D01*
X745632Y1829034D01*
X745924Y1828951D01*
X746132Y1828742D01*
X746216Y1828492D01*
Y1828076D01*
X746341Y1827701D01*
X746591Y1827451D01*
X746882Y1827367D01*
X747174Y1827451D01*
X747382Y1827659D01*
X747507Y1827992D01*
X747549Y1828284D01*
G01X746049Y1815834D02*
X742049D01*
Y1808434D01*
G01X701066Y1820634D02*
Y1823134D01*
X702107D01*
X702441Y1823009D01*
X702649Y1822842D01*
X702732Y1822509D01*
X702649Y1822176D01*
X702399Y1821967D01*
X702107Y1821842D01*
X701066D01*
G01X702107D02*
X702732Y1820634D01*
G01X704082Y1821134D02*
X704332Y1820842D01*
X704666Y1820676D01*
X705041Y1820634D01*
X705374Y1820676D01*
X705707Y1820884D01*
X705916Y1821134D01*
X705957Y1821384D01*
X705874Y1821676D01*
X705582Y1821884D01*
X705291Y1821967D01*
X704916D01*
G01X705291D02*
X705541Y1822092D01*
X705749Y1822301D01*
X705832Y1822551D01*
X705749Y1822801D01*
X705541Y1823009D01*
X705166Y1823134D01*
X704791Y1823092D01*
X704416Y1822926D01*
G01X708016Y1820634D02*
X708099Y1821176D01*
X708224Y1821634D01*
X708391Y1822051D01*
X708599Y1822509D01*
X708932Y1823134D01*
X707266D01*
G01X710491Y1820926D02*
X710782Y1820717D01*
X711116Y1820634D01*
X711449Y1820717D01*
X711741Y1820967D01*
X711949Y1821342D01*
X712032Y1821717D01*
Y1822176D01*
X711949Y1822551D01*
X711741Y1822884D01*
X711491Y1823051D01*
X711199Y1823134D01*
X710866Y1823051D01*
X710616Y1822884D01*
X710449Y1822634D01*
X710366Y1822301D01*
X710449Y1822009D01*
X710657Y1821717D01*
X710907Y1821551D01*
X711199Y1821509D01*
X711532Y1821592D01*
X711782Y1821801D01*
X712032Y1822176D01*
G01X691849Y1823634D02*
Y1819634D01*
X699249D01*
G01X701066Y1824634D02*
Y1827134D01*
X702107D01*
X702441Y1827009D01*
X702649Y1826842D01*
X702732Y1826509D01*
X702649Y1826176D01*
X702399Y1825967D01*
X702107Y1825842D01*
X701066D01*
G01X702107D02*
X702732Y1824634D01*
G01X704082Y1825134D02*
X704332Y1824842D01*
X704666Y1824676D01*
X705041Y1824634D01*
X705374Y1824676D01*
X705707Y1824884D01*
X705916Y1825134D01*
X705957Y1825384D01*
X705874Y1825676D01*
X705582Y1825884D01*
X705291Y1825967D01*
X704916D01*
G01X705291D02*
X705541Y1826092D01*
X705749Y1826301D01*
X705832Y1826551D01*
X705749Y1826801D01*
X705541Y1827009D01*
X705166Y1827134D01*
X704791Y1827092D01*
X704416Y1826926D01*
G01X708099Y1824634D02*
X708391Y1824676D01*
X708724Y1824801D01*
X708932Y1825009D01*
X709016Y1825301D01*
X708932Y1825592D01*
X708682Y1825842D01*
X708307Y1825967D01*
X707891D01*
X707641Y1826051D01*
X707432Y1826259D01*
X707349Y1826551D01*
X707474Y1826842D01*
X707766Y1827051D01*
X708099Y1827134D01*
X708432Y1827051D01*
X708724Y1826842D01*
X708849Y1826551D01*
X708766Y1826259D01*
X708557Y1826051D01*
X708307Y1825967D01*
X707891D01*
X707516Y1825842D01*
X707266Y1825592D01*
X707182Y1825301D01*
X707266Y1825009D01*
X707474Y1824801D01*
X707807Y1824676D01*
X708099Y1824634D01*
G01X710407Y1826717D02*
X710657Y1826967D01*
X710949Y1827092D01*
X711282Y1827134D01*
X711699Y1827051D01*
X711991Y1826842D01*
X712074Y1826592D01*
X712032Y1826342D01*
X711866Y1826134D01*
X711032Y1825717D01*
X710657Y1825426D01*
X710407Y1825009D01*
X710324Y1824634D01*
X712074D01*
G01X691849Y1827634D02*
Y1823634D01*
X699249D01*
G01X702749Y1806634D02*
Y1810634D01*
X695349D01*
G01X723049Y1812851D02*
X720549D01*
Y1813892D01*
X720674Y1814226D01*
X720841Y1814434D01*
X721174Y1814517D01*
X721507Y1814434D01*
X721716Y1814184D01*
X721841Y1813892D01*
Y1812851D01*
G01Y1813892D02*
X723049Y1814517D01*
G01X722549Y1815867D02*
X722841Y1816117D01*
X723007Y1816451D01*
X723049Y1816826D01*
X723007Y1817159D01*
X722799Y1817492D01*
X722549Y1817701D01*
X722299Y1817742D01*
X722007Y1817659D01*
X721799Y1817367D01*
X721716Y1817076D01*
Y1816701D01*
G01Y1817076D02*
X721591Y1817326D01*
X721382Y1817534D01*
X721132Y1817617D01*
X720882Y1817534D01*
X720674Y1817326D01*
X720549Y1816951D01*
X720591Y1816576D01*
X720757Y1816201D01*
G01X723049Y1819884D02*
X723007Y1820176D01*
X722882Y1820509D01*
X722674Y1820717D01*
X722382Y1820801D01*
X722091Y1820717D01*
X721841Y1820467D01*
X721716Y1820092D01*
Y1819676D01*
X721632Y1819426D01*
X721424Y1819217D01*
X721132Y1819134D01*
X720841Y1819259D01*
X720632Y1819551D01*
X720549Y1819884D01*
X720632Y1820217D01*
X720841Y1820509D01*
X721132Y1820634D01*
X721424Y1820551D01*
X721632Y1820342D01*
X721716Y1820092D01*
Y1819676D01*
X721841Y1819301D01*
X722091Y1819051D01*
X722382Y1818967D01*
X722674Y1819051D01*
X722882Y1819259D01*
X723007Y1819592D01*
X723049Y1819884D01*
G01Y1822901D02*
X722507Y1822984D01*
X722049Y1823109D01*
X721632Y1823276D01*
X721174Y1823484D01*
X720549Y1823817D01*
Y1822151D01*
G01X714549Y1814034D02*
X710549D01*
Y1806634D01*
G01X719049Y1812851D02*
X716549D01*
Y1813892D01*
X716674Y1814226D01*
X716841Y1814434D01*
X717174Y1814517D01*
X717507Y1814434D01*
X717716Y1814184D01*
X717841Y1813892D01*
Y1812851D01*
G01Y1813892D02*
X719049Y1814517D01*
G01X718549Y1815867D02*
X718841Y1816117D01*
X719007Y1816451D01*
X719049Y1816826D01*
X719007Y1817159D01*
X718799Y1817492D01*
X718549Y1817701D01*
X718299Y1817742D01*
X718007Y1817659D01*
X717799Y1817367D01*
X717716Y1817076D01*
Y1816701D01*
G01Y1817076D02*
X717591Y1817326D01*
X717382Y1817534D01*
X717132Y1817617D01*
X716882Y1817534D01*
X716674Y1817326D01*
X716549Y1816951D01*
X716591Y1816576D01*
X716757Y1816201D01*
G01X719049Y1819884D02*
X719007Y1820176D01*
X718882Y1820509D01*
X718674Y1820717D01*
X718382Y1820801D01*
X718091Y1820717D01*
X717841Y1820467D01*
X717716Y1820092D01*
Y1819676D01*
X717632Y1819426D01*
X717424Y1819217D01*
X717132Y1819134D01*
X716841Y1819259D01*
X716632Y1819551D01*
X716549Y1819884D01*
X716632Y1820217D01*
X716841Y1820509D01*
X717132Y1820634D01*
X717424Y1820551D01*
X717632Y1820342D01*
X717716Y1820092D01*
Y1819676D01*
X717841Y1819301D01*
X718091Y1819051D01*
X718382Y1818967D01*
X718674Y1819051D01*
X718882Y1819259D01*
X719007Y1819592D01*
X719049Y1819884D01*
G01X718757Y1822276D02*
X718966Y1822567D01*
X719049Y1822901D01*
X718966Y1823234D01*
X718716Y1823526D01*
X718341Y1823734D01*
X717966Y1823817D01*
X717507D01*
X717132Y1823734D01*
X716799Y1823526D01*
X716632Y1823276D01*
X716549Y1822984D01*
X716632Y1822651D01*
X716799Y1822401D01*
X717049Y1822234D01*
X717382Y1822151D01*
X717674Y1822234D01*
X717966Y1822442D01*
X718132Y1822692D01*
X718174Y1822984D01*
X718091Y1823317D01*
X717882Y1823567D01*
X717507Y1823817D01*
G01X706549Y1806634D02*
X710549D01*
Y1814034D01*
G01X752532Y1818134D02*
Y1816342D01*
X752699Y1815967D01*
X753032Y1815717D01*
X753449Y1815634D01*
X753866Y1815717D01*
X754199Y1815967D01*
X754366Y1816342D01*
Y1818134D01*
G01X755632Y1816009D02*
X755882Y1815801D01*
X756174Y1815676D01*
X756549Y1815634D01*
X756924Y1815717D01*
X757216Y1815884D01*
X757424Y1816176D01*
X757466Y1816509D01*
X757382Y1816842D01*
X757174Y1817051D01*
X756882Y1817217D01*
X756591Y1817259D01*
X756299Y1817217D01*
X755924Y1817051D01*
X756049Y1818134D01*
X757174D01*
G01X759649D02*
X759316Y1818051D01*
X759066Y1817842D01*
X758899Y1817592D01*
X758774Y1817259D01*
X758732Y1816884D01*
X758774Y1816509D01*
X758899Y1816176D01*
X759066Y1815926D01*
X759316Y1815717D01*
X759649Y1815634D01*
X759982Y1815717D01*
X760232Y1815926D01*
X760399Y1816176D01*
X760524Y1816509D01*
X760566Y1816884D01*
X760524Y1817259D01*
X760399Y1817592D01*
X760232Y1817842D01*
X759982Y1818051D01*
X759649Y1818134D01*
G01X769000Y1968500D02*
X752900D01*
G01D02*
Y1975500D01*
G01X736708Y1959767D02*
X736583Y1959517D01*
X736500Y1959225D01*
Y1958892D01*
X736625Y1958517D01*
X736833Y1958225D01*
X737083Y1958017D01*
X737500Y1957850D01*
X737875Y1957808D01*
X738250Y1957892D01*
X738500Y1958017D01*
X738750Y1958267D01*
X738917Y1958558D01*
X739000Y1958850D01*
Y1959142D01*
X738917Y1959433D01*
X738792Y1959683D01*
X738625Y1959892D01*
G01X738500Y1961033D02*
X738792Y1961283D01*
X738958Y1961617D01*
X739000Y1961992D01*
X738958Y1962325D01*
X738750Y1962658D01*
X738500Y1962867D01*
X738250Y1962908D01*
X737958Y1962825D01*
X737750Y1962533D01*
X737667Y1962242D01*
Y1961867D01*
G01Y1962242D02*
X737542Y1962492D01*
X737333Y1962700D01*
X737083Y1962783D01*
X736833Y1962700D01*
X736625Y1962492D01*
X736500Y1962117D01*
X736542Y1961742D01*
X736708Y1961367D01*
G01X739000Y1964967D02*
X738458Y1965050D01*
X738000Y1965175D01*
X737583Y1965342D01*
X737125Y1965550D01*
X736500Y1965883D01*
Y1964217D01*
G01X738708Y1967442D02*
X738917Y1967733D01*
X739000Y1968067D01*
X738917Y1968400D01*
X738667Y1968692D01*
X738292Y1968900D01*
X737917Y1968983D01*
X737458D01*
X737083Y1968900D01*
X736750Y1968692D01*
X736583Y1968442D01*
X736500Y1968150D01*
X736583Y1967817D01*
X736750Y1967567D01*
X737000Y1967400D01*
X737333Y1967317D01*
X737625Y1967400D01*
X737917Y1967608D01*
X738083Y1967858D01*
X738125Y1968150D01*
X738042Y1968483D01*
X737833Y1968733D01*
X737458Y1968983D01*
G01X730000Y1945350D02*
X729958Y1945017D01*
X729792Y1944725D01*
X729542Y1944475D01*
X729250Y1944308D01*
X728917Y1944225D01*
X728583D01*
X728250Y1944308D01*
X727958Y1944475D01*
X727708Y1944725D01*
X727542Y1945017D01*
X727500Y1945350D01*
X727542Y1945683D01*
X727708Y1945975D01*
X727958Y1946225D01*
X728250Y1946392D01*
X728583Y1946475D01*
X728917D01*
X729250Y1946392D01*
X729542Y1946225D01*
X729792Y1945975D01*
X729958Y1945683D01*
X730000Y1945350D01*
G01X729333Y1945683D02*
X730000Y1946183D01*
G01Y1948450D02*
X727500D01*
X728000Y1947950D01*
G01X730000D02*
Y1948950D01*
G01X754114Y1957913D02*
Y1946513D01*
G01X767514Y1957913D02*
X754114D01*
G01Y1946513D02*
X767514D01*
G01X735000Y1958017D02*
X732500D01*
Y1959058D01*
X732625Y1959392D01*
X732792Y1959600D01*
X733125Y1959683D01*
X733458Y1959600D01*
X733667Y1959350D01*
X733792Y1959058D01*
Y1958017D01*
G01Y1959058D02*
X735000Y1959683D01*
G01X734625Y1961033D02*
X734833Y1961283D01*
X734958Y1961575D01*
X735000Y1961950D01*
X734917Y1962325D01*
X734750Y1962617D01*
X734458Y1962825D01*
X734125Y1962867D01*
X733792Y1962783D01*
X733583Y1962575D01*
X733417Y1962283D01*
X733375Y1961992D01*
X733417Y1961700D01*
X733583Y1961325D01*
X732500Y1961450D01*
Y1962575D01*
G01X733958Y1964258D02*
X733667Y1964550D01*
X733500Y1964800D01*
X733417Y1965133D01*
X733500Y1965425D01*
X733667Y1965633D01*
X733917Y1965800D01*
X734208Y1965842D01*
X734458Y1965800D01*
X734708Y1965633D01*
X734917Y1965383D01*
X735000Y1965092D01*
X734917Y1964758D01*
X734667Y1964467D01*
X734292Y1964300D01*
X733875Y1964258D01*
X733333Y1964342D01*
X733042Y1964467D01*
X732750Y1964675D01*
X732542Y1964967D01*
X732500Y1965258D01*
X732583Y1965550D01*
X732792Y1965758D01*
G01X734500Y1967233D02*
X734792Y1967483D01*
X734958Y1967817D01*
X735000Y1968192D01*
X734958Y1968525D01*
X734750Y1968858D01*
X734500Y1969067D01*
X734250Y1969108D01*
X733958Y1969025D01*
X733750Y1968733D01*
X733667Y1968442D01*
Y1968067D01*
G01Y1968442D02*
X733542Y1968692D01*
X733333Y1968900D01*
X733083Y1968983D01*
X732833Y1968900D01*
X732625Y1968692D01*
X732500Y1968317D01*
X732542Y1967942D01*
X732708Y1967567D01*
G01X719017Y1963000D02*
Y1965500D01*
X720058D01*
X720392Y1965375D01*
X720600Y1965208D01*
X720683Y1964875D01*
X720600Y1964542D01*
X720350Y1964333D01*
X720058Y1964208D01*
X719017D01*
G01X720058D02*
X720683Y1963000D01*
G01X723450D02*
Y1965500D01*
X721908Y1963708D01*
X723992D01*
G01X725967Y1963000D02*
X726050Y1963542D01*
X726175Y1964000D01*
X726342Y1964417D01*
X726550Y1964875D01*
X726883Y1965500D01*
X725217D01*
G01X729150Y1963000D02*
X729442Y1963042D01*
X729775Y1963167D01*
X729983Y1963375D01*
X730067Y1963667D01*
X729983Y1963958D01*
X729733Y1964208D01*
X729358Y1964333D01*
X728942D01*
X728692Y1964417D01*
X728483Y1964625D01*
X728400Y1964917D01*
X728525Y1965208D01*
X728817Y1965417D01*
X729150Y1965500D01*
X729483Y1965417D01*
X729775Y1965208D01*
X729900Y1964917D01*
X729817Y1964625D01*
X729608Y1964417D01*
X729358Y1964333D01*
X728942D01*
X728567Y1964208D01*
X728317Y1963958D01*
X728233Y1963667D01*
X728317Y1963375D01*
X728525Y1963167D01*
X728858Y1963042D01*
X729150Y1963000D01*
G01X755300Y1967000D02*
Y1963000D01*
X762700D01*
G01X726831Y1934713D02*
Y1937213D01*
X727872D01*
X728206Y1937088D01*
X728414Y1936921D01*
X728497Y1936588D01*
X728414Y1936255D01*
X728164Y1936046D01*
X727872Y1935921D01*
X726831D01*
G01X727872D02*
X728497Y1934713D01*
G01X730764D02*
Y1937213D01*
X730264Y1936713D01*
G01Y1934713D02*
X731264D01*
G01X733864Y1937213D02*
X733531Y1937130D01*
X733281Y1936921D01*
X733114Y1936671D01*
X732989Y1936338D01*
X732947Y1935963D01*
X732989Y1935588D01*
X733114Y1935255D01*
X733281Y1935005D01*
X733531Y1934796D01*
X733864Y1934713D01*
X734197Y1934796D01*
X734447Y1935005D01*
X734614Y1935255D01*
X734739Y1935588D01*
X734781Y1935963D01*
X734739Y1936338D01*
X734614Y1936671D01*
X734447Y1936921D01*
X734197Y1937130D01*
X733864Y1937213D01*
G01X736881Y1934713D02*
X736964Y1935255D01*
X737089Y1935713D01*
X737256Y1936130D01*
X737464Y1936588D01*
X737797Y1937213D01*
X736131D01*
G01X755514Y1935713D02*
Y1939713D01*
X748114D01*
G01X718717Y1958800D02*
Y1961300D01*
X719758D01*
X720092Y1961175D01*
X720300Y1961008D01*
X720383Y1960675D01*
X720300Y1960342D01*
X720050Y1960133D01*
X719758Y1960008D01*
X718717D01*
G01X719758D02*
X720383Y1958800D01*
G01X722650D02*
Y1961300D01*
X722150Y1960800D01*
G01Y1958800D02*
X723150D01*
G01X725750Y1961300D02*
X725417Y1961217D01*
X725167Y1961008D01*
X725000Y1960758D01*
X724875Y1960425D01*
X724833Y1960050D01*
X724875Y1959675D01*
X725000Y1959342D01*
X725167Y1959092D01*
X725417Y1958883D01*
X725750Y1958800D01*
X726083Y1958883D01*
X726333Y1959092D01*
X726500Y1959342D01*
X726625Y1959675D01*
X726667Y1960050D01*
X726625Y1960425D01*
X726500Y1960758D01*
X726333Y1961008D01*
X726083Y1961217D01*
X725750Y1961300D01*
G01X728850Y1958800D02*
X729142Y1958842D01*
X729475Y1958967D01*
X729683Y1959175D01*
X729767Y1959467D01*
X729683Y1959758D01*
X729433Y1960008D01*
X729058Y1960133D01*
X728642D01*
X728392Y1960217D01*
X728183Y1960425D01*
X728100Y1960717D01*
X728225Y1961008D01*
X728517Y1961217D01*
X728850Y1961300D01*
X729183Y1961217D01*
X729475Y1961008D01*
X729600Y1960717D01*
X729517Y1960425D01*
X729308Y1960217D01*
X729058Y1960133D01*
X728642D01*
X728267Y1960008D01*
X728017Y1959758D01*
X727933Y1959467D01*
X728017Y1959175D01*
X728225Y1958967D01*
X728558Y1958842D01*
X728850Y1958800D01*
G01X751800Y1963000D02*
Y1959000D01*
X759200D01*
G01X716100Y1957117D02*
X713600D01*
Y1958158D01*
X713725Y1958492D01*
X713892Y1958700D01*
X714225Y1958783D01*
X714558Y1958700D01*
X714767Y1958450D01*
X714892Y1958158D01*
Y1957117D01*
G01Y1958158D02*
X716100Y1958783D01*
G01Y1961050D02*
X713600D01*
X714100Y1960550D01*
G01X716100D02*
Y1961550D01*
G01X713600Y1964150D02*
X713683Y1963817D01*
X713892Y1963567D01*
X714142Y1963400D01*
X714475Y1963275D01*
X714850Y1963233D01*
X715225Y1963275D01*
X715558Y1963400D01*
X715808Y1963567D01*
X716017Y1963817D01*
X716100Y1964150D01*
X716017Y1964483D01*
X715808Y1964733D01*
X715558Y1964900D01*
X715225Y1965025D01*
X714850Y1965067D01*
X714475Y1965025D01*
X714142Y1964900D01*
X713892Y1964733D01*
X713683Y1964483D01*
X713600Y1964150D01*
G01X715808Y1966542D02*
X716017Y1966833D01*
X716100Y1967167D01*
X716017Y1967500D01*
X715767Y1967792D01*
X715392Y1968000D01*
X715017Y1968083D01*
X714558D01*
X714183Y1968000D01*
X713850Y1967792D01*
X713683Y1967542D01*
X713600Y1967250D01*
X713683Y1966917D01*
X713850Y1966667D01*
X714100Y1966500D01*
X714433Y1966417D01*
X714725Y1966500D01*
X715017Y1966708D01*
X715183Y1966958D01*
X715225Y1967250D01*
X715142Y1967583D01*
X714933Y1967833D01*
X714558Y1968083D01*
G01X751500Y1963700D02*
X747500D01*
Y1956300D01*
G01X726000Y1944517D02*
X723500D01*
Y1945558D01*
X723625Y1945892D01*
X723792Y1946100D01*
X724125Y1946183D01*
X724458Y1946100D01*
X724667Y1945850D01*
X724792Y1945558D01*
Y1944517D01*
G01Y1945558D02*
X726000Y1946183D01*
G01Y1948450D02*
X723500D01*
X724000Y1947950D01*
G01X726000D02*
Y1948950D01*
G01Y1951550D02*
X723500D01*
X724000Y1951050D01*
G01X726000D02*
Y1952050D01*
G01X723917Y1953858D02*
X723667Y1954108D01*
X723542Y1954400D01*
X723500Y1954733D01*
X723583Y1955150D01*
X723792Y1955442D01*
X724042Y1955525D01*
X724292Y1955483D01*
X724500Y1955317D01*
X724917Y1954483D01*
X725208Y1954108D01*
X725625Y1953858D01*
X726000Y1953775D01*
Y1955525D01*
G01X749000Y1945300D02*
X753000D01*
Y1952700D01*
G01X726831Y1939213D02*
Y1941713D01*
X727872D01*
X728206Y1941588D01*
X728414Y1941421D01*
X728497Y1941088D01*
X728414Y1940755D01*
X728164Y1940546D01*
X727872Y1940421D01*
X726831D01*
G01X727872D02*
X728497Y1939213D01*
G01X730764D02*
Y1941713D01*
X730264Y1941213D01*
G01Y1939213D02*
X731264D01*
G01X733864D02*
Y1941713D01*
X733364Y1941213D01*
G01Y1939213D02*
X734364D01*
G01X736047Y1939713D02*
X736297Y1939421D01*
X736631Y1939255D01*
X737006Y1939213D01*
X737339Y1939255D01*
X737672Y1939463D01*
X737881Y1939713D01*
X737922Y1939963D01*
X737839Y1940255D01*
X737547Y1940463D01*
X737256Y1940546D01*
X736881D01*
G01X737256D02*
X737506Y1940671D01*
X737714Y1940880D01*
X737797Y1941130D01*
X737714Y1941380D01*
X737506Y1941588D01*
X737131Y1941713D01*
X736756Y1941671D01*
X736381Y1941505D01*
G01X755514Y1940213D02*
Y1944213D01*
X748114D01*
G01X734000Y1944517D02*
X731500D01*
Y1945558D01*
X731625Y1945892D01*
X731792Y1946100D01*
X732125Y1946183D01*
X732458Y1946100D01*
X732667Y1945850D01*
X732792Y1945558D01*
Y1944517D01*
G01Y1945558D02*
X734000Y1946183D01*
G01Y1948950D02*
X731500D01*
X733292Y1947408D01*
Y1949492D01*
G01X731500Y1951550D02*
X731583Y1951217D01*
X731792Y1950967D01*
X732042Y1950800D01*
X732375Y1950675D01*
X732750Y1950633D01*
X733125Y1950675D01*
X733458Y1950800D01*
X733708Y1950967D01*
X733917Y1951217D01*
X734000Y1951550D01*
X733917Y1951883D01*
X733708Y1952133D01*
X733458Y1952300D01*
X733125Y1952425D01*
X732750Y1952467D01*
X732375Y1952425D01*
X732042Y1952300D01*
X731792Y1952133D01*
X731583Y1951883D01*
X731500Y1951550D01*
G01X734000Y1954650D02*
X733958Y1954942D01*
X733833Y1955275D01*
X733625Y1955483D01*
X733333Y1955567D01*
X733042Y1955483D01*
X732792Y1955233D01*
X732667Y1954858D01*
Y1954442D01*
X732583Y1954192D01*
X732375Y1953983D01*
X732083Y1953900D01*
X731792Y1954025D01*
X731583Y1954317D01*
X731500Y1954650D01*
X731583Y1954983D01*
X731792Y1955275D01*
X732083Y1955400D01*
X732375Y1955317D01*
X732583Y1955108D01*
X732667Y1954858D01*
Y1954442D01*
X732792Y1954067D01*
X733042Y1953817D01*
X733333Y1953733D01*
X733625Y1953817D01*
X733833Y1954025D01*
X733958Y1954358D01*
X734000Y1954650D01*
G01X756614Y1944713D02*
X770014D01*
G01X756614Y1934713D02*
Y1944713D01*
G01X770014Y1934713D02*
X756614D01*
G01X725983Y1973500D02*
Y1976000D01*
X726817D01*
X727150Y1975875D01*
X727400Y1975708D01*
X727608Y1975458D01*
X727775Y1975167D01*
X727817Y1974750D01*
X727775Y1974333D01*
X727608Y1974042D01*
X727400Y1973792D01*
X727150Y1973625D01*
X726817Y1973500D01*
X725983D01*
G01X730000D02*
Y1976000D01*
X729500Y1975500D01*
G01Y1973500D02*
X730500D01*
G01X732183Y1973875D02*
X732433Y1973667D01*
X732725Y1973542D01*
X733100Y1973500D01*
X733475Y1973583D01*
X733767Y1973750D01*
X733975Y1974042D01*
X734017Y1974375D01*
X733933Y1974708D01*
X733725Y1974917D01*
X733433Y1975083D01*
X733142Y1975125D01*
X732850Y1975083D01*
X732475Y1974917D01*
X732600Y1976000D01*
X733725D01*
G01X752900Y1975500D02*
X769000D01*
G01X817999Y144567D02*
X815499D01*
Y145608D01*
X815624Y145942D01*
X815791Y146150D01*
X816124Y146233D01*
X816457Y146150D01*
X816666Y145900D01*
X816791Y145608D01*
Y144567D01*
G01Y145608D02*
X817999Y146233D01*
G01X817499Y147583D02*
X817791Y147833D01*
X817957Y148167D01*
X817999Y148542D01*
X817957Y148875D01*
X817749Y149208D01*
X817499Y149417D01*
X817249Y149458D01*
X816957Y149375D01*
X816749Y149083D01*
X816666Y148792D01*
Y148417D01*
G01Y148792D02*
X816541Y149042D01*
X816332Y149250D01*
X816082Y149333D01*
X815832Y149250D01*
X815624Y149042D01*
X815499Y148667D01*
X815541Y148292D01*
X815707Y147917D01*
G01X817499Y150683D02*
X817791Y150933D01*
X817957Y151267D01*
X817999Y151642D01*
X817957Y151975D01*
X817749Y152308D01*
X817499Y152517D01*
X817249Y152558D01*
X816957Y152475D01*
X816749Y152183D01*
X816666Y151892D01*
Y151517D01*
G01Y151892D02*
X816541Y152142D01*
X816332Y152350D01*
X816082Y152433D01*
X815832Y152350D01*
X815624Y152142D01*
X815499Y151767D01*
X815541Y151392D01*
X815707Y151017D01*
G01X817999Y154700D02*
X815499D01*
X815999Y154200D01*
G01X817999D02*
Y155200D01*
G01X825499Y144567D02*
X822999D01*
Y145608D01*
X823124Y145942D01*
X823291Y146150D01*
X823624Y146233D01*
X823957Y146150D01*
X824166Y145900D01*
X824291Y145608D01*
Y144567D01*
G01Y145608D02*
X825499Y146233D01*
G01X824999Y147583D02*
X825291Y147833D01*
X825457Y148167D01*
X825499Y148542D01*
X825457Y148875D01*
X825249Y149208D01*
X824999Y149417D01*
X824749Y149458D01*
X824457Y149375D01*
X824249Y149083D01*
X824166Y148792D01*
Y148417D01*
G01Y148792D02*
X824041Y149042D01*
X823832Y149250D01*
X823582Y149333D01*
X823332Y149250D01*
X823124Y149042D01*
X822999Y148667D01*
X823041Y148292D01*
X823207Y147917D01*
G01X824999Y150683D02*
X825291Y150933D01*
X825457Y151267D01*
X825499Y151642D01*
X825457Y151975D01*
X825249Y152308D01*
X824999Y152517D01*
X824749Y152558D01*
X824457Y152475D01*
X824249Y152183D01*
X824166Y151892D01*
Y151517D01*
G01Y151892D02*
X824041Y152142D01*
X823832Y152350D01*
X823582Y152433D01*
X823332Y152350D01*
X823124Y152142D01*
X822999Y151767D01*
X823041Y151392D01*
X823207Y151017D01*
G01X823416Y153908D02*
X823166Y154158D01*
X823041Y154450D01*
X822999Y154783D01*
X823082Y155200D01*
X823291Y155492D01*
X823541Y155575D01*
X823791Y155533D01*
X823999Y155367D01*
X824416Y154533D01*
X824707Y154158D01*
X825124Y153908D01*
X825499Y153825D01*
Y155575D01*
G01X832999Y144567D02*
X830499D01*
Y145608D01*
X830624Y145942D01*
X830791Y146150D01*
X831124Y146233D01*
X831457Y146150D01*
X831666Y145900D01*
X831791Y145608D01*
Y144567D01*
G01Y145608D02*
X832999Y146233D01*
G01X832499Y147583D02*
X832791Y147833D01*
X832957Y148167D01*
X832999Y148542D01*
X832957Y148875D01*
X832749Y149208D01*
X832499Y149417D01*
X832249Y149458D01*
X831957Y149375D01*
X831749Y149083D01*
X831666Y148792D01*
Y148417D01*
G01Y148792D02*
X831541Y149042D01*
X831332Y149250D01*
X831082Y149333D01*
X830832Y149250D01*
X830624Y149042D01*
X830499Y148667D01*
X830541Y148292D01*
X830707Y147917D01*
G01X832499Y150683D02*
X832791Y150933D01*
X832957Y151267D01*
X832999Y151642D01*
X832957Y151975D01*
X832749Y152308D01*
X832499Y152517D01*
X832249Y152558D01*
X831957Y152475D01*
X831749Y152183D01*
X831666Y151892D01*
Y151517D01*
G01Y151892D02*
X831541Y152142D01*
X831332Y152350D01*
X831082Y152433D01*
X830832Y152350D01*
X830624Y152142D01*
X830499Y151767D01*
X830541Y151392D01*
X830707Y151017D01*
G01X832499Y153783D02*
X832791Y154033D01*
X832957Y154367D01*
X832999Y154742D01*
X832957Y155075D01*
X832749Y155408D01*
X832499Y155617D01*
X832249Y155658D01*
X831957Y155575D01*
X831749Y155283D01*
X831666Y154992D01*
Y154617D01*
G01Y154992D02*
X831541Y155242D01*
X831332Y155450D01*
X831082Y155533D01*
X830832Y155450D01*
X830624Y155242D01*
X830499Y154867D01*
X830541Y154492D01*
X830707Y154117D01*
G01X829400Y122117D02*
X826900D01*
Y123117D01*
X827025Y123450D01*
X827317Y123700D01*
X827650Y123783D01*
X827983Y123700D01*
X828233Y123492D01*
X828358Y123117D01*
Y122117D01*
G01X827108Y126967D02*
X826983Y126717D01*
X826900Y126425D01*
Y126092D01*
X827025Y125717D01*
X827233Y125425D01*
X827483Y125217D01*
X827900Y125050D01*
X828275Y125008D01*
X828650Y125092D01*
X828900Y125217D01*
X829150Y125467D01*
X829317Y125758D01*
X829400Y126050D01*
Y126342D01*
X829317Y126633D01*
X829192Y126883D01*
X829025Y127092D01*
G01X829400Y129150D02*
X826900D01*
X827400Y128650D01*
G01X829400D02*
Y129650D01*
G01Y132250D02*
X826900D01*
X827400Y131750D01*
G01X829400D02*
Y132750D01*
G01X834200Y122017D02*
X831700D01*
Y123017D01*
X831825Y123350D01*
X832117Y123600D01*
X832450Y123683D01*
X832783Y123600D01*
X833033Y123392D01*
X833158Y123017D01*
Y122017D01*
G01X831700Y125950D02*
X834200D01*
G01X831700Y124992D02*
Y126908D01*
G01X831908Y129967D02*
X831783Y129717D01*
X831700Y129425D01*
Y129092D01*
X831825Y128717D01*
X832033Y128425D01*
X832283Y128217D01*
X832700Y128050D01*
X833075Y128008D01*
X833450Y128092D01*
X833700Y128217D01*
X833950Y128467D01*
X834117Y128758D01*
X834200Y129050D01*
Y129342D01*
X834117Y129633D01*
X833992Y129883D01*
X833825Y130092D01*
G01X832117Y131358D02*
X831867Y131608D01*
X831742Y131900D01*
X831700Y132233D01*
X831783Y132650D01*
X831992Y132942D01*
X832242Y133025D01*
X832492Y132983D01*
X832700Y132817D01*
X833117Y131983D01*
X833408Y131608D01*
X833825Y131358D01*
X834200Y131275D01*
Y133025D01*
G01X839300Y122317D02*
X836800D01*
Y123317D01*
X836925Y123650D01*
X837217Y123900D01*
X837550Y123983D01*
X837883Y123900D01*
X838133Y123692D01*
X838258Y123317D01*
Y122317D01*
G01X836800Y126250D02*
X839300D01*
G01X836800Y125292D02*
Y127208D01*
G01X837008Y130267D02*
X836883Y130017D01*
X836800Y129725D01*
Y129392D01*
X836925Y129017D01*
X837133Y128725D01*
X837383Y128517D01*
X837800Y128350D01*
X838175Y128308D01*
X838550Y128392D01*
X838800Y128517D01*
X839050Y128767D01*
X839217Y129058D01*
X839300Y129350D01*
Y129642D01*
X839217Y129933D01*
X839092Y130183D01*
X838925Y130392D01*
G01X839300Y132450D02*
X836800D01*
X837300Y131950D01*
G01X839300D02*
Y132950D01*
G01X811992Y172975D02*
X811867Y172725D01*
X811784Y172433D01*
Y172100D01*
X811909Y171725D01*
X812117Y171433D01*
X812367Y171225D01*
X812784Y171058D01*
X813159Y171016D01*
X813534Y171100D01*
X813784Y171225D01*
X814034Y171475D01*
X814201Y171766D01*
X814284Y172058D01*
Y172350D01*
X814201Y172641D01*
X814076Y172891D01*
X813909Y173100D01*
G01X813784Y174241D02*
X814076Y174491D01*
X814242Y174825D01*
X814284Y175200D01*
X814242Y175533D01*
X814034Y175866D01*
X813784Y176075D01*
X813534Y176116D01*
X813242Y176033D01*
X813034Y175741D01*
X812951Y175450D01*
Y175075D01*
G01Y175450D02*
X812826Y175700D01*
X812617Y175908D01*
X812367Y175991D01*
X812117Y175908D01*
X811909Y175700D01*
X811784Y175325D01*
X811826Y174950D01*
X811992Y174575D01*
G01X814284Y178758D02*
X811784D01*
X813576Y177216D01*
Y179300D01*
G01X813784Y180441D02*
X814076Y180691D01*
X814242Y181025D01*
X814284Y181400D01*
X814242Y181733D01*
X814034Y182066D01*
X813784Y182275D01*
X813534Y182316D01*
X813242Y182233D01*
X813034Y181941D01*
X812951Y181650D01*
Y181275D01*
G01Y181650D02*
X812826Y181900D01*
X812617Y182108D01*
X812367Y182191D01*
X812117Y182108D01*
X811909Y181900D01*
X811784Y181525D01*
X811826Y181150D01*
X811992Y180775D01*
G01X835999Y210250D02*
X831999D01*
Y202850D01*
G01X814499Y157350D02*
X818499D01*
Y164750D01*
G01X821999Y157350D02*
X825999D01*
Y164750D01*
G01X829499Y157350D02*
X833499D01*
Y164750D01*
G01X831499Y210250D02*
X827499D01*
Y202850D01*
G01X802284Y171225D02*
X799784D01*
Y172266D01*
X799909Y172600D01*
X800076Y172808D01*
X800409Y172891D01*
X800742Y172808D01*
X800951Y172558D01*
X801076Y172266D01*
Y171225D01*
G01Y172266D02*
X802284Y172891D01*
G01X801784Y174241D02*
X802076Y174491D01*
X802242Y174825D01*
X802284Y175200D01*
X802242Y175533D01*
X802034Y175866D01*
X801784Y176075D01*
X801534Y176116D01*
X801242Y176033D01*
X801034Y175741D01*
X800951Y175450D01*
Y175075D01*
G01Y175450D02*
X800826Y175700D01*
X800617Y175908D01*
X800367Y175991D01*
X800117Y175908D01*
X799909Y175700D01*
X799784Y175325D01*
X799826Y174950D01*
X799992Y174575D01*
G01X801784Y177341D02*
X802076Y177591D01*
X802242Y177925D01*
X802284Y178300D01*
X802242Y178633D01*
X802034Y178966D01*
X801784Y179175D01*
X801534Y179216D01*
X801242Y179133D01*
X801034Y178841D01*
X800951Y178550D01*
Y178175D01*
G01Y178550D02*
X800826Y178800D01*
X800617Y179008D01*
X800367Y179091D01*
X800117Y179008D01*
X799909Y178800D01*
X799784Y178425D01*
X799826Y178050D01*
X799992Y177675D01*
G01X801992Y180650D02*
X802201Y180941D01*
X802284Y181275D01*
X802201Y181608D01*
X801951Y181900D01*
X801576Y182108D01*
X801201Y182191D01*
X800742D01*
X800367Y182108D01*
X800034Y181900D01*
X799867Y181650D01*
X799784Y181358D01*
X799867Y181025D01*
X800034Y180775D01*
X800284Y180608D01*
X800617Y180525D01*
X800909Y180608D01*
X801201Y180816D01*
X801367Y181066D01*
X801409Y181358D01*
X801326Y181691D01*
X801117Y181941D01*
X800742Y182191D01*
G01X818699Y165050D02*
Y169050D01*
X811299D01*
G01X806284Y171225D02*
X803784D01*
Y172266D01*
X803909Y172600D01*
X804076Y172808D01*
X804409Y172891D01*
X804742Y172808D01*
X804951Y172558D01*
X805076Y172266D01*
Y171225D01*
G01Y172266D02*
X806284Y172891D01*
G01X805784Y174241D02*
X806076Y174491D01*
X806242Y174825D01*
X806284Y175200D01*
X806242Y175533D01*
X806034Y175866D01*
X805784Y176075D01*
X805534Y176116D01*
X805242Y176033D01*
X805034Y175741D01*
X804951Y175450D01*
Y175075D01*
G01Y175450D02*
X804826Y175700D01*
X804617Y175908D01*
X804367Y175991D01*
X804117Y175908D01*
X803909Y175700D01*
X803784Y175325D01*
X803826Y174950D01*
X803992Y174575D01*
G01X806284Y178758D02*
X803784D01*
X805576Y177216D01*
Y179300D01*
G01X803784Y181358D02*
X803867Y181025D01*
X804076Y180775D01*
X804326Y180608D01*
X804659Y180483D01*
X805034Y180441D01*
X805409Y180483D01*
X805742Y180608D01*
X805992Y180775D01*
X806201Y181025D01*
X806284Y181358D01*
X806201Y181691D01*
X805992Y181941D01*
X805742Y182108D01*
X805409Y182233D01*
X805034Y182275D01*
X804659Y182233D01*
X804326Y182108D01*
X804076Y181941D01*
X803867Y181691D01*
X803784Y181358D01*
G01X826199Y165050D02*
Y169050D01*
X818799D01*
G01X810284Y171225D02*
X807784D01*
Y172266D01*
X807909Y172600D01*
X808076Y172808D01*
X808409Y172891D01*
X808742Y172808D01*
X808951Y172558D01*
X809076Y172266D01*
Y171225D01*
G01Y172266D02*
X810284Y172891D01*
G01X809784Y174241D02*
X810076Y174491D01*
X810242Y174825D01*
X810284Y175200D01*
X810242Y175533D01*
X810034Y175866D01*
X809784Y176075D01*
X809534Y176116D01*
X809242Y176033D01*
X809034Y175741D01*
X808951Y175450D01*
Y175075D01*
G01Y175450D02*
X808826Y175700D01*
X808617Y175908D01*
X808367Y175991D01*
X808117Y175908D01*
X807909Y175700D01*
X807784Y175325D01*
X807826Y174950D01*
X807992Y174575D01*
G01X810284Y178758D02*
X807784D01*
X809576Y177216D01*
Y179300D01*
G01X810284Y181358D02*
X807784D01*
X808284Y180858D01*
G01X810284D02*
Y181858D01*
G01X833699Y165050D02*
Y169050D01*
X826299D01*
G01X817193Y200960D02*
X819693D01*
G01X817193Y200002D02*
Y201918D01*
G01X819693Y203227D02*
X817193D01*
Y204227D01*
X817318Y204560D01*
X817610Y204810D01*
X817943Y204893D01*
X818276Y204810D01*
X818526Y204602D01*
X818651Y204227D01*
Y203227D01*
G01X819693Y207660D02*
X817193D01*
X818985Y206118D01*
Y208202D01*
G01X816413Y185678D02*
X818205D01*
X818580Y185845D01*
X818830Y186178D01*
X818913Y186595D01*
X818830Y187012D01*
X818580Y187345D01*
X818205Y187512D01*
X816413D01*
G01X818913Y190195D02*
X816413D01*
X818205Y188653D01*
Y190737D01*
G01X818621Y192087D02*
X818830Y192378D01*
X818913Y192712D01*
X818830Y193045D01*
X818580Y193337D01*
X818205Y193545D01*
X817830Y193628D01*
X817371D01*
X816996Y193545D01*
X816663Y193337D01*
X816496Y193087D01*
X816413Y192795D01*
X816496Y192462D01*
X816663Y192212D01*
X816913Y192045D01*
X817246Y191962D01*
X817538Y192045D01*
X817830Y192253D01*
X817996Y192503D01*
X818038Y192795D01*
X817955Y193128D01*
X817746Y193378D01*
X817371Y193628D01*
G01X824923Y189039D02*
Y181039D01*
X836873D01*
Y189039D01*
X824923D01*
G01X836873Y182889D02*
X834873Y184889D01*
X836873Y186889D01*
G01X803267Y285792D02*
X803017Y285917D01*
X802725Y286000D01*
X802392D01*
X802017Y285875D01*
X801725Y285667D01*
X801517Y285417D01*
X801350Y285000D01*
X801308Y284625D01*
X801392Y284250D01*
X801517Y284000D01*
X801767Y283750D01*
X802058Y283583D01*
X802350Y283500D01*
X802642D01*
X802933Y283583D01*
X803183Y283708D01*
X803392Y283875D01*
G01X804533Y284000D02*
X804783Y283708D01*
X805117Y283542D01*
X805492Y283500D01*
X805825Y283542D01*
X806158Y283750D01*
X806367Y284000D01*
X806408Y284250D01*
X806325Y284542D01*
X806033Y284750D01*
X805742Y284833D01*
X805367D01*
G01X805742D02*
X805992Y284958D01*
X806200Y285167D01*
X806283Y285417D01*
X806200Y285667D01*
X805992Y285875D01*
X805617Y286000D01*
X805242Y285958D01*
X804867Y285792D01*
G01X807758Y284542D02*
X808050Y284833D01*
X808300Y285000D01*
X808633Y285083D01*
X808925Y285000D01*
X809133Y284833D01*
X809300Y284583D01*
X809342Y284292D01*
X809300Y284042D01*
X809133Y283792D01*
X808883Y283583D01*
X808592Y283500D01*
X808258Y283583D01*
X807967Y283833D01*
X807800Y284208D01*
X807758Y284625D01*
X807842Y285167D01*
X807967Y285458D01*
X808175Y285750D01*
X808467Y285958D01*
X808758Y286000D01*
X809050Y285917D01*
X809258Y285708D01*
G01X811650Y283500D02*
X811942Y283542D01*
X812275Y283667D01*
X812483Y283875D01*
X812567Y284167D01*
X812483Y284458D01*
X812233Y284708D01*
X811858Y284833D01*
X811442D01*
X811192Y284917D01*
X810983Y285125D01*
X810900Y285417D01*
X811025Y285708D01*
X811317Y285917D01*
X811650Y286000D01*
X811983Y285917D01*
X812275Y285708D01*
X812400Y285417D01*
X812317Y285125D01*
X812108Y284917D01*
X811858Y284833D01*
X811442D01*
X811067Y284708D01*
X810817Y284458D01*
X810733Y284167D01*
X810817Y283875D01*
X811025Y283667D01*
X811358Y283542D01*
X811650Y283500D01*
G01X758208Y302767D02*
X758083Y302517D01*
X758000Y302225D01*
Y301892D01*
X758125Y301517D01*
X758333Y301225D01*
X758583Y301017D01*
X759000Y300850D01*
X759375Y300808D01*
X759750Y300892D01*
X760000Y301017D01*
X760250Y301267D01*
X760417Y301558D01*
X760500Y301850D01*
Y302142D01*
X760417Y302433D01*
X760292Y302683D01*
X760125Y302892D01*
G01X760500Y304950D02*
X758000D01*
X758500Y304450D01*
G01X760500D02*
Y305450D01*
G01Y307967D02*
X759958Y308050D01*
X759500Y308175D01*
X759083Y308342D01*
X758625Y308550D01*
X758000Y308883D01*
Y307217D01*
G01X760500Y311150D02*
X758000D01*
X758500Y310650D01*
G01X760500D02*
Y311650D01*
G01X774708Y302267D02*
X774583Y302017D01*
X774500Y301725D01*
Y301392D01*
X774625Y301017D01*
X774833Y300725D01*
X775083Y300517D01*
X775500Y300350D01*
X775875Y300308D01*
X776250Y300392D01*
X776500Y300517D01*
X776750Y300767D01*
X776917Y301058D01*
X777000Y301350D01*
Y301642D01*
X776917Y301933D01*
X776792Y302183D01*
X776625Y302392D01*
G01X777000Y304450D02*
X774500D01*
X775000Y303950D01*
G01X777000D02*
Y304950D01*
G01X775958Y306758D02*
X775667Y307050D01*
X775500Y307300D01*
X775417Y307633D01*
X775500Y307925D01*
X775667Y308133D01*
X775917Y308300D01*
X776208Y308342D01*
X776458Y308300D01*
X776708Y308133D01*
X776917Y307883D01*
X777000Y307592D01*
X776917Y307258D01*
X776667Y306967D01*
X776292Y306800D01*
X775875Y306758D01*
X775333Y306842D01*
X775042Y306967D01*
X774750Y307175D01*
X774542Y307467D01*
X774500Y307758D01*
X774583Y308050D01*
X774792Y308258D01*
G01X776625Y309733D02*
X776833Y309983D01*
X776958Y310275D01*
X777000Y310650D01*
X776917Y311025D01*
X776750Y311317D01*
X776458Y311525D01*
X776125Y311567D01*
X775792Y311483D01*
X775583Y311275D01*
X775417Y310983D01*
X775375Y310692D01*
X775417Y310400D01*
X775583Y310025D01*
X774500Y310150D01*
Y311275D01*
G01X810000Y264400D02*
X809958Y264067D01*
X809792Y263775D01*
X809542Y263525D01*
X809250Y263358D01*
X808917Y263275D01*
X808583D01*
X808250Y263358D01*
X807958Y263525D01*
X807708Y263775D01*
X807542Y264067D01*
X807500Y264400D01*
X807542Y264733D01*
X807708Y265025D01*
X807958Y265275D01*
X808250Y265442D01*
X808583Y265525D01*
X808917D01*
X809250Y265442D01*
X809542Y265275D01*
X809792Y265025D01*
X809958Y264733D01*
X810000Y264400D01*
G01X809333Y264733D02*
X810000Y265233D01*
G01X809625Y266583D02*
X809833Y266833D01*
X809958Y267125D01*
X810000Y267500D01*
X809917Y267875D01*
X809750Y268167D01*
X809458Y268375D01*
X809125Y268417D01*
X808792Y268333D01*
X808583Y268125D01*
X808417Y267833D01*
X808375Y267542D01*
X808417Y267250D01*
X808583Y266875D01*
X807500Y267000D01*
Y268125D01*
G01X810000Y271100D02*
X807500D01*
X809292Y269558D01*
Y271642D01*
G01X811700Y273200D02*
Y261800D01*
G01X825100Y273200D02*
X811700D01*
G01X825100Y261800D02*
Y273200D01*
G01X811700Y261800D02*
X825100D01*
G01X792450Y302500D02*
X792117Y302542D01*
X791825Y302708D01*
X791575Y302958D01*
X791408Y303250D01*
X791325Y303583D01*
Y303917D01*
X791408Y304250D01*
X791575Y304542D01*
X791825Y304792D01*
X792117Y304958D01*
X792450Y305000D01*
X792783Y304958D01*
X793075Y304792D01*
X793325Y304542D01*
X793492Y304250D01*
X793575Y303917D01*
Y303583D01*
X793492Y303250D01*
X793325Y302958D01*
X793075Y302708D01*
X792783Y302542D01*
X792450Y302500D01*
G01X792783Y303167D02*
X793283Y302500D01*
G01X794842Y302792D02*
X795133Y302583D01*
X795467Y302500D01*
X795800Y302583D01*
X796092Y302833D01*
X796300Y303208D01*
X796383Y303583D01*
Y304042D01*
X796300Y304417D01*
X796092Y304750D01*
X795842Y304917D01*
X795550Y305000D01*
X795217Y304917D01*
X794967Y304750D01*
X794800Y304500D01*
X794717Y304167D01*
X794800Y303875D01*
X795008Y303583D01*
X795258Y303417D01*
X795550Y303375D01*
X795883Y303458D01*
X796133Y303667D01*
X796383Y304042D01*
G01X810873Y289271D02*
X812673Y291371D01*
X814873Y289271D01*
G01X818473Y289171D02*
Y308371D01*
X807273D01*
Y289171D01*
X818473D01*
Y289571D01*
G01X834228Y296624D02*
Y283624D01*
G01X860228Y296624D02*
X834228D01*
G01Y283624D02*
X860228D01*
G01X829500Y249567D02*
X827000D01*
Y250608D01*
X827125Y250942D01*
X827292Y251150D01*
X827625Y251233D01*
X827958Y251150D01*
X828167Y250900D01*
X828292Y250608D01*
Y249567D01*
G01Y250608D02*
X829500Y251233D01*
G01X829000Y252583D02*
X829292Y252833D01*
X829458Y253167D01*
X829500Y253542D01*
X829458Y253875D01*
X829250Y254208D01*
X829000Y254417D01*
X828750Y254458D01*
X828458Y254375D01*
X828250Y254083D01*
X828167Y253792D01*
Y253417D01*
G01Y253792D02*
X828042Y254042D01*
X827833Y254250D01*
X827583Y254333D01*
X827333Y254250D01*
X827125Y254042D01*
X827000Y253667D01*
X827042Y253292D01*
X827208Y252917D01*
G01X829500Y256517D02*
X828958Y256600D01*
X828500Y256725D01*
X828083Y256892D01*
X827625Y257100D01*
X827000Y257433D01*
Y255767D01*
G01Y259700D02*
X827083Y259367D01*
X827292Y259117D01*
X827542Y258950D01*
X827875Y258825D01*
X828250Y258783D01*
X828625Y258825D01*
X828958Y258950D01*
X829208Y259117D01*
X829417Y259367D01*
X829500Y259700D01*
X829417Y260033D01*
X829208Y260283D01*
X828958Y260450D01*
X828625Y260575D01*
X828250Y260617D01*
X827875Y260575D01*
X827542Y260450D01*
X827292Y260283D01*
X827083Y260033D01*
X827000Y259700D01*
G01X829500Y272900D02*
X825500D01*
Y265500D01*
G01X828978Y310124D02*
Y315624D01*
G01X836978Y310124D02*
X828978D01*
G01X836978Y315624D02*
Y310124D01*
G01X840900Y260000D02*
X840567Y260042D01*
X840275Y260208D01*
X840025Y260458D01*
X839858Y260750D01*
X839775Y261083D01*
Y261417D01*
X839858Y261750D01*
X840025Y262042D01*
X840275Y262292D01*
X840567Y262458D01*
X840900Y262500D01*
X841233Y262458D01*
X841525Y262292D01*
X841775Y262042D01*
X841942Y261750D01*
X842025Y261417D01*
Y261083D01*
X841942Y260750D01*
X841775Y260458D01*
X841525Y260208D01*
X841233Y260042D01*
X840900Y260000D01*
G01X841233Y260667D02*
X841733Y260000D01*
G01X843083Y260375D02*
X843333Y260167D01*
X843625Y260042D01*
X844000Y260000D01*
X844375Y260083D01*
X844667Y260250D01*
X844875Y260542D01*
X844917Y260875D01*
X844833Y261208D01*
X844625Y261417D01*
X844333Y261583D01*
X844042Y261625D01*
X843750Y261583D01*
X843375Y261417D01*
X843500Y262500D01*
X844625D01*
G01X846183Y260375D02*
X846433Y260167D01*
X846725Y260042D01*
X847100Y260000D01*
X847475Y260083D01*
X847767Y260250D01*
X847975Y260542D01*
X848017Y260875D01*
X847933Y261208D01*
X847725Y261417D01*
X847433Y261583D01*
X847142Y261625D01*
X846850Y261583D01*
X846475Y261417D01*
X846600Y262500D01*
X847725D01*
G01X830200Y264200D02*
X843200D01*
G01X830200Y278200D02*
Y264200D01*
G01X843200Y278200D02*
X830200D01*
G01X766000Y366000D02*
Y359000D01*
G01X769178Y333724D02*
Y345124D01*
G01X837728Y330424D02*
Y317424D01*
G01X863728Y330424D02*
X837728D01*
G01Y317424D02*
X863728D01*
G01X763000Y350300D02*
X767000D01*
Y357700D01*
G01X789516Y366550D02*
Y369050D01*
X790557D01*
X790891Y368925D01*
X791099Y368758D01*
X791182Y368425D01*
X791099Y368092D01*
X790849Y367883D01*
X790557Y367758D01*
X789516D01*
G01X790557D02*
X791182Y366550D01*
G01X793949D02*
Y369050D01*
X792407Y367258D01*
X794491D01*
G01X795632Y367050D02*
X795882Y366758D01*
X796216Y366592D01*
X796591Y366550D01*
X796924Y366592D01*
X797257Y366800D01*
X797466Y367050D01*
X797507Y367300D01*
X797424Y367592D01*
X797132Y367800D01*
X796841Y367883D01*
X796466D01*
G01X796841D02*
X797091Y368008D01*
X797299Y368217D01*
X797382Y368467D01*
X797299Y368717D01*
X797091Y368925D01*
X796716Y369050D01*
X796341Y369008D01*
X795966Y368842D01*
G01X799649Y366550D02*
X799941Y366592D01*
X800274Y366717D01*
X800482Y366925D01*
X800566Y367217D01*
X800482Y367508D01*
X800232Y367758D01*
X799857Y367883D01*
X799441D01*
X799191Y367967D01*
X798982Y368175D01*
X798899Y368467D01*
X799024Y368758D01*
X799316Y368967D01*
X799649Y369050D01*
X799982Y368967D01*
X800274Y368758D01*
X800399Y368467D01*
X800316Y368175D01*
X800107Y367967D01*
X799857Y367883D01*
X799441D01*
X799066Y367758D01*
X798816Y367508D01*
X798732Y367217D01*
X798816Y366925D01*
X799024Y366717D01*
X799357Y366592D01*
X799649Y366550D01*
G01X802699Y334050D02*
Y338050D01*
X795299D01*
G01X789516Y362550D02*
Y365050D01*
X790557D01*
X790891Y364925D01*
X791099Y364758D01*
X791182Y364425D01*
X791099Y364092D01*
X790849Y363883D01*
X790557Y363758D01*
X789516D01*
G01X790557D02*
X791182Y362550D01*
G01X793949D02*
Y365050D01*
X792407Y363258D01*
X794491D01*
G01X795632Y363050D02*
X795882Y362758D01*
X796216Y362592D01*
X796591Y362550D01*
X796924Y362592D01*
X797257Y362800D01*
X797466Y363050D01*
X797507Y363300D01*
X797424Y363592D01*
X797132Y363800D01*
X796841Y363883D01*
X796466D01*
G01X796841D02*
X797091Y364008D01*
X797299Y364217D01*
X797382Y364467D01*
X797299Y364717D01*
X797091Y364925D01*
X796716Y365050D01*
X796341Y365008D01*
X795966Y364842D01*
G01X798941Y362842D02*
X799232Y362633D01*
X799566Y362550D01*
X799899Y362633D01*
X800191Y362883D01*
X800399Y363258D01*
X800482Y363633D01*
Y364092D01*
X800399Y364467D01*
X800191Y364800D01*
X799941Y364967D01*
X799649Y365050D01*
X799316Y364967D01*
X799066Y364800D01*
X798899Y364550D01*
X798816Y364217D01*
X798899Y363925D01*
X799107Y363633D01*
X799357Y363467D01*
X799649Y363425D01*
X799982Y363508D01*
X800232Y363717D01*
X800482Y364092D01*
G01X802699Y330050D02*
Y334050D01*
X795299D01*
G01X781699Y324550D02*
Y328550D01*
X774299D01*
G01X781699Y320550D02*
Y324550D01*
X774299D01*
G01X769500Y335800D02*
X773500D01*
Y343200D01*
G01X795499Y316533D02*
X797291D01*
X797666Y316700D01*
X797916Y317033D01*
X797999Y317450D01*
X797916Y317867D01*
X797666Y318200D01*
X797291Y318367D01*
X795499D01*
G01X797999Y320550D02*
X795499D01*
X795999Y320050D01*
G01X797999D02*
Y321050D01*
G01X797499Y322733D02*
X797791Y322983D01*
X797957Y323317D01*
X797999Y323692D01*
X797957Y324025D01*
X797749Y324358D01*
X797499Y324567D01*
X797249Y324608D01*
X796957Y324525D01*
X796749Y324233D01*
X796666Y323942D01*
Y323567D01*
G01Y323942D02*
X796541Y324192D01*
X796332Y324400D01*
X796082Y324483D01*
X795832Y324400D01*
X795624Y324192D01*
X795499Y323817D01*
X795541Y323442D01*
X795707Y323067D01*
G01X782999Y317850D02*
Y331250D01*
G01X792999Y317850D02*
X782999D01*
G01X792999Y331250D02*
Y317850D01*
G01X782999Y331250D02*
X792999D01*
G01X757778Y331424D02*
X771178D01*
G01X757778Y321424D02*
Y331424D01*
G01X771178Y321424D02*
X757778D01*
G01X771178Y331424D02*
Y321424D01*
G01X789482Y373050D02*
Y371258D01*
X789649Y370883D01*
X789982Y370633D01*
X790399Y370550D01*
X790816Y370633D01*
X791149Y370883D01*
X791316Y371258D01*
Y373050D01*
G01X793499Y370550D02*
Y373050D01*
X792999Y372550D01*
G01Y370550D02*
X793999D01*
G01X797099D02*
Y373050D01*
X795557Y371258D01*
X797641D01*
G01X789978Y360224D02*
X787978Y358224D01*
X785978Y360224D01*
G01X782378D02*
Y341024D01*
X793578D01*
Y360224D01*
X782378D01*
G01X815450Y319600D02*
Y317100D01*
G01X814492Y319600D02*
X816408D01*
G01X817717Y317100D02*
Y319600D01*
X818717D01*
X819050Y319475D01*
X819300Y319183D01*
X819383Y318850D01*
X819300Y318517D01*
X819092Y318267D01*
X818717Y318142D01*
X817717D01*
G01X820858Y319183D02*
X821108Y319433D01*
X821400Y319558D01*
X821733Y319600D01*
X822150Y319517D01*
X822442Y319308D01*
X822525Y319058D01*
X822483Y318808D01*
X822317Y318600D01*
X821483Y318183D01*
X821108Y317892D01*
X820858Y317475D01*
X820775Y317100D01*
X822525D01*
G01X824042Y317392D02*
X824333Y317183D01*
X824667Y317100D01*
X825000Y317183D01*
X825292Y317433D01*
X825500Y317808D01*
X825583Y318183D01*
Y318642D01*
X825500Y319017D01*
X825292Y319350D01*
X825042Y319517D01*
X824750Y319600D01*
X824417Y319517D01*
X824167Y319350D01*
X824000Y319100D01*
X823917Y318767D01*
X824000Y318475D01*
X824208Y318183D01*
X824458Y318017D01*
X824750Y317975D01*
X825083Y318058D01*
X825333Y318267D01*
X825583Y318642D01*
G01X816767Y325292D02*
X816517Y325417D01*
X816225Y325500D01*
X815892D01*
X815517Y325375D01*
X815225Y325167D01*
X815017Y324917D01*
X814850Y324500D01*
X814808Y324125D01*
X814892Y323750D01*
X815017Y323500D01*
X815267Y323250D01*
X815558Y323083D01*
X815850Y323000D01*
X816142D01*
X816433Y323083D01*
X816683Y323208D01*
X816892Y323375D01*
G01X818950Y323000D02*
Y325500D01*
X818450Y325000D01*
G01Y323000D02*
X819450D01*
G01X821967D02*
X822050Y323542D01*
X822175Y324000D01*
X822342Y324417D01*
X822550Y324875D01*
X822883Y325500D01*
X821217D01*
G01X825650Y323000D02*
Y325500D01*
X824108Y323708D01*
X826192D01*
G01X836978Y327724D02*
Y322224D01*
G01X828978Y327724D02*
X836978D01*
G01X828978Y322224D02*
Y327724D01*
G01X839508Y354467D02*
X839383Y354217D01*
X839300Y353925D01*
Y353592D01*
X839425Y353217D01*
X839633Y352925D01*
X839883Y352717D01*
X840300Y352550D01*
X840675Y352508D01*
X841050Y352592D01*
X841300Y352717D01*
X841550Y352967D01*
X841717Y353258D01*
X841800Y353550D01*
Y353842D01*
X841717Y354133D01*
X841592Y354383D01*
X841425Y354592D01*
G01X841800Y356650D02*
X839300D01*
X839800Y356150D01*
G01X841800D02*
Y357150D01*
G01Y359667D02*
X841258Y359750D01*
X840800Y359875D01*
X840383Y360042D01*
X839925Y360250D01*
X839300Y360583D01*
Y358917D01*
G01X841425Y361933D02*
X841633Y362183D01*
X841758Y362475D01*
X841800Y362850D01*
X841717Y363225D01*
X841550Y363517D01*
X841258Y363725D01*
X840925Y363767D01*
X840592Y363683D01*
X840383Y363475D01*
X840217Y363183D01*
X840175Y362892D01*
X840217Y362600D01*
X840383Y362225D01*
X839300Y362350D01*
Y363475D01*
G01X836800Y332500D02*
Y338000D01*
G01X844800Y332500D02*
X836800D01*
G01Y350100D02*
X844800D01*
G01X836800Y344600D02*
Y350100D01*
G01X803708Y681767D02*
X803583Y681517D01*
X803500Y681225D01*
Y680892D01*
X803625Y680517D01*
X803833Y680225D01*
X804083Y680017D01*
X804500Y679850D01*
X804875Y679808D01*
X805250Y679892D01*
X805500Y680017D01*
X805750Y680267D01*
X805917Y680558D01*
X806000Y680850D01*
Y681142D01*
X805917Y681433D01*
X805792Y681683D01*
X805625Y681892D01*
G01X805500Y683033D02*
X805792Y683283D01*
X805958Y683617D01*
X806000Y683992D01*
X805958Y684325D01*
X805750Y684658D01*
X805500Y684867D01*
X805250Y684908D01*
X804958Y684825D01*
X804750Y684533D01*
X804667Y684242D01*
Y683867D01*
G01Y684242D02*
X804542Y684492D01*
X804333Y684700D01*
X804083Y684783D01*
X803833Y684700D01*
X803625Y684492D01*
X803500Y684117D01*
X803542Y683742D01*
X803708Y683367D01*
G01X804958Y686258D02*
X804667Y686550D01*
X804500Y686800D01*
X804417Y687133D01*
X804500Y687425D01*
X804667Y687633D01*
X804917Y687800D01*
X805208Y687842D01*
X805458Y687800D01*
X805708Y687633D01*
X805917Y687383D01*
X806000Y687092D01*
X805917Y686758D01*
X805667Y686467D01*
X805292Y686300D01*
X804875Y686258D01*
X804333Y686342D01*
X804042Y686467D01*
X803750Y686675D01*
X803542Y686967D01*
X803500Y687258D01*
X803583Y687550D01*
X803792Y687758D01*
G01X806000Y690067D02*
X805458Y690150D01*
X805000Y690275D01*
X804583Y690442D01*
X804125Y690650D01*
X803500Y690983D01*
Y689317D01*
G01X771208Y701267D02*
X771083Y701017D01*
X771000Y700725D01*
Y700392D01*
X771125Y700017D01*
X771333Y699725D01*
X771583Y699517D01*
X772000Y699350D01*
X772375Y699308D01*
X772750Y699392D01*
X773000Y699517D01*
X773250Y699767D01*
X773417Y700058D01*
X773500Y700350D01*
Y700642D01*
X773417Y700933D01*
X773292Y701183D01*
X773125Y701392D01*
G01X773500Y703450D02*
X771000D01*
X771500Y702950D01*
G01X773500D02*
Y703950D01*
G01Y707050D02*
X771000D01*
X772792Y705508D01*
Y707592D01*
G01X773208Y708942D02*
X773417Y709233D01*
X773500Y709567D01*
X773417Y709900D01*
X773167Y710192D01*
X772792Y710400D01*
X772417Y710483D01*
X771958D01*
X771583Y710400D01*
X771250Y710192D01*
X771083Y709942D01*
X771000Y709650D01*
X771083Y709317D01*
X771250Y709067D01*
X771500Y708900D01*
X771833Y708817D01*
X772125Y708900D01*
X772417Y709108D01*
X772583Y709358D01*
X772625Y709650D01*
X772542Y709983D01*
X772333Y710233D01*
X771958Y710483D01*
G01X819500Y651400D02*
X819458Y651067D01*
X819292Y650775D01*
X819042Y650525D01*
X818750Y650358D01*
X818417Y650275D01*
X818083D01*
X817750Y650358D01*
X817458Y650525D01*
X817208Y650775D01*
X817042Y651067D01*
X817000Y651400D01*
X817042Y651733D01*
X817208Y652025D01*
X817458Y652275D01*
X817750Y652442D01*
X818083Y652525D01*
X818417D01*
X818750Y652442D01*
X819042Y652275D01*
X819292Y652025D01*
X819458Y651733D01*
X819500Y651400D01*
G01X818833Y651733D02*
X819500Y652233D01*
G01X819125Y653583D02*
X819333Y653833D01*
X819458Y654125D01*
X819500Y654500D01*
X819417Y654875D01*
X819250Y655167D01*
X818958Y655375D01*
X818625Y655417D01*
X818292Y655333D01*
X818083Y655125D01*
X817917Y654833D01*
X817875Y654542D01*
X817917Y654250D01*
X818083Y653875D01*
X817000Y654000D01*
Y655125D01*
G01X817417Y656808D02*
X817167Y657058D01*
X817042Y657350D01*
X817000Y657683D01*
X817083Y658100D01*
X817292Y658392D01*
X817542Y658475D01*
X817792Y658433D01*
X818000Y658267D01*
X818417Y657433D01*
X818708Y657058D01*
X819125Y656808D01*
X819500Y656725D01*
Y658475D01*
G01X810200Y675800D02*
Y664400D01*
G01X823600Y675800D02*
X810200D01*
G01X823600Y664400D02*
Y675800D01*
G01X810200Y664400D02*
X823600D01*
G01X790950Y705000D02*
X790617Y705042D01*
X790325Y705208D01*
X790075Y705458D01*
X789908Y705750D01*
X789825Y706083D01*
Y706417D01*
X789908Y706750D01*
X790075Y707042D01*
X790325Y707292D01*
X790617Y707458D01*
X790950Y707500D01*
X791283Y707458D01*
X791575Y707292D01*
X791825Y707042D01*
X791992Y706750D01*
X792075Y706417D01*
Y706083D01*
X791992Y705750D01*
X791825Y705458D01*
X791575Y705208D01*
X791283Y705042D01*
X790950Y705000D01*
G01X791283Y705667D02*
X791783Y705000D01*
G01X793967D02*
X794050Y705542D01*
X794175Y706000D01*
X794342Y706417D01*
X794550Y706875D01*
X794883Y707500D01*
X793217D01*
G01X808831Y693653D02*
X810631Y695753D01*
X812831Y693653D01*
G01X816431Y693553D02*
Y712753D01*
X805231D01*
Y693553D01*
X816431D01*
Y693953D01*
G01X832446Y697682D02*
Y684682D01*
G01X858446Y697682D02*
X832446D01*
G01Y684682D02*
X858446D01*
G01X835499Y731050D02*
Y718050D01*
G01D02*
X861499D01*
G01X823500Y650567D02*
X821000D01*
Y651608D01*
X821125Y651942D01*
X821292Y652150D01*
X821625Y652233D01*
X821958Y652150D01*
X822167Y651900D01*
X822292Y651608D01*
Y650567D01*
G01Y651608D02*
X823500Y652233D01*
G01X823000Y653583D02*
X823292Y653833D01*
X823458Y654167D01*
X823500Y654542D01*
X823458Y654875D01*
X823250Y655208D01*
X823000Y655417D01*
X822750Y655458D01*
X822458Y655375D01*
X822250Y655083D01*
X822167Y654792D01*
Y654417D01*
G01Y654792D02*
X822042Y655042D01*
X821833Y655250D01*
X821583Y655333D01*
X821333Y655250D01*
X821125Y655042D01*
X821000Y654667D01*
X821042Y654292D01*
X821208Y653917D01*
G01X822458Y656808D02*
X822167Y657100D01*
X822000Y657350D01*
X821917Y657683D01*
X822000Y657975D01*
X822167Y658183D01*
X822417Y658350D01*
X822708Y658392D01*
X822958Y658350D01*
X823208Y658183D01*
X823417Y657933D01*
X823500Y657642D01*
X823417Y657308D01*
X823167Y657017D01*
X822792Y656850D01*
X822375Y656808D01*
X821833Y656892D01*
X821542Y657017D01*
X821250Y657225D01*
X821042Y657517D01*
X821000Y657808D01*
X821083Y658100D01*
X821292Y658308D01*
G01X822458Y659908D02*
X822167Y660200D01*
X822000Y660450D01*
X821917Y660783D01*
X822000Y661075D01*
X822167Y661283D01*
X822417Y661450D01*
X822708Y661492D01*
X822958Y661450D01*
X823208Y661283D01*
X823417Y661033D01*
X823500Y660742D01*
X823417Y660408D01*
X823167Y660117D01*
X822792Y659950D01*
X822375Y659908D01*
X821833Y659992D01*
X821542Y660117D01*
X821250Y660325D01*
X821042Y660617D01*
X821000Y660908D01*
X821083Y661200D01*
X821292Y661408D01*
G01X824100Y664700D02*
X828100D01*
Y672100D01*
G01X768017Y713000D02*
Y715500D01*
X769058D01*
X769392Y715375D01*
X769600Y715208D01*
X769683Y714875D01*
X769600Y714542D01*
X769350Y714333D01*
X769058Y714208D01*
X768017D01*
G01X769058D02*
X769683Y713000D01*
G01X772450D02*
Y715500D01*
X770908Y713708D01*
X772992D01*
G01X774133Y713500D02*
X774383Y713208D01*
X774717Y713042D01*
X775092Y713000D01*
X775425Y713042D01*
X775758Y713250D01*
X775967Y713500D01*
X776008Y713750D01*
X775925Y714042D01*
X775633Y714250D01*
X775342Y714333D01*
X774967D01*
G01X775342D02*
X775592Y714458D01*
X775800Y714667D01*
X775883Y714917D01*
X775800Y715167D01*
X775592Y715375D01*
X775217Y715500D01*
X774842Y715458D01*
X774467Y715292D01*
G01X778067Y713000D02*
X778150Y713542D01*
X778275Y714000D01*
X778442Y714417D01*
X778650Y714875D01*
X778983Y715500D01*
X777317D01*
G01X779699Y722050D02*
Y726050D01*
X772299D01*
G01X768017Y717000D02*
Y719500D01*
X769058D01*
X769392Y719375D01*
X769600Y719208D01*
X769683Y718875D01*
X769600Y718542D01*
X769350Y718333D01*
X769058Y718208D01*
X768017D01*
G01X769058D02*
X769683Y717000D01*
G01X772450D02*
Y719500D01*
X770908Y717708D01*
X772992D01*
G01X774133Y717500D02*
X774383Y717208D01*
X774717Y717042D01*
X775092Y717000D01*
X775425Y717042D01*
X775758Y717250D01*
X775967Y717500D01*
X776008Y717750D01*
X775925Y718042D01*
X775633Y718250D01*
X775342Y718333D01*
X774967D01*
G01X775342D02*
X775592Y718458D01*
X775800Y718667D01*
X775883Y718917D01*
X775800Y719167D01*
X775592Y719375D01*
X775217Y719500D01*
X774842Y719458D01*
X774467Y719292D01*
G01X777358Y718042D02*
X777650Y718333D01*
X777900Y718500D01*
X778233Y718583D01*
X778525Y718500D01*
X778733Y718333D01*
X778900Y718083D01*
X778942Y717792D01*
X778900Y717542D01*
X778733Y717292D01*
X778483Y717083D01*
X778192Y717000D01*
X777858Y717083D01*
X777567Y717333D01*
X777400Y717708D01*
X777358Y718125D01*
X777442Y718667D01*
X777567Y718958D01*
X777775Y719250D01*
X778067Y719458D01*
X778358Y719500D01*
X778650Y719417D01*
X778858Y719208D01*
G01X779699Y726550D02*
Y730550D01*
X772299D01*
G01X794499Y718533D02*
X796291D01*
X796666Y718700D01*
X796916Y719033D01*
X796999Y719450D01*
X796916Y719867D01*
X796666Y720200D01*
X796291Y720367D01*
X794499D01*
G01X796999Y722550D02*
X794499D01*
X794999Y722050D01*
G01X796999D02*
Y723050D01*
G01X794499Y725650D02*
X794582Y725317D01*
X794791Y725067D01*
X795041Y724900D01*
X795374Y724775D01*
X795749Y724733D01*
X796124Y724775D01*
X796457Y724900D01*
X796707Y725067D01*
X796916Y725317D01*
X796999Y725650D01*
X796916Y725983D01*
X796707Y726233D01*
X796457Y726400D01*
X796124Y726525D01*
X795749Y726567D01*
X795374Y726525D01*
X795041Y726400D01*
X794791Y726233D01*
X794582Y725983D01*
X794499Y725650D01*
G01X782499Y718850D02*
Y732250D01*
G01X792499Y718850D02*
X782499D01*
G01X792499Y732250D02*
Y718850D01*
G01X770396Y732382D02*
Y722382D01*
G01X813367Y727792D02*
X813117Y727917D01*
X812825Y728000D01*
X812492D01*
X812117Y727875D01*
X811825Y727667D01*
X811617Y727417D01*
X811450Y727000D01*
X811408Y726625D01*
X811492Y726250D01*
X811617Y726000D01*
X811867Y725750D01*
X812158Y725583D01*
X812450Y725500D01*
X812742D01*
X813033Y725583D01*
X813283Y725708D01*
X813492Y725875D01*
G01X815550Y725500D02*
Y728000D01*
X815050Y727500D01*
G01Y725500D02*
X816050D01*
G01X817733Y725875D02*
X817983Y725667D01*
X818275Y725542D01*
X818650Y725500D01*
X819025Y725583D01*
X819317Y725750D01*
X819525Y726042D01*
X819567Y726375D01*
X819483Y726708D01*
X819275Y726917D01*
X818983Y727083D01*
X818692Y727125D01*
X818400Y727083D01*
X818025Y726917D01*
X818150Y728000D01*
X819275D01*
G01X821042Y725792D02*
X821333Y725583D01*
X821667Y725500D01*
X822000Y725583D01*
X822292Y725833D01*
X822500Y726208D01*
X822583Y726583D01*
Y727042D01*
X822500Y727417D01*
X822292Y727750D01*
X822042Y727917D01*
X821750Y728000D01*
X821417Y727917D01*
X821167Y727750D01*
X821000Y727500D01*
X820917Y727167D01*
X821000Y726875D01*
X821208Y726583D01*
X821458Y726417D01*
X821750Y726375D01*
X822083Y726458D01*
X822333Y726667D01*
X822583Y727042D01*
G01X834499Y729850D02*
Y724350D01*
G01X826499D02*
Y729850D01*
G01Y712250D02*
Y717750D01*
G01X834499Y712250D02*
X826499D01*
G01X834499Y717750D02*
Y712250D01*
G01X830900Y657500D02*
X830567Y657542D01*
X830275Y657708D01*
X830025Y657958D01*
X829858Y658250D01*
X829775Y658583D01*
Y658917D01*
X829858Y659250D01*
X830025Y659542D01*
X830275Y659792D01*
X830567Y659958D01*
X830900Y660000D01*
X831233Y659958D01*
X831525Y659792D01*
X831775Y659542D01*
X831942Y659250D01*
X832025Y658917D01*
Y658583D01*
X831942Y658250D01*
X831775Y657958D01*
X831525Y657708D01*
X831233Y657542D01*
X830900Y657500D01*
G01X831233Y658167D02*
X831733Y657500D01*
G01X833083Y657875D02*
X833333Y657667D01*
X833625Y657542D01*
X834000Y657500D01*
X834375Y657583D01*
X834667Y657750D01*
X834875Y658042D01*
X834917Y658375D01*
X834833Y658708D01*
X834625Y658917D01*
X834333Y659083D01*
X834042Y659125D01*
X833750Y659083D01*
X833375Y658917D01*
X833500Y660000D01*
X834625D01*
G01X836183Y658000D02*
X836433Y657708D01*
X836767Y657542D01*
X837142Y657500D01*
X837475Y657542D01*
X837808Y657750D01*
X838017Y658000D01*
X838058Y658250D01*
X837975Y658542D01*
X837683Y658750D01*
X837392Y658833D01*
X837017D01*
G01X837392D02*
X837642Y658958D01*
X837850Y659167D01*
X837933Y659417D01*
X837850Y659667D01*
X837642Y659875D01*
X837267Y660000D01*
X836892Y659958D01*
X836517Y659792D01*
G01X828800Y666900D02*
X841800D01*
G01X828800Y680900D02*
Y666900D01*
G01X841800Y680900D02*
X828800D01*
G01X769000Y765000D02*
Y758000D01*
G01X767396Y734182D02*
Y745582D01*
G01X861499Y731050D02*
X835499D01*
G01X764000Y749300D02*
X768000D01*
Y756700D01*
G01X787016Y768050D02*
Y770550D01*
X788057D01*
X788391Y770425D01*
X788599Y770258D01*
X788682Y769925D01*
X788599Y769592D01*
X788349Y769383D01*
X788057Y769258D01*
X787016D01*
G01X788057D02*
X788682Y768050D01*
G01X791449D02*
Y770550D01*
X789907Y768758D01*
X791991D01*
G01X793132Y768550D02*
X793382Y768258D01*
X793716Y768092D01*
X794091Y768050D01*
X794424Y768092D01*
X794757Y768300D01*
X794966Y768550D01*
X795007Y768800D01*
X794924Y769092D01*
X794632Y769300D01*
X794341Y769383D01*
X793966D01*
G01X794341D02*
X794591Y769508D01*
X794799Y769717D01*
X794882Y769967D01*
X794799Y770217D01*
X794591Y770425D01*
X794216Y770550D01*
X793841Y770508D01*
X793466Y770342D01*
G01X797649Y768050D02*
Y770550D01*
X796107Y768758D01*
X798191D01*
G01X801199Y734050D02*
Y738050D01*
X793799D01*
G01X787016Y764050D02*
Y766550D01*
X788057D01*
X788391Y766425D01*
X788599Y766258D01*
X788682Y765925D01*
X788599Y765592D01*
X788349Y765383D01*
X788057Y765258D01*
X787016D01*
G01X788057D02*
X788682Y764050D01*
G01X791449D02*
Y766550D01*
X789907Y764758D01*
X791991D01*
G01X793132Y764550D02*
X793382Y764258D01*
X793716Y764092D01*
X794091Y764050D01*
X794424Y764092D01*
X794757Y764300D01*
X794966Y764550D01*
X795007Y764800D01*
X794924Y765092D01*
X794632Y765300D01*
X794341Y765383D01*
X793966D01*
G01X794341D02*
X794591Y765508D01*
X794799Y765717D01*
X794882Y765967D01*
X794799Y766217D01*
X794591Y766425D01*
X794216Y766550D01*
X793841Y766508D01*
X793466Y766342D01*
G01X796232Y764425D02*
X796482Y764217D01*
X796774Y764092D01*
X797149Y764050D01*
X797524Y764133D01*
X797816Y764300D01*
X798024Y764592D01*
X798066Y764925D01*
X797982Y765258D01*
X797774Y765467D01*
X797482Y765633D01*
X797191Y765675D01*
X796899Y765633D01*
X796524Y765467D01*
X796649Y766550D01*
X797774D01*
G01X801199Y730050D02*
Y734050D01*
X793799D01*
G01X768000Y736800D02*
X772000D01*
Y744200D01*
G01X782499Y732250D02*
X792499D01*
G01X786982Y775050D02*
Y773258D01*
X787149Y772883D01*
X787482Y772633D01*
X787899Y772550D01*
X788316Y772633D01*
X788649Y772883D01*
X788816Y773258D01*
Y775050D01*
G01X790999Y772550D02*
Y775050D01*
X790499Y774550D01*
G01Y772550D02*
X791499D01*
G01X794099D02*
Y775050D01*
X793599Y774550D01*
G01Y772550D02*
X794599D01*
G01X788696Y760682D02*
X786696Y758682D01*
X784696Y760682D01*
G01X781096D02*
Y741482D01*
X792296D01*
Y760682D01*
X781096D01*
G01X826499Y729850D02*
X834499D01*
G01X837504Y755249D02*
X837379Y754999D01*
X837296Y754707D01*
Y754374D01*
X837421Y753999D01*
X837629Y753707D01*
X837879Y753499D01*
X838296Y753332D01*
X838671Y753290D01*
X839046Y753374D01*
X839296Y753499D01*
X839546Y753749D01*
X839713Y754040D01*
X839796Y754332D01*
Y754624D01*
X839713Y754915D01*
X839588Y755165D01*
X839421Y755374D01*
G01X839796Y757432D02*
X837296D01*
X837796Y756932D01*
G01X839796D02*
Y757932D01*
G01X838754Y759740D02*
X838463Y760032D01*
X838296Y760282D01*
X838213Y760615D01*
X838296Y760907D01*
X838463Y761115D01*
X838713Y761282D01*
X839004Y761324D01*
X839254Y761282D01*
X839504Y761115D01*
X839713Y760865D01*
X839796Y760574D01*
X839713Y760240D01*
X839463Y759949D01*
X839088Y759782D01*
X838671Y759740D01*
X838129Y759824D01*
X837838Y759949D01*
X837546Y760157D01*
X837338Y760449D01*
X837296Y760740D01*
X837379Y761032D01*
X837588Y761240D01*
G01X837296Y763632D02*
X837379Y763299D01*
X837588Y763049D01*
X837838Y762882D01*
X838171Y762757D01*
X838546Y762715D01*
X838921Y762757D01*
X839254Y762882D01*
X839504Y763049D01*
X839713Y763299D01*
X839796Y763632D01*
X839713Y763965D01*
X839504Y764215D01*
X839254Y764382D01*
X838921Y764507D01*
X838546Y764549D01*
X838171Y764507D01*
X837838Y764382D01*
X837588Y764215D01*
X837379Y763965D01*
X837296Y763632D01*
G01X834796Y733282D02*
Y738782D01*
G01X842796Y733282D02*
X834796D01*
G01Y750882D02*
X842796D01*
G01X834796Y745382D02*
Y750882D01*
G01X827000Y1058517D02*
X824500D01*
Y1059558D01*
X824625Y1059892D01*
X824792Y1060100D01*
X825125Y1060183D01*
X825458Y1060100D01*
X825667Y1059850D01*
X825792Y1059558D01*
Y1058517D01*
G01Y1059558D02*
X827000Y1060183D01*
G01X826500Y1061533D02*
X826792Y1061783D01*
X826958Y1062117D01*
X827000Y1062492D01*
X826958Y1062825D01*
X826750Y1063158D01*
X826500Y1063367D01*
X826250Y1063408D01*
X825958Y1063325D01*
X825750Y1063033D01*
X825667Y1062742D01*
Y1062367D01*
G01Y1062742D02*
X825542Y1062992D01*
X825333Y1063200D01*
X825083Y1063283D01*
X824833Y1063200D01*
X824625Y1062992D01*
X824500Y1062617D01*
X824542Y1062242D01*
X824708Y1061867D01*
G01X825958Y1064758D02*
X825667Y1065050D01*
X825500Y1065300D01*
X825417Y1065633D01*
X825500Y1065925D01*
X825667Y1066133D01*
X825917Y1066300D01*
X826208Y1066342D01*
X826458Y1066300D01*
X826708Y1066133D01*
X826917Y1065883D01*
X827000Y1065592D01*
X826917Y1065258D01*
X826667Y1064967D01*
X826292Y1064800D01*
X825875Y1064758D01*
X825333Y1064842D01*
X825042Y1064967D01*
X824750Y1065175D01*
X824542Y1065467D01*
X824500Y1065758D01*
X824583Y1066050D01*
X824792Y1066258D01*
G01X826500Y1067733D02*
X826792Y1067983D01*
X826958Y1068317D01*
X827000Y1068692D01*
X826958Y1069025D01*
X826750Y1069358D01*
X826500Y1069567D01*
X826250Y1069608D01*
X825958Y1069525D01*
X825750Y1069233D01*
X825667Y1068942D01*
Y1068567D01*
G01Y1068942D02*
X825542Y1069192D01*
X825333Y1069400D01*
X825083Y1069483D01*
X824833Y1069400D01*
X824625Y1069192D01*
X824500Y1068817D01*
X824542Y1068442D01*
X824708Y1068067D01*
G01X810908Y1086367D02*
X810783Y1086117D01*
X810700Y1085825D01*
Y1085492D01*
X810825Y1085117D01*
X811033Y1084825D01*
X811283Y1084617D01*
X811700Y1084450D01*
X812075Y1084408D01*
X812450Y1084492D01*
X812700Y1084617D01*
X812950Y1084867D01*
X813117Y1085158D01*
X813200Y1085450D01*
Y1085742D01*
X813117Y1086033D01*
X812992Y1086283D01*
X812825Y1086492D01*
G01X812700Y1087633D02*
X812992Y1087883D01*
X813158Y1088217D01*
X813200Y1088592D01*
X813158Y1088925D01*
X812950Y1089258D01*
X812700Y1089467D01*
X812450Y1089508D01*
X812158Y1089425D01*
X811950Y1089133D01*
X811867Y1088842D01*
Y1088467D01*
G01Y1088842D02*
X811742Y1089092D01*
X811533Y1089300D01*
X811283Y1089383D01*
X811033Y1089300D01*
X810825Y1089092D01*
X810700Y1088717D01*
X810742Y1088342D01*
X810908Y1087967D01*
G01X812158Y1090858D02*
X811867Y1091150D01*
X811700Y1091400D01*
X811617Y1091733D01*
X811700Y1092025D01*
X811867Y1092233D01*
X812117Y1092400D01*
X812408Y1092442D01*
X812658Y1092400D01*
X812908Y1092233D01*
X813117Y1091983D01*
X813200Y1091692D01*
X813117Y1091358D01*
X812867Y1091067D01*
X812492Y1090900D01*
X812075Y1090858D01*
X811533Y1090942D01*
X811242Y1091067D01*
X810950Y1091275D01*
X810742Y1091567D01*
X810700Y1091858D01*
X810783Y1092150D01*
X810992Y1092358D01*
G01X812158Y1093958D02*
X811867Y1094250D01*
X811700Y1094500D01*
X811617Y1094833D01*
X811700Y1095125D01*
X811867Y1095333D01*
X812117Y1095500D01*
X812408Y1095542D01*
X812658Y1095500D01*
X812908Y1095333D01*
X813117Y1095083D01*
X813200Y1094792D01*
X813117Y1094458D01*
X812867Y1094167D01*
X812492Y1094000D01*
X812075Y1093958D01*
X811533Y1094042D01*
X811242Y1094167D01*
X810950Y1094375D01*
X810742Y1094667D01*
X810700Y1094958D01*
X810783Y1095250D01*
X810992Y1095458D01*
G01X773208Y1104767D02*
X773083Y1104517D01*
X773000Y1104225D01*
Y1103892D01*
X773125Y1103517D01*
X773333Y1103225D01*
X773583Y1103017D01*
X774000Y1102850D01*
X774375Y1102808D01*
X774750Y1102892D01*
X775000Y1103017D01*
X775250Y1103267D01*
X775417Y1103558D01*
X775500Y1103850D01*
Y1104142D01*
X775417Y1104433D01*
X775292Y1104683D01*
X775125Y1104892D01*
G01X775500Y1106950D02*
X773000D01*
X773500Y1106450D01*
G01X775500D02*
Y1107450D01*
G01X775000Y1109133D02*
X775292Y1109383D01*
X775458Y1109717D01*
X775500Y1110092D01*
X775458Y1110425D01*
X775250Y1110758D01*
X775000Y1110967D01*
X774750Y1111008D01*
X774458Y1110925D01*
X774250Y1110633D01*
X774167Y1110342D01*
Y1109967D01*
G01Y1110342D02*
X774042Y1110592D01*
X773833Y1110800D01*
X773583Y1110883D01*
X773333Y1110800D01*
X773125Y1110592D01*
X773000Y1110217D01*
X773042Y1109842D01*
X773208Y1109467D01*
G01X775000Y1112233D02*
X775292Y1112483D01*
X775458Y1112817D01*
X775500Y1113192D01*
X775458Y1113525D01*
X775250Y1113858D01*
X775000Y1114067D01*
X774750Y1114108D01*
X774458Y1114025D01*
X774250Y1113733D01*
X774167Y1113442D01*
Y1113067D01*
G01Y1113442D02*
X774042Y1113692D01*
X773833Y1113900D01*
X773583Y1113983D01*
X773333Y1113900D01*
X773125Y1113692D01*
X773000Y1113317D01*
X773042Y1112942D01*
X773208Y1112567D01*
G01X767199Y1138350D02*
Y1149750D01*
G01X807500Y1064400D02*
X807458Y1064067D01*
X807292Y1063775D01*
X807042Y1063525D01*
X806750Y1063358D01*
X806417Y1063275D01*
X806083D01*
X805750Y1063358D01*
X805458Y1063525D01*
X805208Y1063775D01*
X805042Y1064067D01*
X805000Y1064400D01*
X805042Y1064733D01*
X805208Y1065025D01*
X805458Y1065275D01*
X805750Y1065442D01*
X806083Y1065525D01*
X806417D01*
X806750Y1065442D01*
X807042Y1065275D01*
X807292Y1065025D01*
X807458Y1064733D01*
X807500Y1064400D01*
G01X806833Y1064733D02*
X807500Y1065233D01*
G01X807000Y1066583D02*
X807292Y1066833D01*
X807458Y1067167D01*
X807500Y1067542D01*
X807458Y1067875D01*
X807250Y1068208D01*
X807000Y1068417D01*
X806750Y1068458D01*
X806458Y1068375D01*
X806250Y1068083D01*
X806167Y1067792D01*
Y1067417D01*
G01Y1067792D02*
X806042Y1068042D01*
X805833Y1068250D01*
X805583Y1068333D01*
X805333Y1068250D01*
X805125Y1068042D01*
X805000Y1067667D01*
X805042Y1067292D01*
X805208Y1066917D01*
G01X807000Y1069683D02*
X807292Y1069933D01*
X807458Y1070267D01*
X807500Y1070642D01*
X807458Y1070975D01*
X807250Y1071308D01*
X807000Y1071517D01*
X806750Y1071558D01*
X806458Y1071475D01*
X806250Y1071183D01*
X806167Y1070892D01*
Y1070517D01*
G01Y1070892D02*
X806042Y1071142D01*
X805833Y1071350D01*
X805583Y1071433D01*
X805333Y1071350D01*
X805125Y1071142D01*
X805000Y1070767D01*
X805042Y1070392D01*
X805208Y1070017D01*
G01X809900Y1078600D02*
Y1067200D01*
G01X823300Y1078600D02*
X809900D01*
G01X823300Y1067200D02*
Y1078600D01*
G01X809900Y1067200D02*
X823300D01*
G01X791450Y1108500D02*
X791117Y1108542D01*
X790825Y1108708D01*
X790575Y1108958D01*
X790408Y1109250D01*
X790325Y1109583D01*
Y1109917D01*
X790408Y1110250D01*
X790575Y1110542D01*
X790825Y1110792D01*
X791117Y1110958D01*
X791450Y1111000D01*
X791783Y1110958D01*
X792075Y1110792D01*
X792325Y1110542D01*
X792492Y1110250D01*
X792575Y1109917D01*
Y1109583D01*
X792492Y1109250D01*
X792325Y1108958D01*
X792075Y1108708D01*
X791783Y1108542D01*
X791450Y1108500D01*
G01X791783Y1109167D02*
X792283Y1108500D01*
G01X793633Y1108875D02*
X793883Y1108667D01*
X794175Y1108542D01*
X794550Y1108500D01*
X794925Y1108583D01*
X795217Y1108750D01*
X795425Y1109042D01*
X795467Y1109375D01*
X795383Y1109708D01*
X795175Y1109917D01*
X794883Y1110083D01*
X794592Y1110125D01*
X794300Y1110083D01*
X793925Y1109917D01*
X794050Y1111000D01*
X795175D01*
G01X808841Y1098016D02*
X810641Y1100116D01*
X812841Y1098016D01*
G01X816441Y1097916D02*
Y1117116D01*
X805241D01*
Y1097916D01*
X816441D01*
Y1098316D01*
G01X832583Y1103192D02*
Y1090192D01*
G01X858583Y1103192D02*
X832583D01*
G01Y1090192D02*
X858583D01*
G01X835999Y1136050D02*
Y1123050D01*
G01X861999Y1136050D02*
X835999D01*
G01Y1123050D02*
X861999D01*
G01X839517Y1067500D02*
Y1070000D01*
X840558D01*
X840892Y1069875D01*
X841100Y1069708D01*
X841183Y1069375D01*
X841100Y1069042D01*
X840850Y1068833D01*
X840558Y1068708D01*
X839517D01*
G01X840558D02*
X841183Y1067500D01*
G01X843450D02*
Y1070000D01*
X842950Y1069500D01*
G01Y1067500D02*
X843950D01*
G01X845633Y1068000D02*
X845883Y1067708D01*
X846217Y1067542D01*
X846592Y1067500D01*
X846925Y1067542D01*
X847258Y1067750D01*
X847467Y1068000D01*
X847508Y1068250D01*
X847425Y1068542D01*
X847133Y1068750D01*
X846842Y1068833D01*
X846467D01*
G01X846842D02*
X847092Y1068958D01*
X847300Y1069167D01*
X847383Y1069417D01*
X847300Y1069667D01*
X847092Y1069875D01*
X846717Y1070000D01*
X846342Y1069958D01*
X845967Y1069792D01*
G01X848733Y1068000D02*
X848983Y1067708D01*
X849317Y1067542D01*
X849692Y1067500D01*
X850025Y1067542D01*
X850358Y1067750D01*
X850567Y1068000D01*
X850608Y1068250D01*
X850525Y1068542D01*
X850233Y1068750D01*
X849942Y1068833D01*
X849567D01*
G01X849942D02*
X850192Y1068958D01*
X850400Y1069167D01*
X850483Y1069417D01*
X850400Y1069667D01*
X850192Y1069875D01*
X849817Y1070000D01*
X849442Y1069958D01*
X849067Y1069792D01*
G01X839517Y1063500D02*
Y1066000D01*
X840558D01*
X840892Y1065875D01*
X841100Y1065708D01*
X841183Y1065375D01*
X841100Y1065042D01*
X840850Y1064833D01*
X840558Y1064708D01*
X839517D01*
G01X840558D02*
X841183Y1063500D01*
G01X842533Y1064000D02*
X842783Y1063708D01*
X843117Y1063542D01*
X843492Y1063500D01*
X843825Y1063542D01*
X844158Y1063750D01*
X844367Y1064000D01*
X844408Y1064250D01*
X844325Y1064542D01*
X844033Y1064750D01*
X843742Y1064833D01*
X843367D01*
G01X843742D02*
X843992Y1064958D01*
X844200Y1065167D01*
X844283Y1065417D01*
X844200Y1065667D01*
X843992Y1065875D01*
X843617Y1066000D01*
X843242Y1065958D01*
X842867Y1065792D01*
G01X845758Y1064542D02*
X846050Y1064833D01*
X846300Y1065000D01*
X846633Y1065083D01*
X846925Y1065000D01*
X847133Y1064833D01*
X847300Y1064583D01*
X847342Y1064292D01*
X847300Y1064042D01*
X847133Y1063792D01*
X846883Y1063583D01*
X846592Y1063500D01*
X846258Y1063583D01*
X845967Y1063833D01*
X845800Y1064208D01*
X845758Y1064625D01*
X845842Y1065167D01*
X845967Y1065458D01*
X846175Y1065750D01*
X846467Y1065958D01*
X846758Y1066000D01*
X847050Y1065917D01*
X847258Y1065708D01*
G01X848733Y1063875D02*
X848983Y1063667D01*
X849275Y1063542D01*
X849650Y1063500D01*
X850025Y1063583D01*
X850317Y1063750D01*
X850525Y1064042D01*
X850567Y1064375D01*
X850483Y1064708D01*
X850275Y1064917D01*
X849983Y1065083D01*
X849692Y1065125D01*
X849400Y1065083D01*
X849025Y1064917D01*
X849150Y1066000D01*
X850275D01*
G01X827700Y1081200D02*
X823700D01*
Y1073800D01*
G01X801199Y1131050D02*
Y1135050D01*
X793799D01*
G01X801199D02*
Y1139050D01*
X793799D01*
G01X780699Y1125550D02*
Y1129550D01*
X773299D01*
G01X780699Y1121550D02*
Y1125550D01*
X773299D01*
G01X767500Y1139800D02*
X771500D01*
Y1147200D01*
G01X794499Y1123083D02*
X796291D01*
X796666Y1123250D01*
X796916Y1123583D01*
X796999Y1124000D01*
X796916Y1124417D01*
X796666Y1124750D01*
X796291Y1124917D01*
X794499D01*
G01X796999Y1127017D02*
X796457Y1127100D01*
X795999Y1127225D01*
X795582Y1127392D01*
X795124Y1127600D01*
X794499Y1127933D01*
Y1126267D01*
G01X781999Y1121850D02*
Y1135250D01*
G01X791999Y1121850D02*
X781999D01*
G01X791999Y1135250D02*
Y1121850D01*
G01X781999Y1135250D02*
X791999D01*
G01X770533Y1133892D02*
Y1123892D01*
G01X781233Y1162192D02*
Y1142992D01*
X792433D01*
Y1162192D01*
X781233D01*
G01X792350Y1089000D02*
Y1086500D01*
G01X791392Y1089000D02*
X793308D01*
G01X794617Y1086500D02*
Y1089000D01*
X795617D01*
X795950Y1088875D01*
X796200Y1088583D01*
X796283Y1088250D01*
X796200Y1087917D01*
X795992Y1087667D01*
X795617Y1087542D01*
X794617D01*
G01X797758Y1088583D02*
X798008Y1088833D01*
X798300Y1088958D01*
X798633Y1089000D01*
X799050Y1088917D01*
X799342Y1088708D01*
X799425Y1088458D01*
X799383Y1088208D01*
X799217Y1088000D01*
X798383Y1087583D01*
X798008Y1087292D01*
X797758Y1086875D01*
X797675Y1086500D01*
X799425D01*
G01X801567D02*
X801650Y1087042D01*
X801775Y1087500D01*
X801942Y1087917D01*
X802150Y1088375D01*
X802483Y1089000D01*
X800817D01*
G01X814067Y1133192D02*
X813817Y1133317D01*
X813525Y1133400D01*
X813192D01*
X812817Y1133275D01*
X812525Y1133067D01*
X812317Y1132817D01*
X812150Y1132400D01*
X812108Y1132025D01*
X812192Y1131650D01*
X812317Y1131400D01*
X812567Y1131150D01*
X812858Y1130983D01*
X813150Y1130900D01*
X813442D01*
X813733Y1130983D01*
X813983Y1131108D01*
X814192Y1131275D01*
G01X816250Y1130900D02*
Y1133400D01*
X815750Y1132900D01*
G01Y1130900D02*
X816750D01*
G01X819850D02*
Y1133400D01*
X818308Y1131608D01*
X820392D01*
G01X821658Y1132983D02*
X821908Y1133233D01*
X822200Y1133358D01*
X822533Y1133400D01*
X822950Y1133317D01*
X823242Y1133108D01*
X823325Y1132858D01*
X823283Y1132608D01*
X823117Y1132400D01*
X822283Y1131983D01*
X821908Y1131692D01*
X821658Y1131275D01*
X821575Y1130900D01*
X823325D01*
G01X834499Y1133850D02*
Y1128350D01*
G01X826499Y1133850D02*
X834499D01*
G01X826499Y1128350D02*
Y1133850D01*
G01Y1116250D02*
Y1121750D01*
G01X834499Y1116250D02*
X826499D01*
G01X834499Y1121750D02*
Y1116250D01*
G01X834833Y1138092D02*
Y1143592D01*
G01X842833Y1138092D02*
X834833D01*
G01X830400Y1062000D02*
X830067Y1062042D01*
X829775Y1062208D01*
X829525Y1062458D01*
X829358Y1062750D01*
X829275Y1063083D01*
Y1063417D01*
X829358Y1063750D01*
X829525Y1064042D01*
X829775Y1064292D01*
X830067Y1064458D01*
X830400Y1064500D01*
X830733Y1064458D01*
X831025Y1064292D01*
X831275Y1064042D01*
X831442Y1063750D01*
X831525Y1063417D01*
Y1063083D01*
X831442Y1062750D01*
X831275Y1062458D01*
X831025Y1062208D01*
X830733Y1062042D01*
X830400Y1062000D01*
G01X830733Y1062667D02*
X831233Y1062000D01*
G01X832583Y1062375D02*
X832833Y1062167D01*
X833125Y1062042D01*
X833500Y1062000D01*
X833875Y1062083D01*
X834167Y1062250D01*
X834375Y1062542D01*
X834417Y1062875D01*
X834333Y1063208D01*
X834125Y1063417D01*
X833833Y1063583D01*
X833542Y1063625D01*
X833250Y1063583D01*
X832875Y1063417D01*
X833000Y1064500D01*
X834125D01*
G01X836600Y1062000D02*
Y1064500D01*
X836100Y1064000D01*
G01Y1062000D02*
X837100D01*
G01X828500Y1072500D02*
X841500D01*
G01X828500Y1086500D02*
Y1072500D01*
G01X841500Y1086500D02*
X828500D01*
G01X765900Y1168300D02*
Y1161300D01*
G01X761000Y1153300D02*
X765000D01*
Y1160700D01*
G01X788016Y1165550D02*
Y1168050D01*
X789057D01*
X789391Y1167925D01*
X789599Y1167758D01*
X789682Y1167425D01*
X789599Y1167092D01*
X789349Y1166883D01*
X789057Y1166758D01*
X788016D01*
G01X789057D02*
X789682Y1165550D01*
G01X792449D02*
Y1168050D01*
X790907Y1166258D01*
X792991D01*
G01X794132Y1166050D02*
X794382Y1165758D01*
X794716Y1165592D01*
X795091Y1165550D01*
X795424Y1165592D01*
X795757Y1165800D01*
X795966Y1166050D01*
X796007Y1166300D01*
X795924Y1166592D01*
X795632Y1166800D01*
X795341Y1166883D01*
X794966D01*
G01X795341D02*
X795591Y1167008D01*
X795799Y1167217D01*
X795882Y1167467D01*
X795799Y1167717D01*
X795591Y1167925D01*
X795216Y1168050D01*
X794841Y1168008D01*
X794466Y1167842D01*
G01X798149Y1168050D02*
X797816Y1167967D01*
X797566Y1167758D01*
X797399Y1167508D01*
X797274Y1167175D01*
X797232Y1166800D01*
X797274Y1166425D01*
X797399Y1166092D01*
X797566Y1165842D01*
X797816Y1165633D01*
X798149Y1165550D01*
X798482Y1165633D01*
X798732Y1165842D01*
X798899Y1166092D01*
X799024Y1166425D01*
X799066Y1166800D01*
X799024Y1167175D01*
X798899Y1167508D01*
X798732Y1167758D01*
X798482Y1167967D01*
X798149Y1168050D01*
G01X788016Y1169550D02*
Y1172050D01*
X789057D01*
X789391Y1171925D01*
X789599Y1171758D01*
X789682Y1171425D01*
X789599Y1171092D01*
X789349Y1170883D01*
X789057Y1170758D01*
X788016D01*
G01X789057D02*
X789682Y1169550D01*
G01X792449D02*
Y1172050D01*
X790907Y1170258D01*
X792991D01*
G01X794132Y1170050D02*
X794382Y1169758D01*
X794716Y1169592D01*
X795091Y1169550D01*
X795424Y1169592D01*
X795757Y1169800D01*
X795966Y1170050D01*
X796007Y1170300D01*
X795924Y1170592D01*
X795632Y1170800D01*
X795341Y1170883D01*
X794966D01*
G01X795341D02*
X795591Y1171008D01*
X795799Y1171217D01*
X795882Y1171467D01*
X795799Y1171717D01*
X795591Y1171925D01*
X795216Y1172050D01*
X794841Y1172008D01*
X794466Y1171842D01*
G01X798149Y1169550D02*
Y1172050D01*
X797649Y1171550D01*
G01Y1169550D02*
X798649D01*
G01X788033Y1176500D02*
Y1174708D01*
X788200Y1174333D01*
X788533Y1174083D01*
X788950Y1174000D01*
X789367Y1174083D01*
X789700Y1174333D01*
X789867Y1174708D01*
Y1176500D01*
G01X792050Y1174000D02*
X792342Y1174042D01*
X792675Y1174167D01*
X792883Y1174375D01*
X792967Y1174667D01*
X792883Y1174958D01*
X792633Y1175208D01*
X792258Y1175333D01*
X791842D01*
X791592Y1175417D01*
X791383Y1175625D01*
X791300Y1175917D01*
X791425Y1176208D01*
X791717Y1176417D01*
X792050Y1176500D01*
X792383Y1176417D01*
X792675Y1176208D01*
X792800Y1175917D01*
X792717Y1175625D01*
X792508Y1175417D01*
X792258Y1175333D01*
X791842D01*
X791467Y1175208D01*
X791217Y1174958D01*
X791133Y1174667D01*
X791217Y1174375D01*
X791425Y1174167D01*
X791758Y1174042D01*
X792050Y1174000D01*
G01X788833Y1162192D02*
X786833Y1160192D01*
X784833Y1162192D01*
G01X837541Y1160059D02*
X837416Y1159809D01*
X837333Y1159517D01*
Y1159184D01*
X837458Y1158809D01*
X837666Y1158517D01*
X837916Y1158309D01*
X838333Y1158142D01*
X838708Y1158100D01*
X839083Y1158184D01*
X839333Y1158309D01*
X839583Y1158559D01*
X839750Y1158850D01*
X839833Y1159142D01*
Y1159434D01*
X839750Y1159725D01*
X839625Y1159975D01*
X839458Y1160184D01*
G01X839833Y1162242D02*
X837333D01*
X837833Y1161742D01*
G01X839833D02*
Y1162742D01*
G01Y1165842D02*
X837333D01*
X839125Y1164300D01*
Y1166384D01*
G01X839333Y1167525D02*
X839625Y1167775D01*
X839791Y1168109D01*
X839833Y1168484D01*
X839791Y1168817D01*
X839583Y1169150D01*
X839333Y1169359D01*
X839083Y1169400D01*
X838791Y1169317D01*
X838583Y1169025D01*
X838500Y1168734D01*
Y1168359D01*
G01Y1168734D02*
X838375Y1168984D01*
X838166Y1169192D01*
X837916Y1169275D01*
X837666Y1169192D01*
X837458Y1168984D01*
X837333Y1168609D01*
X837375Y1168234D01*
X837541Y1167859D01*
G01X834833Y1155692D02*
X842833D01*
G01X834833Y1150192D02*
Y1155692D01*
G01X798500Y1473400D02*
X798458Y1473067D01*
X798292Y1472775D01*
X798042Y1472525D01*
X797750Y1472358D01*
X797417Y1472275D01*
X797083D01*
X796750Y1472358D01*
X796458Y1472525D01*
X796208Y1472775D01*
X796042Y1473067D01*
X796000Y1473400D01*
X796042Y1473733D01*
X796208Y1474025D01*
X796458Y1474275D01*
X796750Y1474442D01*
X797083Y1474525D01*
X797417D01*
X797750Y1474442D01*
X798042Y1474275D01*
X798292Y1474025D01*
X798458Y1473733D01*
X798500Y1473400D01*
G01X797833Y1473733D02*
X798500Y1474233D01*
G01X798000Y1475583D02*
X798292Y1475833D01*
X798458Y1476167D01*
X798500Y1476542D01*
X798458Y1476875D01*
X798250Y1477208D01*
X798000Y1477417D01*
X797750Y1477458D01*
X797458Y1477375D01*
X797250Y1477083D01*
X797167Y1476792D01*
Y1476417D01*
G01Y1476792D02*
X797042Y1477042D01*
X796833Y1477250D01*
X796583Y1477333D01*
X796333Y1477250D01*
X796125Y1477042D01*
X796000Y1476667D01*
X796042Y1476292D01*
X796208Y1475917D01*
G01X796417Y1478808D02*
X796167Y1479058D01*
X796042Y1479350D01*
X796000Y1479683D01*
X796083Y1480100D01*
X796292Y1480392D01*
X796542Y1480475D01*
X796792Y1480433D01*
X797000Y1480267D01*
X797417Y1479433D01*
X797708Y1479058D01*
X798125Y1478808D01*
X798500Y1478725D01*
Y1480475D01*
G01X802500Y1472567D02*
X800000D01*
Y1473608D01*
X800125Y1473942D01*
X800292Y1474150D01*
X800625Y1474233D01*
X800958Y1474150D01*
X801167Y1473900D01*
X801292Y1473608D01*
Y1472567D01*
G01Y1473608D02*
X802500Y1474233D01*
G01X802000Y1475583D02*
X802292Y1475833D01*
X802458Y1476167D01*
X802500Y1476542D01*
X802458Y1476875D01*
X802250Y1477208D01*
X802000Y1477417D01*
X801750Y1477458D01*
X801458Y1477375D01*
X801250Y1477083D01*
X801167Y1476792D01*
Y1476417D01*
G01Y1476792D02*
X801042Y1477042D01*
X800833Y1477250D01*
X800583Y1477333D01*
X800333Y1477250D01*
X800125Y1477042D01*
X800000Y1476667D01*
X800042Y1476292D01*
X800208Y1475917D01*
G01X802500Y1480100D02*
X800000D01*
X801792Y1478558D01*
Y1480642D01*
G01X802500Y1483200D02*
X800000D01*
X801792Y1481658D01*
Y1483742D01*
G01X826400Y1470500D02*
X826067Y1470542D01*
X825775Y1470708D01*
X825525Y1470958D01*
X825358Y1471250D01*
X825275Y1471583D01*
Y1471917D01*
X825358Y1472250D01*
X825525Y1472542D01*
X825775Y1472792D01*
X826067Y1472958D01*
X826400Y1473000D01*
X826733Y1472958D01*
X827025Y1472792D01*
X827275Y1472542D01*
X827442Y1472250D01*
X827525Y1471917D01*
Y1471583D01*
X827442Y1471250D01*
X827275Y1470958D01*
X827025Y1470708D01*
X826733Y1470542D01*
X826400Y1470500D01*
G01X826733Y1471167D02*
X827233Y1470500D01*
G01X828583Y1470875D02*
X828833Y1470667D01*
X829125Y1470542D01*
X829500Y1470500D01*
X829875Y1470583D01*
X830167Y1470750D01*
X830375Y1471042D01*
X830417Y1471375D01*
X830333Y1471708D01*
X830125Y1471917D01*
X829833Y1472083D01*
X829542Y1472125D01*
X829250Y1472083D01*
X828875Y1471917D01*
X829000Y1473000D01*
X830125D01*
G01X832600D02*
X832267Y1472917D01*
X832017Y1472708D01*
X831850Y1472458D01*
X831725Y1472125D01*
X831683Y1471750D01*
X831725Y1471375D01*
X831850Y1471042D01*
X832017Y1470792D01*
X832267Y1470583D01*
X832600Y1470500D01*
X832933Y1470583D01*
X833183Y1470792D01*
X833350Y1471042D01*
X833475Y1471375D01*
X833517Y1471750D01*
X833475Y1472125D01*
X833350Y1472458D01*
X833183Y1472708D01*
X832933Y1472917D01*
X832600Y1473000D01*
G01X807708Y1489267D02*
X807583Y1489017D01*
X807500Y1488725D01*
Y1488392D01*
X807625Y1488017D01*
X807833Y1487725D01*
X808083Y1487517D01*
X808500Y1487350D01*
X808875Y1487308D01*
X809250Y1487392D01*
X809500Y1487517D01*
X809750Y1487767D01*
X809917Y1488058D01*
X810000Y1488350D01*
Y1488642D01*
X809917Y1488933D01*
X809792Y1489183D01*
X809625Y1489392D01*
G01X809500Y1490533D02*
X809792Y1490783D01*
X809958Y1491117D01*
X810000Y1491492D01*
X809958Y1491825D01*
X809750Y1492158D01*
X809500Y1492367D01*
X809250Y1492408D01*
X808958Y1492325D01*
X808750Y1492033D01*
X808667Y1491742D01*
Y1491367D01*
G01Y1491742D02*
X808542Y1491992D01*
X808333Y1492200D01*
X808083Y1492283D01*
X807833Y1492200D01*
X807625Y1491992D01*
X807500Y1491617D01*
X807542Y1491242D01*
X807708Y1490867D01*
G01X808958Y1493758D02*
X808667Y1494050D01*
X808500Y1494300D01*
X808417Y1494633D01*
X808500Y1494925D01*
X808667Y1495133D01*
X808917Y1495300D01*
X809208Y1495342D01*
X809458Y1495300D01*
X809708Y1495133D01*
X809917Y1494883D01*
X810000Y1494592D01*
X809917Y1494258D01*
X809667Y1493967D01*
X809292Y1493800D01*
X808875Y1493758D01*
X808333Y1493842D01*
X808042Y1493967D01*
X807750Y1494175D01*
X807542Y1494467D01*
X807500Y1494758D01*
X807583Y1495050D01*
X807792Y1495258D01*
G01X809625Y1496733D02*
X809833Y1496983D01*
X809958Y1497275D01*
X810000Y1497650D01*
X809917Y1498025D01*
X809750Y1498317D01*
X809458Y1498525D01*
X809125Y1498567D01*
X808792Y1498483D01*
X808583Y1498275D01*
X808417Y1497983D01*
X808375Y1497692D01*
X808417Y1497400D01*
X808583Y1497025D01*
X807500Y1497150D01*
Y1498275D01*
G01X777708Y1510767D02*
X777583Y1510517D01*
X777500Y1510225D01*
Y1509892D01*
X777625Y1509517D01*
X777833Y1509225D01*
X778083Y1509017D01*
X778500Y1508850D01*
X778875Y1508808D01*
X779250Y1508892D01*
X779500Y1509017D01*
X779750Y1509267D01*
X779917Y1509558D01*
X780000Y1509850D01*
Y1510142D01*
X779917Y1510433D01*
X779792Y1510683D01*
X779625Y1510892D01*
G01X780000Y1512950D02*
X777500D01*
X778000Y1512450D01*
G01X780000D02*
Y1513450D01*
G01X777917Y1515258D02*
X777667Y1515508D01*
X777542Y1515800D01*
X777500Y1516133D01*
X777583Y1516550D01*
X777792Y1516842D01*
X778042Y1516925D01*
X778292Y1516883D01*
X778500Y1516717D01*
X778917Y1515883D01*
X779208Y1515508D01*
X779625Y1515258D01*
X780000Y1515175D01*
Y1516925D01*
G01X779625Y1518233D02*
X779833Y1518483D01*
X779958Y1518775D01*
X780000Y1519150D01*
X779917Y1519525D01*
X779750Y1519817D01*
X779458Y1520025D01*
X779125Y1520067D01*
X778792Y1519983D01*
X778583Y1519775D01*
X778417Y1519483D01*
X778375Y1519192D01*
X778417Y1518900D01*
X778583Y1518525D01*
X777500Y1518650D01*
Y1519775D01*
G01X769527Y1541096D02*
Y1552496D01*
G01X811700Y1486300D02*
Y1474900D01*
G01X825100Y1486300D02*
X811700D01*
G01X825100Y1474900D02*
Y1486300D01*
G01X811700Y1474900D02*
X825100D01*
G01X791950Y1513500D02*
X791617Y1513542D01*
X791325Y1513708D01*
X791075Y1513958D01*
X790908Y1514250D01*
X790825Y1514583D01*
Y1514917D01*
X790908Y1515250D01*
X791075Y1515542D01*
X791325Y1515792D01*
X791617Y1515958D01*
X791950Y1516000D01*
X792283Y1515958D01*
X792575Y1515792D01*
X792825Y1515542D01*
X792992Y1515250D01*
X793075Y1514917D01*
Y1514583D01*
X792992Y1514250D01*
X792825Y1513958D01*
X792575Y1513708D01*
X792283Y1513542D01*
X791950Y1513500D01*
G01X792283Y1514167D02*
X792783Y1513500D01*
G01X794133Y1514000D02*
X794383Y1513708D01*
X794717Y1513542D01*
X795092Y1513500D01*
X795425Y1513542D01*
X795758Y1513750D01*
X795967Y1514000D01*
X796008Y1514250D01*
X795925Y1514542D01*
X795633Y1514750D01*
X795342Y1514833D01*
X794967D01*
G01X795342D02*
X795592Y1514958D01*
X795800Y1515167D01*
X795883Y1515417D01*
X795800Y1515667D01*
X795592Y1515875D01*
X795217Y1516000D01*
X794842Y1515958D01*
X794467Y1515792D01*
G01X810245Y1500522D02*
X812045Y1502622D01*
X814245Y1500522D01*
G01X817845Y1500422D02*
Y1519622D01*
X806645D01*
Y1500422D01*
X817845D01*
Y1500822D01*
G01X834327Y1508096D02*
Y1495096D01*
G01X860327Y1508096D02*
X834327D01*
G01Y1495096D02*
X860327D01*
G01X838827Y1540796D02*
Y1527796D01*
G01X864827Y1540796D02*
X838827D01*
G01Y1527796D02*
X864827D01*
G01X764500Y1556300D02*
X768500D01*
Y1563700D01*
G01X829700Y1486100D02*
X825700D01*
Y1478700D01*
G01X806198Y1537793D02*
Y1540293D01*
X807239D01*
X807573Y1540168D01*
X807781Y1540001D01*
X807864Y1539668D01*
X807781Y1539335D01*
X807531Y1539126D01*
X807239Y1539001D01*
X806198D01*
G01X807239D02*
X807864Y1537793D01*
G01X810631D02*
Y1540293D01*
X809089Y1538501D01*
X811173D01*
G01X812439Y1539876D02*
X812689Y1540126D01*
X812981Y1540251D01*
X813314Y1540293D01*
X813731Y1540210D01*
X814023Y1540001D01*
X814106Y1539751D01*
X814064Y1539501D01*
X813898Y1539293D01*
X813064Y1538876D01*
X812689Y1538585D01*
X812439Y1538168D01*
X812356Y1537793D01*
X814106D01*
G01X815539Y1538835D02*
X815831Y1539126D01*
X816081Y1539293D01*
X816414Y1539376D01*
X816706Y1539293D01*
X816914Y1539126D01*
X817081Y1538876D01*
X817123Y1538585D01*
X817081Y1538335D01*
X816914Y1538085D01*
X816664Y1537876D01*
X816373Y1537793D01*
X816039Y1537876D01*
X815748Y1538126D01*
X815581Y1538501D01*
X815539Y1538918D01*
X815623Y1539460D01*
X815748Y1539751D01*
X815956Y1540043D01*
X816248Y1540251D01*
X816539Y1540293D01*
X816831Y1540210D01*
X817039Y1540001D01*
G01X803881Y1536893D02*
Y1540893D01*
X796481D01*
G01X806198Y1541793D02*
Y1544293D01*
X807239D01*
X807573Y1544168D01*
X807781Y1544001D01*
X807864Y1543668D01*
X807781Y1543335D01*
X807531Y1543126D01*
X807239Y1543001D01*
X806198D01*
G01X807239D02*
X807864Y1541793D01*
G01X810631D02*
Y1544293D01*
X809089Y1542501D01*
X811173D01*
G01X812439Y1543876D02*
X812689Y1544126D01*
X812981Y1544251D01*
X813314Y1544293D01*
X813731Y1544210D01*
X814023Y1544001D01*
X814106Y1543751D01*
X814064Y1543501D01*
X813898Y1543293D01*
X813064Y1542876D01*
X812689Y1542585D01*
X812439Y1542168D01*
X812356Y1541793D01*
X814106D01*
G01X816248D02*
X816331Y1542335D01*
X816456Y1542793D01*
X816623Y1543210D01*
X816831Y1543668D01*
X817164Y1544293D01*
X815498D01*
G01X803881Y1540893D02*
Y1544893D01*
X796481D01*
G01X782881Y1525893D02*
Y1529893D01*
X775481D01*
G01X782881D02*
Y1533893D01*
X775481D01*
G01X770000Y1543800D02*
X774000D01*
Y1551200D01*
G01X797999Y1527083D02*
X799791D01*
X800166Y1527250D01*
X800416Y1527583D01*
X800499Y1528000D01*
X800416Y1528417D01*
X800166Y1528750D01*
X799791Y1528917D01*
X797999D01*
G01X800499Y1531600D02*
X797999D01*
X799791Y1530058D01*
Y1532142D01*
G01X785253Y1525678D02*
Y1539078D01*
G01X795253Y1525678D02*
X785253D01*
G01X795253Y1539078D02*
Y1525678D01*
G01X785253Y1539078D02*
X795253D01*
G01X760127Y1538796D02*
X773527D01*
G01X760127Y1528796D02*
Y1538796D01*
G01X773527Y1528796D02*
X760127D01*
G01X773527Y1538796D02*
Y1528796D01*
G01X783727Y1567096D02*
Y1547896D01*
X794927D01*
Y1567096D01*
X783727D01*
G01X788350Y1498000D02*
Y1495500D01*
G01X787392Y1498000D02*
X789308D01*
G01X790617Y1495500D02*
Y1498000D01*
X791617D01*
X791950Y1497875D01*
X792200Y1497583D01*
X792283Y1497250D01*
X792200Y1496917D01*
X791992Y1496667D01*
X791617Y1496542D01*
X790617D01*
G01X793758Y1497583D02*
X794008Y1497833D01*
X794300Y1497958D01*
X794633Y1498000D01*
X795050Y1497917D01*
X795342Y1497708D01*
X795425Y1497458D01*
X795383Y1497208D01*
X795217Y1497000D01*
X794383Y1496583D01*
X794008Y1496292D01*
X793758Y1495875D01*
X793675Y1495500D01*
X795425D01*
G01X796858Y1496542D02*
X797150Y1496833D01*
X797400Y1497000D01*
X797733Y1497083D01*
X798025Y1497000D01*
X798233Y1496833D01*
X798400Y1496583D01*
X798442Y1496292D01*
X798400Y1496042D01*
X798233Y1495792D01*
X797983Y1495583D01*
X797692Y1495500D01*
X797358Y1495583D01*
X797067Y1495833D01*
X796900Y1496208D01*
X796858Y1496625D01*
X796942Y1497167D01*
X797067Y1497458D01*
X797275Y1497750D01*
X797567Y1497958D01*
X797858Y1498000D01*
X798150Y1497917D01*
X798358Y1497708D01*
G01X817867Y1532992D02*
X817617Y1533117D01*
X817325Y1533200D01*
X816992D01*
X816617Y1533075D01*
X816325Y1532867D01*
X816117Y1532617D01*
X815950Y1532200D01*
X815908Y1531825D01*
X815992Y1531450D01*
X816117Y1531200D01*
X816367Y1530950D01*
X816658Y1530783D01*
X816950Y1530700D01*
X817242D01*
X817533Y1530783D01*
X817783Y1530908D01*
X817992Y1531075D01*
G01X820050Y1530700D02*
Y1533200D01*
X819550Y1532700D01*
G01Y1530700D02*
X820550D01*
G01X822358Y1532783D02*
X822608Y1533033D01*
X822900Y1533158D01*
X823233Y1533200D01*
X823650Y1533117D01*
X823942Y1532908D01*
X824025Y1532658D01*
X823983Y1532408D01*
X823817Y1532200D01*
X822983Y1531783D01*
X822608Y1531492D01*
X822358Y1531075D01*
X822275Y1530700D01*
X824025D01*
G01X825458Y1531742D02*
X825750Y1532033D01*
X826000Y1532200D01*
X826333Y1532283D01*
X826625Y1532200D01*
X826833Y1532033D01*
X827000Y1531783D01*
X827042Y1531492D01*
X827000Y1531242D01*
X826833Y1530992D01*
X826583Y1530783D01*
X826292Y1530700D01*
X825958Y1530783D01*
X825667Y1531033D01*
X825500Y1531408D01*
X825458Y1531825D01*
X825542Y1532367D01*
X825667Y1532658D01*
X825875Y1532950D01*
X826167Y1533158D01*
X826458Y1533200D01*
X826750Y1533117D01*
X826958Y1532908D01*
G01X837827Y1538096D02*
Y1532596D01*
G01X829827Y1538096D02*
X837827D01*
G01X829827Y1532596D02*
Y1538096D01*
G01Y1520496D02*
Y1525996D01*
G01X837827Y1520496D02*
X829827D01*
G01X837827Y1525996D02*
Y1520496D01*
G01X837500Y1542000D02*
Y1547500D01*
G01X845500Y1542000D02*
X837500D01*
G01Y1554100D02*
Y1559600D01*
G01X830400Y1475800D02*
X843400D01*
G01X830400Y1489800D02*
Y1475800D01*
G01X843400Y1489800D02*
X830400D01*
G01X839800Y1635133D02*
X841133Y1634300D01*
X842633Y1633800D01*
X843967D01*
X845300Y1634300D01*
X846300Y1635133D01*
X846800Y1636300D01*
X846467Y1637466D01*
X845633Y1638467D01*
X844133Y1639133D01*
X842133Y1639467D01*
X840967Y1640133D01*
X840467Y1641300D01*
X840800Y1642467D01*
X841633Y1643300D01*
X842800Y1643800D01*
X843967D01*
X845133Y1643467D01*
X846133Y1642633D01*
G01X853900Y1643800D02*
Y1633800D01*
G01X850067Y1643800D02*
X857733D01*
G01X861167Y1633800D02*
Y1643800D01*
X865333D01*
X866667Y1643300D01*
X867500Y1642633D01*
X867833Y1641300D01*
X867500Y1639967D01*
X866500Y1639133D01*
X865333Y1638633D01*
X861167D01*
G01X865333D02*
X867833Y1633800D01*
G01X870933D02*
X875100Y1643800D01*
X879267Y1633800D01*
G01X877767Y1637300D02*
X872433D01*
G01X882033Y1633800D02*
Y1643800D01*
X885367D01*
X886700Y1643300D01*
X887700Y1642633D01*
X888533Y1641633D01*
X889200Y1640466D01*
X889367Y1638800D01*
X889200Y1637133D01*
X888533Y1635967D01*
X887700Y1634966D01*
X886700Y1634300D01*
X885367Y1633800D01*
X882033D01*
G01X892633D02*
Y1643800D01*
X895967D01*
X897300Y1643300D01*
X898300Y1642633D01*
X899133Y1641633D01*
X899800Y1640466D01*
X899967Y1638800D01*
X899800Y1637133D01*
X899133Y1635967D01*
X898300Y1634966D01*
X897300Y1634300D01*
X895967Y1633800D01*
X892633D01*
G01X903567Y1643800D02*
Y1633800D01*
X910233D01*
G01X920833D02*
X914167D01*
Y1643800D01*
X920833D01*
G01X918167Y1638967D02*
X914167D01*
G01X942367Y1642967D02*
X941367Y1643467D01*
X940200Y1643800D01*
X938867D01*
X937366Y1643300D01*
X936200Y1642467D01*
X935367Y1641467D01*
X934700Y1639800D01*
X934533Y1638300D01*
X934867Y1636800D01*
X935367Y1635800D01*
X936367Y1634800D01*
X937533Y1634133D01*
X938700Y1633800D01*
X939867D01*
X941033Y1634133D01*
X942033Y1634633D01*
X942867Y1635300D01*
G01X949300Y1633800D02*
X947966Y1633967D01*
X946800Y1634633D01*
X945800Y1635633D01*
X945133Y1636800D01*
X944800Y1638133D01*
Y1639467D01*
X945133Y1640800D01*
X945800Y1641967D01*
X946800Y1642967D01*
X947966Y1643633D01*
X949300Y1643800D01*
X950633Y1643633D01*
X951800Y1642967D01*
X952800Y1641967D01*
X953467Y1640800D01*
X953800Y1639467D01*
Y1638133D01*
X953467Y1636800D01*
X952800Y1635633D01*
X951800Y1634633D01*
X950633Y1633967D01*
X949300Y1633800D01*
G01X956067D02*
Y1643800D01*
X963733Y1633800D01*
Y1643800D01*
G01X966667Y1633800D02*
Y1643800D01*
X974333Y1633800D01*
Y1643800D01*
G01X768500Y1571500D02*
Y1564500D01*
G01X786633Y1572600D02*
Y1570808D01*
X786800Y1570433D01*
X787133Y1570183D01*
X787550Y1570100D01*
X787967Y1570183D01*
X788300Y1570433D01*
X788467Y1570808D01*
Y1572600D01*
G01X789733Y1570475D02*
X789983Y1570267D01*
X790275Y1570142D01*
X790650Y1570100D01*
X791025Y1570183D01*
X791317Y1570350D01*
X791525Y1570642D01*
X791567Y1570975D01*
X791483Y1571308D01*
X791275Y1571517D01*
X790983Y1571683D01*
X790692Y1571725D01*
X790400Y1571683D01*
X790025Y1571517D01*
X790150Y1572600D01*
X791275D01*
G01X791327Y1567096D02*
X789327Y1565096D01*
X787327Y1567096D01*
G01X840208Y1563467D02*
X840083Y1563217D01*
X840000Y1562925D01*
Y1562592D01*
X840125Y1562217D01*
X840333Y1561925D01*
X840583Y1561717D01*
X841000Y1561550D01*
X841375Y1561508D01*
X841750Y1561592D01*
X842000Y1561717D01*
X842250Y1561967D01*
X842417Y1562258D01*
X842500Y1562550D01*
Y1562842D01*
X842417Y1563133D01*
X842292Y1563383D01*
X842125Y1563592D01*
G01X842500Y1565650D02*
X840000D01*
X840500Y1565150D01*
G01X842500D02*
Y1566150D01*
G01X840417Y1567958D02*
X840167Y1568208D01*
X840042Y1568500D01*
X840000Y1568833D01*
X840083Y1569250D01*
X840292Y1569542D01*
X840542Y1569625D01*
X840792Y1569583D01*
X841000Y1569417D01*
X841417Y1568583D01*
X841708Y1568208D01*
X842125Y1567958D01*
X842500Y1567875D01*
Y1569625D01*
G01Y1571767D02*
X841958Y1571850D01*
X841500Y1571975D01*
X841083Y1572142D01*
X840625Y1572350D01*
X840000Y1572683D01*
Y1571017D01*
G01X837500Y1559600D02*
X845500D01*
G01X823517Y1715000D02*
Y1717500D01*
X824517D01*
X824850Y1717375D01*
X825100Y1717083D01*
X825183Y1716750D01*
X825100Y1716417D01*
X824892Y1716167D01*
X824517Y1716042D01*
X823517D01*
G01X826617Y1715000D02*
Y1717500D01*
X827658D01*
X827992Y1717375D01*
X828200Y1717208D01*
X828283Y1716875D01*
X828200Y1716542D01*
X827950Y1716333D01*
X827658Y1716208D01*
X826617D01*
G01X827658D02*
X828283Y1715000D01*
G01X829633Y1715375D02*
X829883Y1715167D01*
X830175Y1715042D01*
X830550Y1715000D01*
X830925Y1715083D01*
X831217Y1715250D01*
X831425Y1715542D01*
X831467Y1715875D01*
X831383Y1716208D01*
X831175Y1716417D01*
X830883Y1716583D01*
X830592Y1716625D01*
X830300Y1716583D01*
X829925Y1716417D01*
X830050Y1717500D01*
X831175D01*
G01X833567Y1715000D02*
X833650Y1715542D01*
X833775Y1716000D01*
X833942Y1716417D01*
X834150Y1716875D01*
X834483Y1717500D01*
X832817D01*
G01X823517Y1711000D02*
Y1713500D01*
X824517D01*
X824850Y1713375D01*
X825100Y1713083D01*
X825183Y1712750D01*
X825100Y1712417D01*
X824892Y1712167D01*
X824517Y1712042D01*
X823517D01*
G01X828367Y1713292D02*
X828117Y1713417D01*
X827825Y1713500D01*
X827492D01*
X827117Y1713375D01*
X826825Y1713167D01*
X826617Y1712917D01*
X826450Y1712500D01*
X826408Y1712125D01*
X826492Y1711750D01*
X826617Y1711500D01*
X826867Y1711250D01*
X827158Y1711083D01*
X827450Y1711000D01*
X827742D01*
X828033Y1711083D01*
X828283Y1711208D01*
X828492Y1711375D01*
G01X831050Y1711000D02*
Y1713500D01*
X829508Y1711708D01*
X831592D01*
G01X832733Y1711500D02*
X832983Y1711208D01*
X833317Y1711042D01*
X833692Y1711000D01*
X834025Y1711042D01*
X834358Y1711250D01*
X834567Y1711500D01*
X834608Y1711750D01*
X834525Y1712042D01*
X834233Y1712250D01*
X833942Y1712333D01*
X833567D01*
G01X833942D02*
X834192Y1712458D01*
X834400Y1712667D01*
X834483Y1712917D01*
X834400Y1713167D01*
X834192Y1713375D01*
X833817Y1713500D01*
X833442Y1713458D01*
X833067Y1713292D01*
G01X839600Y1722200D02*
X834100D01*
G01X839600Y1730200D02*
Y1722200D01*
G01X822000D02*
Y1730200D01*
G01X827500Y1722200D02*
X822000D01*
G01X838800Y1738000D02*
Y1731000D01*
X825400D01*
Y1738000D01*
X838800D01*
G01X834499Y1765067D02*
X831999D01*
Y1766108D01*
X832124Y1766442D01*
X832291Y1766650D01*
X832624Y1766733D01*
X832957Y1766650D01*
X833166Y1766400D01*
X833291Y1766108D01*
Y1765067D01*
G01Y1766108D02*
X834499Y1766733D01*
G01X833999Y1768083D02*
X834291Y1768333D01*
X834457Y1768667D01*
X834499Y1769042D01*
X834457Y1769375D01*
X834249Y1769708D01*
X833999Y1769917D01*
X833749Y1769958D01*
X833457Y1769875D01*
X833249Y1769583D01*
X833166Y1769292D01*
Y1768917D01*
G01Y1769292D02*
X833041Y1769542D01*
X832832Y1769750D01*
X832582Y1769833D01*
X832332Y1769750D01*
X832124Y1769542D01*
X831999Y1769167D01*
X832041Y1768792D01*
X832207Y1768417D01*
G01X832416Y1771308D02*
X832166Y1771558D01*
X832041Y1771850D01*
X831999Y1772183D01*
X832082Y1772600D01*
X832291Y1772892D01*
X832541Y1772975D01*
X832791Y1772933D01*
X832999Y1772767D01*
X833416Y1771933D01*
X833707Y1771558D01*
X834124Y1771308D01*
X834499Y1771225D01*
Y1772975D01*
G01Y1775117D02*
X833957Y1775200D01*
X833499Y1775325D01*
X833082Y1775492D01*
X832624Y1775700D01*
X831999Y1776033D01*
Y1774367D01*
G01X831499Y1778350D02*
X835499D01*
Y1785750D01*
G01X815999Y1765067D02*
X813499D01*
Y1766108D01*
X813624Y1766442D01*
X813791Y1766650D01*
X814124Y1766733D01*
X814457Y1766650D01*
X814666Y1766400D01*
X814791Y1766108D01*
Y1765067D01*
G01Y1766108D02*
X815999Y1766733D01*
G01X815499Y1768083D02*
X815791Y1768333D01*
X815957Y1768667D01*
X815999Y1769042D01*
X815957Y1769375D01*
X815749Y1769708D01*
X815499Y1769917D01*
X815249Y1769958D01*
X814957Y1769875D01*
X814749Y1769583D01*
X814666Y1769292D01*
Y1768917D01*
G01Y1769292D02*
X814541Y1769542D01*
X814332Y1769750D01*
X814082Y1769833D01*
X813832Y1769750D01*
X813624Y1769542D01*
X813499Y1769167D01*
X813541Y1768792D01*
X813707Y1768417D01*
G01X813916Y1771308D02*
X813666Y1771558D01*
X813541Y1771850D01*
X813499Y1772183D01*
X813582Y1772600D01*
X813791Y1772892D01*
X814041Y1772975D01*
X814291Y1772933D01*
X814499Y1772767D01*
X814916Y1771933D01*
X815207Y1771558D01*
X815624Y1771308D01*
X815999Y1771225D01*
Y1772975D01*
G01Y1775200D02*
X815957Y1775492D01*
X815832Y1775825D01*
X815624Y1776033D01*
X815332Y1776117D01*
X815041Y1776033D01*
X814791Y1775783D01*
X814666Y1775408D01*
Y1774992D01*
X814582Y1774742D01*
X814374Y1774533D01*
X814082Y1774450D01*
X813791Y1774575D01*
X813582Y1774867D01*
X813499Y1775200D01*
X813582Y1775533D01*
X813791Y1775825D01*
X814082Y1775950D01*
X814374Y1775867D01*
X814582Y1775658D01*
X814666Y1775408D01*
Y1774992D01*
X814791Y1774617D01*
X815041Y1774367D01*
X815332Y1774283D01*
X815624Y1774367D01*
X815832Y1774575D01*
X815957Y1774908D01*
X815999Y1775200D01*
G01X812999Y1778350D02*
X816999D01*
Y1785750D01*
G01X825499Y1765067D02*
X822999D01*
Y1766108D01*
X823124Y1766442D01*
X823291Y1766650D01*
X823624Y1766733D01*
X823957Y1766650D01*
X824166Y1766400D01*
X824291Y1766108D01*
Y1765067D01*
G01Y1766108D02*
X825499Y1766733D01*
G01X824999Y1768083D02*
X825291Y1768333D01*
X825457Y1768667D01*
X825499Y1769042D01*
X825457Y1769375D01*
X825249Y1769708D01*
X824999Y1769917D01*
X824749Y1769958D01*
X824457Y1769875D01*
X824249Y1769583D01*
X824166Y1769292D01*
Y1768917D01*
G01Y1769292D02*
X824041Y1769542D01*
X823832Y1769750D01*
X823582Y1769833D01*
X823332Y1769750D01*
X823124Y1769542D01*
X822999Y1769167D01*
X823041Y1768792D01*
X823207Y1768417D01*
G01X823416Y1771308D02*
X823166Y1771558D01*
X823041Y1771850D01*
X822999Y1772183D01*
X823082Y1772600D01*
X823291Y1772892D01*
X823541Y1772975D01*
X823791Y1772933D01*
X823999Y1772767D01*
X824416Y1771933D01*
X824707Y1771558D01*
X825124Y1771308D01*
X825499Y1771225D01*
Y1772975D01*
G01X825207Y1774492D02*
X825416Y1774783D01*
X825499Y1775117D01*
X825416Y1775450D01*
X825166Y1775742D01*
X824791Y1775950D01*
X824416Y1776033D01*
X823957D01*
X823582Y1775950D01*
X823249Y1775742D01*
X823082Y1775492D01*
X822999Y1775200D01*
X823082Y1774867D01*
X823249Y1774617D01*
X823499Y1774450D01*
X823832Y1774367D01*
X824124Y1774450D01*
X824416Y1774658D01*
X824582Y1774908D01*
X824624Y1775200D01*
X824541Y1775533D01*
X824332Y1775783D01*
X823957Y1776033D01*
G01X822499Y1778350D02*
X826499D01*
Y1785750D01*
G01X790016Y1791550D02*
Y1794050D01*
X791057D01*
X791391Y1793925D01*
X791599Y1793758D01*
X791682Y1793425D01*
X791599Y1793092D01*
X791349Y1792883D01*
X791057Y1792758D01*
X790016D01*
G01X791057D02*
X791682Y1791550D01*
G01X793032Y1792050D02*
X793282Y1791758D01*
X793616Y1791592D01*
X793991Y1791550D01*
X794324Y1791592D01*
X794657Y1791800D01*
X794866Y1792050D01*
X794907Y1792300D01*
X794824Y1792592D01*
X794532Y1792800D01*
X794241Y1792883D01*
X793866D01*
G01X794241D02*
X794491Y1793008D01*
X794699Y1793217D01*
X794782Y1793467D01*
X794699Y1793717D01*
X794491Y1793925D01*
X794116Y1794050D01*
X793741Y1794008D01*
X793366Y1793842D01*
G01X796132Y1792050D02*
X796382Y1791758D01*
X796716Y1791592D01*
X797091Y1791550D01*
X797424Y1791592D01*
X797757Y1791800D01*
X797966Y1792050D01*
X798007Y1792300D01*
X797924Y1792592D01*
X797632Y1792800D01*
X797341Y1792883D01*
X796966D01*
G01X797341D02*
X797591Y1793008D01*
X797799Y1793217D01*
X797882Y1793467D01*
X797799Y1793717D01*
X797591Y1793925D01*
X797216Y1794050D01*
X796841Y1794008D01*
X796466Y1793842D01*
G01X799357Y1792592D02*
X799649Y1792883D01*
X799899Y1793050D01*
X800232Y1793133D01*
X800524Y1793050D01*
X800732Y1792883D01*
X800899Y1792633D01*
X800941Y1792342D01*
X800899Y1792092D01*
X800732Y1791842D01*
X800482Y1791633D01*
X800191Y1791550D01*
X799857Y1791633D01*
X799566Y1791883D01*
X799399Y1792258D01*
X799357Y1792675D01*
X799441Y1793217D01*
X799566Y1793508D01*
X799774Y1793800D01*
X800066Y1794008D01*
X800357Y1794050D01*
X800649Y1793967D01*
X800857Y1793758D01*
G01X819199Y1786050D02*
Y1790050D01*
X811799D01*
G01X803016Y1791550D02*
Y1794050D01*
X804057D01*
X804391Y1793925D01*
X804599Y1793758D01*
X804682Y1793425D01*
X804599Y1793092D01*
X804349Y1792883D01*
X804057Y1792758D01*
X803016D01*
G01X804057D02*
X804682Y1791550D01*
G01X806032Y1792050D02*
X806282Y1791758D01*
X806616Y1791592D01*
X806991Y1791550D01*
X807324Y1791592D01*
X807657Y1791800D01*
X807866Y1792050D01*
X807907Y1792300D01*
X807824Y1792592D01*
X807532Y1792800D01*
X807241Y1792883D01*
X806866D01*
G01X807241D02*
X807491Y1793008D01*
X807699Y1793217D01*
X807782Y1793467D01*
X807699Y1793717D01*
X807491Y1793925D01*
X807116Y1794050D01*
X806741Y1794008D01*
X806366Y1793842D01*
G01X809132Y1792050D02*
X809382Y1791758D01*
X809716Y1791592D01*
X810091Y1791550D01*
X810424Y1791592D01*
X810757Y1791800D01*
X810966Y1792050D01*
X811007Y1792300D01*
X810924Y1792592D01*
X810632Y1792800D01*
X810341Y1792883D01*
X809966D01*
G01X810341D02*
X810591Y1793008D01*
X810799Y1793217D01*
X810882Y1793467D01*
X810799Y1793717D01*
X810591Y1793925D01*
X810216Y1794050D01*
X809841Y1794008D01*
X809466Y1793842D01*
G01X813066Y1791550D02*
X813149Y1792092D01*
X813274Y1792550D01*
X813441Y1792967D01*
X813649Y1793425D01*
X813982Y1794050D01*
X812316D01*
G01X826699Y1786050D02*
Y1790050D01*
X819299D01*
G01X829016Y1791050D02*
Y1793550D01*
X830057D01*
X830391Y1793425D01*
X830599Y1793258D01*
X830682Y1792925D01*
X830599Y1792592D01*
X830349Y1792383D01*
X830057Y1792258D01*
X829016D01*
G01X830057D02*
X830682Y1791050D01*
G01X832032Y1791550D02*
X832282Y1791258D01*
X832616Y1791092D01*
X832991Y1791050D01*
X833324Y1791092D01*
X833657Y1791300D01*
X833866Y1791550D01*
X833907Y1791800D01*
X833824Y1792092D01*
X833532Y1792300D01*
X833241Y1792383D01*
X832866D01*
G01X833241D02*
X833491Y1792508D01*
X833699Y1792717D01*
X833782Y1792967D01*
X833699Y1793217D01*
X833491Y1793425D01*
X833116Y1793550D01*
X832741Y1793508D01*
X832366Y1793342D01*
G01X835132Y1791550D02*
X835382Y1791258D01*
X835716Y1791092D01*
X836091Y1791050D01*
X836424Y1791092D01*
X836757Y1791300D01*
X836966Y1791550D01*
X837007Y1791800D01*
X836924Y1792092D01*
X836632Y1792300D01*
X836341Y1792383D01*
X835966D01*
G01X836341D02*
X836591Y1792508D01*
X836799Y1792717D01*
X836882Y1792967D01*
X836799Y1793217D01*
X836591Y1793425D01*
X836216Y1793550D01*
X835841Y1793508D01*
X835466Y1793342D01*
G01X839149Y1791050D02*
X839441Y1791092D01*
X839774Y1791217D01*
X839982Y1791425D01*
X840066Y1791717D01*
X839982Y1792008D01*
X839732Y1792258D01*
X839357Y1792383D01*
X838941D01*
X838691Y1792467D01*
X838482Y1792675D01*
X838399Y1792967D01*
X838524Y1793258D01*
X838816Y1793467D01*
X839149Y1793550D01*
X839482Y1793467D01*
X839774Y1793258D01*
X839899Y1792967D01*
X839816Y1792675D01*
X839607Y1792467D01*
X839357Y1792383D01*
X838941D01*
X838566Y1792258D01*
X838316Y1792008D01*
X838232Y1791717D01*
X838316Y1791425D01*
X838524Y1791217D01*
X838857Y1791092D01*
X839149Y1791050D01*
G01X834199Y1786050D02*
Y1790050D01*
X826799D01*
G01X792566Y1803134D02*
Y1805634D01*
X793607D01*
X793941Y1805509D01*
X794149Y1805342D01*
X794232Y1805009D01*
X794149Y1804676D01*
X793899Y1804467D01*
X793607Y1804342D01*
X792566D01*
G01X793607D02*
X794232Y1803134D01*
G01X795582Y1803634D02*
X795832Y1803342D01*
X796166Y1803176D01*
X796541Y1803134D01*
X796874Y1803176D01*
X797207Y1803384D01*
X797416Y1803634D01*
X797457Y1803884D01*
X797374Y1804176D01*
X797082Y1804384D01*
X796791Y1804467D01*
X796416D01*
G01X796791D02*
X797041Y1804592D01*
X797249Y1804801D01*
X797332Y1805051D01*
X797249Y1805301D01*
X797041Y1805509D01*
X796666Y1805634D01*
X796291Y1805592D01*
X795916Y1805426D01*
G01X798682Y1803509D02*
X798932Y1803301D01*
X799224Y1803176D01*
X799599Y1803134D01*
X799974Y1803217D01*
X800266Y1803384D01*
X800474Y1803676D01*
X800516Y1804009D01*
X800432Y1804342D01*
X800224Y1804551D01*
X799932Y1804717D01*
X799641Y1804759D01*
X799349Y1804717D01*
X798974Y1804551D01*
X799099Y1805634D01*
X800224D01*
G01X801907Y1805217D02*
X802157Y1805467D01*
X802449Y1805592D01*
X802782Y1805634D01*
X803199Y1805551D01*
X803491Y1805342D01*
X803574Y1805092D01*
X803532Y1804842D01*
X803366Y1804634D01*
X802532Y1804217D01*
X802157Y1803926D01*
X801907Y1803509D01*
X801824Y1803134D01*
X803574D01*
G01X783849Y1806634D02*
Y1802634D01*
X791249D01*
G01X792566Y1799134D02*
Y1801634D01*
X793607D01*
X793941Y1801509D01*
X794149Y1801342D01*
X794232Y1801009D01*
X794149Y1800676D01*
X793899Y1800467D01*
X793607Y1800342D01*
X792566D01*
G01X793607D02*
X794232Y1799134D01*
G01X795582Y1799634D02*
X795832Y1799342D01*
X796166Y1799176D01*
X796541Y1799134D01*
X796874Y1799176D01*
X797207Y1799384D01*
X797416Y1799634D01*
X797457Y1799884D01*
X797374Y1800176D01*
X797082Y1800384D01*
X796791Y1800467D01*
X796416D01*
G01X796791D02*
X797041Y1800592D01*
X797249Y1800801D01*
X797332Y1801051D01*
X797249Y1801301D01*
X797041Y1801509D01*
X796666Y1801634D01*
X796291Y1801592D01*
X795916Y1801426D01*
G01X798682Y1799509D02*
X798932Y1799301D01*
X799224Y1799176D01*
X799599Y1799134D01*
X799974Y1799217D01*
X800266Y1799384D01*
X800474Y1799676D01*
X800516Y1800009D01*
X800432Y1800342D01*
X800224Y1800551D01*
X799932Y1800717D01*
X799641Y1800759D01*
X799349Y1800717D01*
X798974Y1800551D01*
X799099Y1801634D01*
X800224D01*
G01X803199Y1799134D02*
Y1801634D01*
X801657Y1799842D01*
X803741D01*
G01X783849Y1802634D02*
Y1798634D01*
X791249D01*
G01X839500Y1802546D02*
X841292D01*
X841667Y1802713D01*
X841917Y1803046D01*
X842000Y1803463D01*
X841917Y1803880D01*
X841667Y1804213D01*
X841292Y1804380D01*
X839500D01*
G01X842000Y1807063D02*
X839500D01*
X841292Y1805521D01*
Y1807605D01*
G01X842000Y1809663D02*
X841958Y1809955D01*
X841833Y1810288D01*
X841625Y1810496D01*
X841333Y1810580D01*
X841042Y1810496D01*
X840792Y1810246D01*
X840667Y1809871D01*
Y1809455D01*
X840583Y1809205D01*
X840375Y1808996D01*
X840083Y1808913D01*
X839792Y1809038D01*
X839583Y1809330D01*
X839500Y1809663D01*
X839583Y1809996D01*
X839792Y1810288D01*
X840083Y1810413D01*
X840375Y1810330D01*
X840583Y1810121D01*
X840667Y1809871D01*
Y1809455D01*
X840792Y1809080D01*
X841042Y1808830D01*
X841333Y1808746D01*
X841625Y1808830D01*
X841833Y1809038D01*
X841958Y1809371D01*
X842000Y1809663D01*
G01X824923Y1811087D02*
Y1803087D01*
X836873D01*
Y1811087D01*
X824923D01*
G01X836873Y1804937D02*
X834873Y1806937D01*
X836873Y1808937D01*
G01X834100Y1730200D02*
X839600D01*
G01X822000D02*
X827500D01*
G01X781757Y1825401D02*
X781632Y1825151D01*
X781549Y1824859D01*
Y1824526D01*
X781674Y1824151D01*
X781882Y1823859D01*
X782132Y1823651D01*
X782549Y1823484D01*
X782924Y1823442D01*
X783299Y1823526D01*
X783549Y1823651D01*
X783799Y1823901D01*
X783966Y1824192D01*
X784049Y1824484D01*
Y1824776D01*
X783966Y1825067D01*
X783841Y1825317D01*
X783674Y1825526D01*
G01X783549Y1826667D02*
X783841Y1826917D01*
X784007Y1827251D01*
X784049Y1827626D01*
X784007Y1827959D01*
X783799Y1828292D01*
X783549Y1828501D01*
X783299Y1828542D01*
X783007Y1828459D01*
X782799Y1828167D01*
X782716Y1827876D01*
Y1827501D01*
G01Y1827876D02*
X782591Y1828126D01*
X782382Y1828334D01*
X782132Y1828417D01*
X781882Y1828334D01*
X781674Y1828126D01*
X781549Y1827751D01*
X781591Y1827376D01*
X781757Y1827001D01*
G01X784049Y1831184D02*
X781549D01*
X783341Y1829642D01*
Y1831726D01*
G01X783007Y1832992D02*
X782716Y1833284D01*
X782549Y1833534D01*
X782466Y1833867D01*
X782549Y1834159D01*
X782716Y1834367D01*
X782966Y1834534D01*
X783257Y1834576D01*
X783507Y1834534D01*
X783757Y1834367D01*
X783966Y1834117D01*
X784049Y1833826D01*
X783966Y1833492D01*
X783716Y1833201D01*
X783341Y1833034D01*
X782924Y1832992D01*
X782382Y1833076D01*
X782091Y1833201D01*
X781799Y1833409D01*
X781591Y1833701D01*
X781549Y1833992D01*
X781632Y1834284D01*
X781841Y1834492D01*
G01X786757Y1825401D02*
X786632Y1825151D01*
X786549Y1824859D01*
Y1824526D01*
X786674Y1824151D01*
X786882Y1823859D01*
X787132Y1823651D01*
X787549Y1823484D01*
X787924Y1823442D01*
X788299Y1823526D01*
X788549Y1823651D01*
X788799Y1823901D01*
X788966Y1824192D01*
X789049Y1824484D01*
Y1824776D01*
X788966Y1825067D01*
X788841Y1825317D01*
X788674Y1825526D01*
G01X788549Y1826667D02*
X788841Y1826917D01*
X789007Y1827251D01*
X789049Y1827626D01*
X789007Y1827959D01*
X788799Y1828292D01*
X788549Y1828501D01*
X788299Y1828542D01*
X788007Y1828459D01*
X787799Y1828167D01*
X787716Y1827876D01*
Y1827501D01*
G01Y1827876D02*
X787591Y1828126D01*
X787382Y1828334D01*
X787132Y1828417D01*
X786882Y1828334D01*
X786674Y1828126D01*
X786549Y1827751D01*
X786591Y1827376D01*
X786757Y1827001D01*
G01X789049Y1831184D02*
X786549D01*
X788341Y1829642D01*
Y1831726D01*
G01X789049Y1833701D02*
X788507Y1833784D01*
X788049Y1833909D01*
X787632Y1834076D01*
X787174Y1834284D01*
X786549Y1834617D01*
Y1832951D01*
G01X803900Y1879500D02*
X803567Y1879542D01*
X803275Y1879708D01*
X803025Y1879958D01*
X802858Y1880250D01*
X802775Y1880583D01*
Y1880917D01*
X802858Y1881250D01*
X803025Y1881542D01*
X803275Y1881792D01*
X803567Y1881958D01*
X803900Y1882000D01*
X804233Y1881958D01*
X804525Y1881792D01*
X804775Y1881542D01*
X804942Y1881250D01*
X805025Y1880917D01*
Y1880583D01*
X804942Y1880250D01*
X804775Y1879958D01*
X804525Y1879708D01*
X804233Y1879542D01*
X803900Y1879500D01*
G01X804233Y1880167D02*
X804733Y1879500D01*
G01X806083Y1880000D02*
X806333Y1879708D01*
X806667Y1879542D01*
X807042Y1879500D01*
X807375Y1879542D01*
X807708Y1879750D01*
X807917Y1880000D01*
X807958Y1880250D01*
X807875Y1880542D01*
X807583Y1880750D01*
X807292Y1880833D01*
X806917D01*
G01X807292D02*
X807542Y1880958D01*
X807750Y1881167D01*
X807833Y1881417D01*
X807750Y1881667D01*
X807542Y1881875D01*
X807167Y1882000D01*
X806792Y1881958D01*
X806417Y1881792D01*
G01X810100Y1879500D02*
Y1882000D01*
X809600Y1881500D01*
G01Y1879500D02*
X810600D01*
G01X812300Y1890700D02*
Y1879300D01*
G01X825700D02*
Y1890700D01*
G01X812300Y1879300D02*
X825700D01*
G01X798816Y1824450D02*
Y1826950D01*
X799857D01*
X800191Y1826825D01*
X800399Y1826658D01*
X800482Y1826325D01*
X800399Y1825992D01*
X800149Y1825783D01*
X799857Y1825658D01*
X798816D01*
G01X799857D02*
X800482Y1824450D01*
G01X801832Y1824950D02*
X802082Y1824658D01*
X802416Y1824492D01*
X802791Y1824450D01*
X803124Y1824492D01*
X803457Y1824700D01*
X803666Y1824950D01*
X803707Y1825200D01*
X803624Y1825492D01*
X803332Y1825700D01*
X803041Y1825783D01*
X802666D01*
G01X803041D02*
X803291Y1825908D01*
X803499Y1826117D01*
X803582Y1826367D01*
X803499Y1826617D01*
X803291Y1826825D01*
X802916Y1826950D01*
X802541Y1826908D01*
X802166Y1826742D01*
G01X805057Y1826533D02*
X805307Y1826783D01*
X805599Y1826908D01*
X805932Y1826950D01*
X806349Y1826867D01*
X806641Y1826658D01*
X806724Y1826408D01*
X806682Y1826158D01*
X806516Y1825950D01*
X805682Y1825533D01*
X805307Y1825242D01*
X805057Y1824825D01*
X804974Y1824450D01*
X806724D01*
G01X808157Y1825492D02*
X808449Y1825783D01*
X808699Y1825950D01*
X809032Y1826033D01*
X809324Y1825950D01*
X809532Y1825783D01*
X809699Y1825533D01*
X809741Y1825242D01*
X809699Y1824992D01*
X809532Y1824742D01*
X809282Y1824533D01*
X808991Y1824450D01*
X808657Y1824533D01*
X808366Y1824783D01*
X808199Y1825158D01*
X808157Y1825575D01*
X808241Y1826117D01*
X808366Y1826408D01*
X808574Y1826700D01*
X808866Y1826908D01*
X809157Y1826950D01*
X809449Y1826867D01*
X809657Y1826658D01*
G01X811799Y1827550D02*
Y1823550D01*
X819199D01*
G01X798816Y1820450D02*
Y1822950D01*
X799857D01*
X800191Y1822825D01*
X800399Y1822658D01*
X800482Y1822325D01*
X800399Y1821992D01*
X800149Y1821783D01*
X799857Y1821658D01*
X798816D01*
G01X799857D02*
X800482Y1820450D01*
G01X801832Y1820950D02*
X802082Y1820658D01*
X802416Y1820492D01*
X802791Y1820450D01*
X803124Y1820492D01*
X803457Y1820700D01*
X803666Y1820950D01*
X803707Y1821200D01*
X803624Y1821492D01*
X803332Y1821700D01*
X803041Y1821783D01*
X802666D01*
G01X803041D02*
X803291Y1821908D01*
X803499Y1822117D01*
X803582Y1822367D01*
X803499Y1822617D01*
X803291Y1822825D01*
X802916Y1822950D01*
X802541Y1822908D01*
X802166Y1822742D01*
G01X804932Y1820950D02*
X805182Y1820658D01*
X805516Y1820492D01*
X805891Y1820450D01*
X806224Y1820492D01*
X806557Y1820700D01*
X806766Y1820950D01*
X806807Y1821200D01*
X806724Y1821492D01*
X806432Y1821700D01*
X806141Y1821783D01*
X805766D01*
G01X806141D02*
X806391Y1821908D01*
X806599Y1822117D01*
X806682Y1822367D01*
X806599Y1822617D01*
X806391Y1822825D01*
X806016Y1822950D01*
X805641Y1822908D01*
X805266Y1822742D01*
G01X809449Y1820450D02*
Y1822950D01*
X807907Y1821158D01*
X809991D01*
G01X811799Y1823550D02*
Y1819550D01*
X819199D01*
G01X829500Y1866517D02*
X827000D01*
Y1867558D01*
X827125Y1867892D01*
X827292Y1868100D01*
X827625Y1868183D01*
X827958Y1868100D01*
X828167Y1867850D01*
X828292Y1867558D01*
Y1866517D01*
G01Y1867558D02*
X829500Y1868183D01*
G01X829000Y1869533D02*
X829292Y1869783D01*
X829458Y1870117D01*
X829500Y1870492D01*
X829458Y1870825D01*
X829250Y1871158D01*
X829000Y1871367D01*
X828750Y1871408D01*
X828458Y1871325D01*
X828250Y1871033D01*
X828167Y1870742D01*
Y1870367D01*
G01Y1870742D02*
X828042Y1870992D01*
X827833Y1871200D01*
X827583Y1871283D01*
X827333Y1871200D01*
X827125Y1870992D01*
X827000Y1870617D01*
X827042Y1870242D01*
X827208Y1869867D01*
G01X829500Y1874050D02*
X827000D01*
X828792Y1872508D01*
Y1874592D01*
G01X827417Y1875858D02*
X827167Y1876108D01*
X827042Y1876400D01*
X827000Y1876733D01*
X827083Y1877150D01*
X827292Y1877442D01*
X827542Y1877525D01*
X827792Y1877483D01*
X828000Y1877317D01*
X828417Y1876483D01*
X828708Y1876108D01*
X829125Y1875858D01*
X829500Y1875775D01*
Y1877525D01*
G01X826000Y1879300D02*
X830000D01*
Y1886700D01*
G01X768066Y1822634D02*
Y1825134D01*
X769107D01*
X769441Y1825009D01*
X769649Y1824842D01*
X769732Y1824509D01*
X769649Y1824176D01*
X769399Y1823967D01*
X769107Y1823842D01*
X768066D01*
G01X769107D02*
X769732Y1822634D01*
G01X771082Y1823134D02*
X771332Y1822842D01*
X771666Y1822676D01*
X772041Y1822634D01*
X772374Y1822676D01*
X772707Y1822884D01*
X772916Y1823134D01*
X772957Y1823384D01*
X772874Y1823676D01*
X772582Y1823884D01*
X772291Y1823967D01*
X771916D01*
G01X772291D02*
X772541Y1824092D01*
X772749Y1824301D01*
X772832Y1824551D01*
X772749Y1824801D01*
X772541Y1825009D01*
X772166Y1825134D01*
X771791Y1825092D01*
X771416Y1824926D01*
G01X774182Y1823009D02*
X774432Y1822801D01*
X774724Y1822676D01*
X775099Y1822634D01*
X775474Y1822717D01*
X775766Y1822884D01*
X775974Y1823176D01*
X776016Y1823509D01*
X775932Y1823842D01*
X775724Y1824051D01*
X775432Y1824217D01*
X775141Y1824259D01*
X774849Y1824217D01*
X774474Y1824051D01*
X774599Y1825134D01*
X775724D01*
G01X778199Y1822634D02*
Y1825134D01*
X777699Y1824634D01*
G01Y1822634D02*
X778699D01*
G01X772349Y1819634D02*
Y1815634D01*
X779749D01*
G01X806099Y1807550D02*
X808599D01*
G01X806099Y1806592D02*
Y1808508D01*
G01X808599Y1809817D02*
X806099D01*
Y1810817D01*
X806224Y1811150D01*
X806516Y1811400D01*
X806849Y1811483D01*
X807182Y1811400D01*
X807432Y1811192D01*
X807557Y1810817D01*
Y1809817D01*
G01X808099Y1812833D02*
X808391Y1813083D01*
X808557Y1813417D01*
X808599Y1813792D01*
X808557Y1814125D01*
X808349Y1814458D01*
X808099Y1814667D01*
X807849Y1814708D01*
X807557Y1814625D01*
X807349Y1814333D01*
X807266Y1814042D01*
Y1813667D01*
G01Y1814042D02*
X807141Y1814292D01*
X806932Y1814500D01*
X806682Y1814583D01*
X806432Y1814500D01*
X806224Y1814292D01*
X806099Y1813917D01*
X806141Y1813542D01*
X806307Y1813167D01*
G01X830999Y1881550D02*
X843999D01*
G01X830999Y1895550D02*
Y1881550D01*
G01X769000Y1975500D02*
Y1968500D01*
G01X810208Y1894767D02*
X810083Y1894517D01*
X810000Y1894225D01*
Y1893892D01*
X810125Y1893517D01*
X810333Y1893225D01*
X810583Y1893017D01*
X811000Y1892850D01*
X811375Y1892808D01*
X811750Y1892892D01*
X812000Y1893017D01*
X812250Y1893267D01*
X812417Y1893558D01*
X812500Y1893850D01*
Y1894142D01*
X812417Y1894433D01*
X812292Y1894683D01*
X812125Y1894892D01*
G01X812000Y1896033D02*
X812292Y1896283D01*
X812458Y1896617D01*
X812500Y1896992D01*
X812458Y1897325D01*
X812250Y1897658D01*
X812000Y1897867D01*
X811750Y1897908D01*
X811458Y1897825D01*
X811250Y1897533D01*
X811167Y1897242D01*
Y1896867D01*
G01Y1897242D02*
X811042Y1897492D01*
X810833Y1897700D01*
X810583Y1897783D01*
X810333Y1897700D01*
X810125Y1897492D01*
X810000Y1897117D01*
X810042Y1896742D01*
X810208Y1896367D01*
G01X811458Y1899258D02*
X811167Y1899550D01*
X811000Y1899800D01*
X810917Y1900133D01*
X811000Y1900425D01*
X811167Y1900633D01*
X811417Y1900800D01*
X811708Y1900842D01*
X811958Y1900800D01*
X812208Y1900633D01*
X812417Y1900383D01*
X812500Y1900092D01*
X812417Y1899758D01*
X812167Y1899467D01*
X811792Y1899300D01*
X811375Y1899258D01*
X810833Y1899342D01*
X810542Y1899467D01*
X810250Y1899675D01*
X810042Y1899967D01*
X810000Y1900258D01*
X810083Y1900550D01*
X810292Y1900758D01*
G01X812500Y1903650D02*
X810000D01*
X811792Y1902108D01*
Y1904192D01*
G01X762708Y1916267D02*
X762583Y1916017D01*
X762500Y1915725D01*
Y1915392D01*
X762625Y1915017D01*
X762833Y1914725D01*
X763083Y1914517D01*
X763500Y1914350D01*
X763875Y1914308D01*
X764250Y1914392D01*
X764500Y1914517D01*
X764750Y1914767D01*
X764917Y1915058D01*
X765000Y1915350D01*
Y1915642D01*
X764917Y1915933D01*
X764792Y1916183D01*
X764625Y1916392D01*
G01X765000Y1918450D02*
X762500D01*
X763000Y1917950D01*
G01X765000D02*
Y1918950D01*
G01Y1921550D02*
X762500D01*
X763000Y1921050D01*
G01X765000D02*
Y1922050D01*
G01X762500Y1924650D02*
X762583Y1924317D01*
X762792Y1924067D01*
X763042Y1923900D01*
X763375Y1923775D01*
X763750Y1923733D01*
X764125Y1923775D01*
X764458Y1923900D01*
X764708Y1924067D01*
X764917Y1924317D01*
X765000Y1924650D01*
X764917Y1924983D01*
X764708Y1925233D01*
X764458Y1925400D01*
X764125Y1925525D01*
X763750Y1925567D01*
X763375Y1925525D01*
X763042Y1925400D01*
X762792Y1925233D01*
X762583Y1924983D01*
X762500Y1924650D01*
G01X783208Y1905767D02*
X783083Y1905517D01*
X783000Y1905225D01*
Y1904892D01*
X783125Y1904517D01*
X783333Y1904225D01*
X783583Y1904017D01*
X784000Y1903850D01*
X784375Y1903808D01*
X784750Y1903892D01*
X785000Y1904017D01*
X785250Y1904267D01*
X785417Y1904558D01*
X785500Y1904850D01*
Y1905142D01*
X785417Y1905433D01*
X785292Y1905683D01*
X785125Y1905892D01*
G01X785500Y1907950D02*
X783000D01*
X783500Y1907450D01*
G01X785500D02*
Y1908450D01*
G01X783000Y1911050D02*
X783083Y1910717D01*
X783292Y1910467D01*
X783542Y1910300D01*
X783875Y1910175D01*
X784250Y1910133D01*
X784625Y1910175D01*
X784958Y1910300D01*
X785208Y1910467D01*
X785417Y1910717D01*
X785500Y1911050D01*
X785417Y1911383D01*
X785208Y1911633D01*
X784958Y1911800D01*
X784625Y1911925D01*
X784250Y1911967D01*
X783875Y1911925D01*
X783542Y1911800D01*
X783292Y1911633D01*
X783083Y1911383D01*
X783000Y1911050D01*
G01X783417Y1913358D02*
X783167Y1913608D01*
X783042Y1913900D01*
X783000Y1914233D01*
X783083Y1914650D01*
X783292Y1914942D01*
X783542Y1915025D01*
X783792Y1914983D01*
X784000Y1914817D01*
X784417Y1913983D01*
X784708Y1913608D01*
X785125Y1913358D01*
X785500Y1913275D01*
Y1915025D01*
G01X767514Y1946513D02*
Y1957913D01*
G01X825700Y1890700D02*
X812300D01*
G01X794950Y1902500D02*
X794617Y1902542D01*
X794325Y1902708D01*
X794075Y1902958D01*
X793908Y1903250D01*
X793825Y1903583D01*
Y1903917D01*
X793908Y1904250D01*
X794075Y1904542D01*
X794325Y1904792D01*
X794617Y1904958D01*
X794950Y1905000D01*
X795283Y1904958D01*
X795575Y1904792D01*
X795825Y1904542D01*
X795992Y1904250D01*
X796075Y1903917D01*
Y1903583D01*
X795992Y1903250D01*
X795825Y1902958D01*
X795575Y1902708D01*
X795283Y1902542D01*
X794950Y1902500D01*
G01X795283Y1903167D02*
X795783Y1902500D01*
G01X797258Y1904583D02*
X797508Y1904833D01*
X797800Y1904958D01*
X798133Y1905000D01*
X798550Y1904917D01*
X798842Y1904708D01*
X798925Y1904458D01*
X798883Y1904208D01*
X798717Y1904000D01*
X797883Y1903583D01*
X797508Y1903292D01*
X797258Y1902875D01*
X797175Y1902500D01*
X798925D01*
G01X809436Y1907165D02*
X811236Y1909265D01*
X813436Y1907165D01*
G01X817036Y1907065D02*
Y1926265D01*
X805836D01*
Y1907065D01*
X817036D01*
Y1907465D01*
G01X834564Y1913813D02*
Y1900813D01*
G01X860564Y1913813D02*
X834564D01*
G01Y1900813D02*
X860564D01*
G01X837499Y1947050D02*
Y1934050D01*
G01X863499Y1947050D02*
X837499D01*
G01Y1934050D02*
X863499D01*
G01X763000Y1958800D02*
X767000D01*
Y1966200D01*
G01X802381Y1942393D02*
Y1946393D01*
X794981D01*
G01X802381D02*
Y1950393D01*
X794981D01*
G01X769517Y1920500D02*
Y1923000D01*
X770558D01*
X770892Y1922875D01*
X771100Y1922708D01*
X771183Y1922375D01*
X771100Y1922042D01*
X770850Y1921833D01*
X770558Y1921708D01*
X769517D01*
G01X770558D02*
X771183Y1920500D01*
G01X773950D02*
Y1923000D01*
X772408Y1921208D01*
X774492D01*
G01X775758Y1922583D02*
X776008Y1922833D01*
X776300Y1922958D01*
X776633Y1923000D01*
X777050Y1922917D01*
X777342Y1922708D01*
X777425Y1922458D01*
X777383Y1922208D01*
X777217Y1922000D01*
X776383Y1921583D01*
X776008Y1921292D01*
X775758Y1920875D01*
X775675Y1920500D01*
X777425D01*
G01X780150D02*
Y1923000D01*
X778608Y1921208D01*
X780692D01*
G01X780199Y1933050D02*
Y1937050D01*
X772799D01*
G01X769517Y1924500D02*
Y1927000D01*
X770558D01*
X770892Y1926875D01*
X771100Y1926708D01*
X771183Y1926375D01*
X771100Y1926042D01*
X770850Y1925833D01*
X770558Y1925708D01*
X769517D01*
G01X770558D02*
X771183Y1924500D01*
G01X773950D02*
Y1927000D01*
X772408Y1925208D01*
X774492D01*
G01X775758Y1926583D02*
X776008Y1926833D01*
X776300Y1926958D01*
X776633Y1927000D01*
X777050Y1926917D01*
X777342Y1926708D01*
X777425Y1926458D01*
X777383Y1926208D01*
X777217Y1926000D01*
X776383Y1925583D01*
X776008Y1925292D01*
X775758Y1924875D01*
X775675Y1924500D01*
X777425D01*
G01X778733Y1924875D02*
X778983Y1924667D01*
X779275Y1924542D01*
X779650Y1924500D01*
X780025Y1924583D01*
X780317Y1924750D01*
X780525Y1925042D01*
X780567Y1925375D01*
X780483Y1925708D01*
X780275Y1925917D01*
X779983Y1926083D01*
X779692Y1926125D01*
X779400Y1926083D01*
X779025Y1925917D01*
X779150Y1927000D01*
X780275D01*
G01X780199Y1937050D02*
Y1941050D01*
X772799D01*
G01X768000Y1947300D02*
X772000D01*
Y1954700D01*
G01X795500Y1934533D02*
X797292D01*
X797667Y1934700D01*
X797917Y1935033D01*
X798000Y1935450D01*
X797917Y1935867D01*
X797667Y1936200D01*
X797292Y1936367D01*
X795500D01*
G01X798000Y1938550D02*
X795500D01*
X796000Y1938050D01*
G01X798000D02*
Y1939050D01*
G01X783499Y1932350D02*
Y1945750D01*
G01X793499Y1932350D02*
X783499D01*
G01X793499Y1945750D02*
Y1932350D01*
G01X783499Y1945750D02*
X793499D01*
G01X762733Y1931000D02*
Y1929208D01*
X762900Y1928833D01*
X763233Y1928583D01*
X763650Y1928500D01*
X764067Y1928583D01*
X764400Y1928833D01*
X764567Y1929208D01*
Y1931000D01*
G01X765833Y1929000D02*
X766083Y1928708D01*
X766417Y1928542D01*
X766792Y1928500D01*
X767125Y1928542D01*
X767458Y1928750D01*
X767667Y1929000D01*
X767708Y1929250D01*
X767625Y1929542D01*
X767333Y1929750D01*
X767042Y1929833D01*
X766667D01*
G01X767042D02*
X767292Y1929958D01*
X767500Y1930167D01*
X767583Y1930417D01*
X767500Y1930667D01*
X767292Y1930875D01*
X766917Y1931000D01*
X766542Y1930958D01*
X766167Y1930792D01*
G01X770014Y1944713D02*
Y1934713D01*
G01X788814Y1973013D02*
X786814Y1971013D01*
X784814Y1973013D01*
G01X781214D02*
Y1953813D01*
X792414D01*
Y1973013D01*
X781214D01*
G01X797350Y1898500D02*
Y1896000D01*
G01X796392Y1898500D02*
X798308D01*
G01X799617Y1896000D02*
Y1898500D01*
X800617D01*
X800950Y1898375D01*
X801200Y1898083D01*
X801283Y1897750D01*
X801200Y1897417D01*
X800992Y1897167D01*
X800617Y1897042D01*
X799617D01*
G01X802758Y1898083D02*
X803008Y1898333D01*
X803300Y1898458D01*
X803633Y1898500D01*
X804050Y1898417D01*
X804342Y1898208D01*
X804425Y1897958D01*
X804383Y1897708D01*
X804217Y1897500D01*
X803383Y1897083D01*
X803008Y1896792D01*
X802758Y1896375D01*
X802675Y1896000D01*
X804425D01*
G01X805733Y1896375D02*
X805983Y1896167D01*
X806275Y1896042D01*
X806650Y1896000D01*
X807025Y1896083D01*
X807317Y1896250D01*
X807525Y1896542D01*
X807567Y1896875D01*
X807483Y1897208D01*
X807275Y1897417D01*
X806983Y1897583D01*
X806692Y1897625D01*
X806400Y1897583D01*
X806025Y1897417D01*
X806150Y1898500D01*
X807275D01*
G01X839108Y1972167D02*
X838983Y1971917D01*
X838900Y1971625D01*
Y1971292D01*
X839025Y1970917D01*
X839233Y1970625D01*
X839483Y1970417D01*
X839900Y1970250D01*
X840275Y1970208D01*
X840650Y1970292D01*
X840900Y1970417D01*
X841150Y1970667D01*
X841317Y1970958D01*
X841400Y1971250D01*
Y1971542D01*
X841317Y1971833D01*
X841192Y1972083D01*
X841025Y1972292D01*
G01X841400Y1974350D02*
X838900D01*
X839400Y1973850D01*
G01X841400D02*
Y1974850D01*
G01Y1977450D02*
X838900D01*
X839400Y1976950D01*
G01X841400D02*
Y1977950D01*
G01Y1980550D02*
X838900D01*
X839400Y1980050D01*
G01X841400D02*
Y1981050D01*
G01X836400Y1950700D02*
Y1956200D01*
G01X844400Y1950700D02*
X836400D01*
G01Y1968300D02*
X844400D01*
G01X836400Y1962800D02*
Y1968300D01*
G01X814867Y1937592D02*
X814617Y1937717D01*
X814325Y1937800D01*
X813992D01*
X813617Y1937675D01*
X813325Y1937467D01*
X813117Y1937217D01*
X812950Y1936800D01*
X812908Y1936425D01*
X812992Y1936050D01*
X813117Y1935800D01*
X813367Y1935550D01*
X813658Y1935383D01*
X813950Y1935300D01*
X814242D01*
X814533Y1935383D01*
X814783Y1935508D01*
X814992Y1935675D01*
G01X817050Y1935300D02*
Y1937800D01*
X816550Y1937300D01*
G01Y1935300D02*
X817550D01*
G01X820150D02*
Y1937800D01*
X819650Y1937300D01*
G01Y1935300D02*
X820650D01*
G01X822458Y1937383D02*
X822708Y1937633D01*
X823000Y1937758D01*
X823333Y1937800D01*
X823750Y1937717D01*
X824042Y1937508D01*
X824125Y1937258D01*
X824083Y1937008D01*
X823917Y1936800D01*
X823083Y1936383D01*
X822708Y1936092D01*
X822458Y1935675D01*
X822375Y1935300D01*
X824125D01*
G01X836499Y1944350D02*
Y1938850D01*
G01X828499Y1944350D02*
X836499D01*
G01X828499Y1938850D02*
Y1944350D01*
G01Y1926750D02*
Y1932250D01*
G01X836499Y1926750D02*
X828499D01*
G01X836499Y1932250D02*
Y1926750D01*
G01X843999Y1895550D02*
X830999D01*
G01X793698Y1975893D02*
Y1978393D01*
X794739D01*
X795073Y1978268D01*
X795281Y1978101D01*
X795364Y1977768D01*
X795281Y1977435D01*
X795031Y1977226D01*
X794739Y1977101D01*
X793698D01*
G01X794739D02*
X795364Y1975893D01*
G01X798131D02*
Y1978393D01*
X796589Y1976601D01*
X798673D01*
G01X799939Y1977976D02*
X800189Y1978226D01*
X800481Y1978351D01*
X800814Y1978393D01*
X801231Y1978310D01*
X801523Y1978101D01*
X801606Y1977851D01*
X801564Y1977601D01*
X801398Y1977393D01*
X800564Y1976976D01*
X800189Y1976685D01*
X799939Y1976268D01*
X799856Y1975893D01*
X801606D01*
G01X803039Y1977976D02*
X803289Y1978226D01*
X803581Y1978351D01*
X803914Y1978393D01*
X804331Y1978310D01*
X804623Y1978101D01*
X804706Y1977851D01*
X804664Y1977601D01*
X804498Y1977393D01*
X803664Y1976976D01*
X803289Y1976685D01*
X803039Y1976268D01*
X802956Y1975893D01*
X804706D01*
G01X793698Y1979893D02*
Y1982393D01*
X794739D01*
X795073Y1982268D01*
X795281Y1982101D01*
X795364Y1981768D01*
X795281Y1981435D01*
X795031Y1981226D01*
X794739Y1981101D01*
X793698D01*
G01X794739D02*
X795364Y1979893D01*
G01X798131D02*
Y1982393D01*
X796589Y1980601D01*
X798673D01*
G01X799939Y1981976D02*
X800189Y1982226D01*
X800481Y1982351D01*
X800814Y1982393D01*
X801231Y1982310D01*
X801523Y1982101D01*
X801606Y1981851D01*
X801564Y1981601D01*
X801398Y1981393D01*
X800564Y1980976D01*
X800189Y1980685D01*
X799939Y1980268D01*
X799856Y1979893D01*
X801606D01*
G01X802914Y1980393D02*
X803164Y1980101D01*
X803498Y1979935D01*
X803873Y1979893D01*
X804206Y1979935D01*
X804539Y1980143D01*
X804748Y1980393D01*
X804789Y1980643D01*
X804706Y1980935D01*
X804414Y1981143D01*
X804123Y1981226D01*
X803748D01*
G01X804123D02*
X804373Y1981351D01*
X804581Y1981560D01*
X804664Y1981810D01*
X804581Y1982060D01*
X804373Y1982268D01*
X803998Y1982393D01*
X803623Y1982351D01*
X803248Y1982185D01*
G01X794032Y1987050D02*
Y1985258D01*
X794199Y1984883D01*
X794532Y1984633D01*
X794949Y1984550D01*
X795366Y1984633D01*
X795699Y1984883D01*
X795866Y1985258D01*
Y1987050D01*
G01X797257Y1986633D02*
X797507Y1986883D01*
X797799Y1987008D01*
X798132Y1987050D01*
X798549Y1986967D01*
X798841Y1986758D01*
X798924Y1986508D01*
X798882Y1986258D01*
X798716Y1986050D01*
X797882Y1985633D01*
X797507Y1985342D01*
X797257Y1984925D01*
X797174Y1984550D01*
X798924D01*
G01X918967Y53300D02*
Y55800D01*
X919967D01*
X920300Y55675D01*
X920550Y55383D01*
X920633Y55050D01*
X920550Y54717D01*
X920342Y54467D01*
X919967Y54342D01*
X918967D01*
G01X922067Y55800D02*
Y53300D01*
X923733D01*
G01X926000D02*
Y55800D01*
X925500Y55300D01*
G01Y53300D02*
X926500D01*
G01X912199Y39450D02*
X934799D01*
G01X912199Y49650D02*
Y39450D01*
G01X934799Y49650D02*
X912199D01*
G01Y39450D02*
X934799D01*
G01X912199Y49650D02*
Y39450D01*
G01X934799Y49650D02*
X912199D01*
G01X857067Y45900D02*
Y48400D01*
X858067D01*
X858400Y48275D01*
X858650Y47983D01*
X858733Y47650D01*
X858650Y47317D01*
X858442Y47067D01*
X858067Y46942D01*
X857067D01*
G01X860167Y48400D02*
Y45900D01*
X861833D01*
G01X863308Y47983D02*
X863558Y48233D01*
X863850Y48358D01*
X864183Y48400D01*
X864600Y48317D01*
X864892Y48108D01*
X864975Y47858D01*
X864933Y47608D01*
X864767Y47400D01*
X863933Y46983D01*
X863558Y46692D01*
X863308Y46275D01*
X863225Y45900D01*
X864975D01*
G01X883699Y102650D02*
X842299D01*
Y52450D01*
X883699D01*
Y102650D01*
G01X910600Y67667D02*
X908100D01*
Y68667D01*
X908225Y69000D01*
X908517Y69250D01*
X908850Y69333D01*
X909183Y69250D01*
X909433Y69042D01*
X909558Y68667D01*
Y67667D01*
G01X908308Y72517D02*
X908183Y72267D01*
X908100Y71975D01*
Y71642D01*
X908225Y71267D01*
X908433Y70975D01*
X908683Y70767D01*
X909100Y70600D01*
X909475Y70558D01*
X909850Y70642D01*
X910100Y70767D01*
X910350Y71017D01*
X910517Y71308D01*
X910600Y71600D01*
Y71892D01*
X910517Y72183D01*
X910392Y72433D01*
X910225Y72642D01*
G01X910308Y73992D02*
X910517Y74283D01*
X910600Y74617D01*
X910517Y74950D01*
X910267Y75242D01*
X909892Y75450D01*
X909517Y75533D01*
X909058D01*
X908683Y75450D01*
X908350Y75242D01*
X908183Y74992D01*
X908100Y74700D01*
X908183Y74367D01*
X908350Y74117D01*
X908600Y73950D01*
X908933Y73867D01*
X909225Y73950D01*
X909517Y74158D01*
X909683Y74408D01*
X909725Y74700D01*
X909642Y75033D01*
X909433Y75283D01*
X909058Y75533D01*
G01X908267Y128600D02*
Y131100D01*
X909267D01*
X909600Y130975D01*
X909850Y130683D01*
X909933Y130350D01*
X909850Y130017D01*
X909642Y129767D01*
X909267Y129642D01*
X908267D01*
G01X913117Y130892D02*
X912867Y131017D01*
X912575Y131100D01*
X912242D01*
X911867Y130975D01*
X911575Y130767D01*
X911367Y130517D01*
X911200Y130100D01*
X911158Y129725D01*
X911242Y129350D01*
X911367Y129100D01*
X911617Y128850D01*
X911908Y128683D01*
X912200Y128600D01*
X912492D01*
X912783Y128683D01*
X913033Y128808D01*
X913242Y128975D01*
G01X915300Y128600D02*
X915592Y128642D01*
X915925Y128767D01*
X916133Y128975D01*
X916217Y129267D01*
X916133Y129558D01*
X915883Y129808D01*
X915508Y129933D01*
X915092D01*
X914842Y130017D01*
X914633Y130225D01*
X914550Y130517D01*
X914675Y130808D01*
X914967Y131017D01*
X915300Y131100D01*
X915633Y131017D01*
X915925Y130808D01*
X916050Y130517D01*
X915967Y130225D01*
X915758Y130017D01*
X915508Y129933D01*
X915092D01*
X914717Y129808D01*
X914467Y129558D01*
X914383Y129267D01*
X914467Y128975D01*
X914675Y128767D01*
X915008Y128642D01*
X915300Y128600D01*
G01X906700Y67867D02*
X904200D01*
Y68867D01*
X904325Y69200D01*
X904617Y69450D01*
X904950Y69533D01*
X905283Y69450D01*
X905533Y69242D01*
X905658Y68867D01*
Y67867D01*
G01X904408Y72717D02*
X904283Y72467D01*
X904200Y72175D01*
Y71842D01*
X904325Y71467D01*
X904533Y71175D01*
X904783Y70967D01*
X905200Y70800D01*
X905575Y70758D01*
X905950Y70842D01*
X906200Y70967D01*
X906450Y71217D01*
X906617Y71508D01*
X906700Y71800D01*
Y72092D01*
X906617Y72383D01*
X906492Y72633D01*
X906325Y72842D01*
G01X906700Y74817D02*
X906158Y74900D01*
X905700Y75025D01*
X905283Y75192D01*
X904825Y75400D01*
X904200Y75733D01*
Y74067D01*
G01X886967Y98100D02*
Y100600D01*
X887967D01*
X888300Y100475D01*
X888550Y100183D01*
X888633Y99850D01*
X888550Y99517D01*
X888342Y99267D01*
X887967Y99142D01*
X886967D01*
G01X890067Y98100D02*
Y100600D01*
X891108D01*
X891442Y100475D01*
X891650Y100308D01*
X891733Y99975D01*
X891650Y99642D01*
X891400Y99433D01*
X891108Y99308D01*
X890067D01*
G01X891108D02*
X891733Y98100D01*
G01X893292Y98392D02*
X893583Y98183D01*
X893917Y98100D01*
X894250Y98183D01*
X894542Y98433D01*
X894750Y98808D01*
X894833Y99183D01*
Y99642D01*
X894750Y100017D01*
X894542Y100350D01*
X894292Y100517D01*
X894000Y100600D01*
X893667Y100517D01*
X893417Y100350D01*
X893250Y100100D01*
X893167Y99767D01*
X893250Y99475D01*
X893458Y99183D01*
X893708Y99017D01*
X894000Y98975D01*
X894333Y99058D01*
X894583Y99267D01*
X894833Y99642D01*
G01X907699Y101050D02*
Y105050D01*
X900299D01*
G01X887267Y93900D02*
Y96400D01*
X888267D01*
X888600Y96275D01*
X888850Y95983D01*
X888933Y95650D01*
X888850Y95317D01*
X888642Y95067D01*
X888267Y94942D01*
X887267D01*
G01X890367Y93900D02*
Y96400D01*
X891408D01*
X891742Y96275D01*
X891950Y96108D01*
X892033Y95775D01*
X891950Y95442D01*
X891700Y95233D01*
X891408Y95108D01*
X890367D01*
G01X891408D02*
X892033Y93900D01*
G01X894300D02*
X894592Y93942D01*
X894925Y94067D01*
X895133Y94275D01*
X895217Y94567D01*
X895133Y94858D01*
X894883Y95108D01*
X894508Y95233D01*
X894092D01*
X893842Y95317D01*
X893633Y95525D01*
X893550Y95817D01*
X893675Y96108D01*
X893967Y96317D01*
X894300Y96400D01*
X894633Y96317D01*
X894925Y96108D01*
X895050Y95817D01*
X894967Y95525D01*
X894758Y95317D01*
X894508Y95233D01*
X894092D01*
X893717Y95108D01*
X893467Y94858D01*
X893383Y94567D01*
X893467Y94275D01*
X893675Y94067D01*
X894008Y93942D01*
X894300Y93900D01*
G01X900299Y101050D02*
Y97050D01*
X907699D01*
G01X917200Y117667D02*
X914700D01*
Y118667D01*
X914825Y119000D01*
X915117Y119250D01*
X915450Y119333D01*
X915783Y119250D01*
X916033Y119042D01*
X916158Y118667D01*
Y117667D01*
G01X917200Y120767D02*
X914700D01*
Y121808D01*
X914825Y122142D01*
X914992Y122350D01*
X915325Y122433D01*
X915658Y122350D01*
X915867Y122100D01*
X915992Y121808D01*
Y120767D01*
G01Y121808D02*
X917200Y122433D01*
G01X916700Y123783D02*
X916992Y124033D01*
X917158Y124367D01*
X917200Y124742D01*
X917158Y125075D01*
X916950Y125408D01*
X916700Y125617D01*
X916450Y125658D01*
X916158Y125575D01*
X915950Y125283D01*
X915867Y124992D01*
Y124617D01*
G01Y124992D02*
X915742Y125242D01*
X915533Y125450D01*
X915283Y125533D01*
X915033Y125450D01*
X914825Y125242D01*
X914700Y124867D01*
X914742Y124492D01*
X914908Y124117D01*
G01X914499Y106350D02*
X918499D01*
Y113750D01*
G01X925200Y117417D02*
X922700D01*
Y118417D01*
X922825Y118750D01*
X923117Y119000D01*
X923450Y119083D01*
X923783Y119000D01*
X924033Y118792D01*
X924158Y118417D01*
Y117417D01*
G01X925200Y120517D02*
X922700D01*
Y121558D01*
X922825Y121892D01*
X922992Y122100D01*
X923325Y122183D01*
X923658Y122100D01*
X923867Y121850D01*
X923992Y121558D01*
Y120517D01*
G01Y121558D02*
X925200Y122183D01*
G01Y124450D02*
X922700D01*
X923200Y123950D01*
G01X925200D02*
Y124950D01*
G01Y128050D02*
X922700D01*
X924492Y126508D01*
Y128592D01*
G01X922499Y106350D02*
X926499D01*
Y113750D01*
G01X913300Y117367D02*
X910800D01*
Y118367D01*
X910925Y118700D01*
X911217Y118950D01*
X911550Y119033D01*
X911883Y118950D01*
X912133Y118742D01*
X912258Y118367D01*
Y117367D01*
G01X913300Y120467D02*
X910800D01*
Y121508D01*
X910925Y121842D01*
X911092Y122050D01*
X911425Y122133D01*
X911758Y122050D01*
X911967Y121800D01*
X912092Y121508D01*
Y120467D01*
G01Y121508D02*
X913300Y122133D01*
G01X912925Y123483D02*
X913133Y123733D01*
X913258Y124025D01*
X913300Y124400D01*
X913217Y124775D01*
X913050Y125067D01*
X912758Y125275D01*
X912425Y125317D01*
X912092Y125233D01*
X911883Y125025D01*
X911717Y124733D01*
X911675Y124442D01*
X911717Y124150D01*
X911883Y123775D01*
X910800Y123900D01*
Y125025D01*
G01X914499Y113750D02*
X910499D01*
Y106350D01*
G01X902600Y67917D02*
X900100D01*
Y68917D01*
X900225Y69250D01*
X900517Y69500D01*
X900850Y69583D01*
X901183Y69500D01*
X901433Y69292D01*
X901558Y68917D01*
Y67917D01*
G01X902600Y71017D02*
X900100D01*
Y72058D01*
X900225Y72392D01*
X900392Y72600D01*
X900725Y72683D01*
X901058Y72600D01*
X901267Y72350D01*
X901392Y72058D01*
Y71017D01*
G01Y72058D02*
X902600Y72683D01*
G01Y75450D02*
X900100D01*
X901892Y73908D01*
Y75992D01*
G01X902308Y77342D02*
X902517Y77633D01*
X902600Y77967D01*
X902517Y78300D01*
X902267Y78592D01*
X901892Y78800D01*
X901517Y78883D01*
X901058D01*
X900683Y78800D01*
X900350Y78592D01*
X900183Y78342D01*
X900100Y78050D01*
X900183Y77717D01*
X900350Y77467D01*
X900600Y77300D01*
X900933Y77217D01*
X901225Y77300D01*
X901517Y77508D01*
X901683Y77758D01*
X901725Y78050D01*
X901642Y78383D01*
X901433Y78633D01*
X901058Y78883D01*
G01X898499Y82850D02*
X902499D01*
Y90250D01*
G01X886917Y102400D02*
Y104900D01*
X887917D01*
X888250Y104775D01*
X888500Y104483D01*
X888583Y104150D01*
X888500Y103817D01*
X888292Y103567D01*
X887917Y103442D01*
X886917D01*
G01X890017Y102400D02*
Y104900D01*
X891058D01*
X891392Y104775D01*
X891600Y104608D01*
X891683Y104275D01*
X891600Y103942D01*
X891350Y103733D01*
X891058Y103608D01*
X890017D01*
G01X891058D02*
X891683Y102400D01*
G01X893950D02*
Y104900D01*
X893450Y104400D01*
G01Y102400D02*
X894450D01*
G01X896133Y102775D02*
X896383Y102567D01*
X896675Y102442D01*
X897050Y102400D01*
X897425Y102483D01*
X897717Y102650D01*
X897925Y102942D01*
X897967Y103275D01*
X897883Y103608D01*
X897675Y103817D01*
X897383Y103983D01*
X897092Y104025D01*
X896800Y103983D01*
X896425Y103817D01*
X896550Y104900D01*
X897675D01*
G01X907699Y105050D02*
Y109050D01*
X900299D01*
G01X921200Y117467D02*
X918700D01*
Y118467D01*
X918825Y118800D01*
X919117Y119050D01*
X919450Y119133D01*
X919783Y119050D01*
X920033Y118842D01*
X920158Y118467D01*
Y117467D01*
G01X921200Y120567D02*
X918700D01*
Y121608D01*
X918825Y121942D01*
X918992Y122150D01*
X919325Y122233D01*
X919658Y122150D01*
X919867Y121900D01*
X919992Y121608D01*
Y120567D01*
G01Y121608D02*
X921200Y122233D01*
G01X919117Y123708D02*
X918867Y123958D01*
X918742Y124250D01*
X918700Y124583D01*
X918783Y125000D01*
X918992Y125292D01*
X919242Y125375D01*
X919492Y125333D01*
X919700Y125167D01*
X920117Y124333D01*
X920408Y123958D01*
X920825Y123708D01*
X921200Y123625D01*
Y125375D01*
G01X922499Y113750D02*
X918499D01*
Y106350D01*
G01X899767Y118100D02*
Y120600D01*
X900767D01*
X901100Y120475D01*
X901350Y120183D01*
X901433Y119850D01*
X901350Y119517D01*
X901142Y119267D01*
X900767Y119142D01*
X899767D01*
G01X902867Y118100D02*
Y120600D01*
X903908D01*
X904242Y120475D01*
X904450Y120308D01*
X904533Y119975D01*
X904450Y119642D01*
X904200Y119433D01*
X903908Y119308D01*
X902867D01*
G01X903908D02*
X904533Y118100D01*
G01X907300D02*
Y120600D01*
X905758Y118808D01*
X907842D01*
G01X886350Y91400D02*
Y88900D01*
G01X885392Y91400D02*
X887308D01*
G01X888617Y88900D02*
Y91400D01*
X889617D01*
X889950Y91275D01*
X890200Y90983D01*
X890283Y90650D01*
X890200Y90317D01*
X889992Y90067D01*
X889617Y89942D01*
X888617D01*
G01X891758Y90983D02*
X892008Y91233D01*
X892300Y91358D01*
X892633Y91400D01*
X893050Y91317D01*
X893342Y91108D01*
X893425Y90858D01*
X893383Y90608D01*
X893217Y90400D01*
X892383Y89983D01*
X892008Y89692D01*
X891758Y89275D01*
X891675Y88900D01*
X893425D01*
G01X894858Y90983D02*
X895108Y91233D01*
X895400Y91358D01*
X895733Y91400D01*
X896150Y91317D01*
X896442Y91108D01*
X896525Y90858D01*
X896483Y90608D01*
X896317Y90400D01*
X895483Y89983D01*
X895108Y89692D01*
X894858Y89275D01*
X894775Y88900D01*
X896525D01*
G01X886450Y87400D02*
Y84900D01*
G01X885492Y87400D02*
X887408D01*
G01X888717Y84900D02*
Y87400D01*
X889717D01*
X890050Y87275D01*
X890300Y86983D01*
X890383Y86650D01*
X890300Y86317D01*
X890092Y86067D01*
X889717Y85942D01*
X888717D01*
G01X892650Y84900D02*
Y87400D01*
X892150Y86900D01*
G01Y84900D02*
X893150D01*
G01X895042Y85192D02*
X895333Y84983D01*
X895667Y84900D01*
X896000Y84983D01*
X896292Y85233D01*
X896500Y85608D01*
X896583Y85983D01*
Y86442D01*
X896500Y86817D01*
X896292Y87150D01*
X896042Y87317D01*
X895750Y87400D01*
X895417Y87317D01*
X895167Y87150D01*
X895000Y86900D01*
X894917Y86567D01*
X895000Y86275D01*
X895208Y85983D01*
X895458Y85817D01*
X895750Y85775D01*
X896083Y85858D01*
X896333Y86067D01*
X896583Y86442D01*
G01X842999Y121250D02*
Y126750D01*
G01X850999Y121250D02*
X842999D01*
G01X850999Y126750D02*
Y121250D01*
G01Y138850D02*
Y133350D01*
G01X842999Y138850D02*
X850999D01*
G01X842999Y133350D02*
Y138850D01*
G01X894517Y146400D02*
Y148900D01*
X895517D01*
X895850Y148775D01*
X896100Y148483D01*
X896183Y148150D01*
X896100Y147817D01*
X895892Y147567D01*
X895517Y147442D01*
X894517D01*
G01X899367Y148692D02*
X899117Y148817D01*
X898825Y148900D01*
X898492D01*
X898117Y148775D01*
X897825Y148567D01*
X897617Y148317D01*
X897450Y147900D01*
X897408Y147525D01*
X897492Y147150D01*
X897617Y146900D01*
X897867Y146650D01*
X898158Y146483D01*
X898450Y146400D01*
X898742D01*
X899033Y146483D01*
X899283Y146608D01*
X899492Y146775D01*
G01X901550Y146400D02*
Y148900D01*
X901050Y148400D01*
G01Y146400D02*
X902050D01*
G01X903858Y148483D02*
X904108Y148733D01*
X904400Y148858D01*
X904733Y148900D01*
X905150Y148817D01*
X905442Y148608D01*
X905525Y148358D01*
X905483Y148108D01*
X905317Y147900D01*
X904483Y147483D01*
X904108Y147192D01*
X903858Y146775D01*
X903775Y146400D01*
X905525D01*
G01X892999Y122250D02*
Y127750D01*
G01X900999Y122250D02*
X892999D01*
G01X900999Y127750D02*
Y122250D01*
G01Y139850D02*
Y134350D01*
G01X892999Y139850D02*
X900999D01*
G01X892999Y134350D02*
Y139850D01*
G01X910100Y134367D02*
X907600D01*
Y135367D01*
X907725Y135700D01*
X908017Y135950D01*
X908350Y136033D01*
X908683Y135950D01*
X908933Y135742D01*
X909058Y135367D01*
Y134367D01*
G01X910100Y137467D02*
X907600D01*
Y138508D01*
X907725Y138842D01*
X907892Y139050D01*
X908225Y139133D01*
X908558Y139050D01*
X908767Y138800D01*
X908892Y138508D01*
Y137467D01*
G01Y138508D02*
X910100Y139133D01*
G01X909058Y140608D02*
X908767Y140900D01*
X908600Y141150D01*
X908517Y141483D01*
X908600Y141775D01*
X908767Y141983D01*
X909017Y142150D01*
X909308Y142192D01*
X909558Y142150D01*
X909808Y141983D01*
X910017Y141733D01*
X910100Y141442D01*
X910017Y141108D01*
X909767Y140817D01*
X909392Y140650D01*
X908975Y140608D01*
X908433Y140692D01*
X908142Y140817D01*
X907850Y141025D01*
X907642Y141317D01*
X907600Y141608D01*
X907683Y141900D01*
X907892Y142108D01*
G01X901499Y126350D02*
X905499D01*
Y133750D01*
G01X914649Y76550D02*
Y71550D01*
X919649D01*
G01X915656Y77676D02*
X912656D01*
G01X915656Y87519D02*
X913656D01*
G01X870999Y107850D02*
Y119050D01*
G01X852999Y107850D02*
X870999D01*
G01X852999Y119050D02*
Y107850D01*
G01X870999Y146250D02*
Y135050D01*
G01X852999Y146250D02*
X870999D01*
G01X852999Y135050D02*
Y146250D01*
G01X891499Y107850D02*
Y119050D01*
G01X873499Y107850D02*
X891499D01*
G01X873499Y119050D02*
Y107850D01*
G01X891499Y146250D02*
Y135050D01*
G01X873499Y146250D02*
X891499D01*
G01X873499Y135050D02*
Y146250D01*
G01X843245Y225716D02*
X842995Y225841D01*
X842703Y225924D01*
X842370D01*
X841995Y225799D01*
X841703Y225591D01*
X841495Y225341D01*
X841328Y224924D01*
X841286Y224549D01*
X841370Y224174D01*
X841495Y223924D01*
X841745Y223674D01*
X842036Y223507D01*
X842328Y223424D01*
X842620D01*
X842911Y223507D01*
X843161Y223632D01*
X843370Y223799D01*
G01X845428Y223424D02*
Y225924D01*
X844928Y225424D01*
G01Y223424D02*
X845928D01*
G01X847736Y224466D02*
X848028Y224757D01*
X848278Y224924D01*
X848611Y225007D01*
X848903Y224924D01*
X849111Y224757D01*
X849278Y224507D01*
X849320Y224216D01*
X849278Y223966D01*
X849111Y223716D01*
X848861Y223507D01*
X848570Y223424D01*
X848236Y223507D01*
X847945Y223757D01*
X847778Y224132D01*
X847736Y224549D01*
X847820Y225091D01*
X847945Y225382D01*
X848153Y225674D01*
X848445Y225882D01*
X848736Y225924D01*
X849028Y225841D01*
X849236Y225632D01*
G01X850836Y224466D02*
X851128Y224757D01*
X851378Y224924D01*
X851711Y225007D01*
X852003Y224924D01*
X852211Y224757D01*
X852378Y224507D01*
X852420Y224216D01*
X852378Y223966D01*
X852211Y223716D01*
X851961Y223507D01*
X851670Y223424D01*
X851336Y223507D01*
X851045Y223757D01*
X850878Y224132D01*
X850836Y224549D01*
X850920Y225091D01*
X851045Y225382D01*
X851253Y225674D01*
X851545Y225882D01*
X851836Y225924D01*
X852128Y225841D01*
X852336Y225632D01*
G01X843167Y229992D02*
X842917Y230117D01*
X842625Y230200D01*
X842292D01*
X841917Y230075D01*
X841625Y229867D01*
X841417Y229617D01*
X841250Y229200D01*
X841208Y228825D01*
X841292Y228450D01*
X841417Y228200D01*
X841667Y227950D01*
X841958Y227783D01*
X842250Y227700D01*
X842542D01*
X842833Y227783D01*
X843083Y227908D01*
X843292Y228075D01*
G01X845350Y227700D02*
Y230200D01*
X844850Y229700D01*
G01Y227700D02*
X845850D01*
G01X847658Y228742D02*
X847950Y229033D01*
X848200Y229200D01*
X848533Y229283D01*
X848825Y229200D01*
X849033Y229033D01*
X849200Y228783D01*
X849242Y228492D01*
X849200Y228242D01*
X849033Y227992D01*
X848783Y227783D01*
X848492Y227700D01*
X848158Y227783D01*
X847867Y228033D01*
X847700Y228408D01*
X847658Y228825D01*
X847742Y229367D01*
X847867Y229658D01*
X848075Y229950D01*
X848367Y230158D01*
X848658Y230200D01*
X848950Y230117D01*
X849158Y229908D01*
G01X851467Y227700D02*
X851550Y228242D01*
X851675Y228700D01*
X851842Y229117D01*
X852050Y229575D01*
X852383Y230200D01*
X850717D01*
G01X890517Y170563D02*
Y168063D01*
X892183D01*
G01X895283D02*
X893617D01*
Y170563D01*
X895283D01*
G01X894617Y169355D02*
X893617D01*
G01X896633Y168063D02*
Y170563D01*
X897467D01*
X897800Y170438D01*
X898050Y170271D01*
X898258Y170021D01*
X898425Y169730D01*
X898467Y169313D01*
X898425Y168896D01*
X898258Y168605D01*
X898050Y168355D01*
X897800Y168188D01*
X897467Y168063D01*
X896633D01*
G01X899733Y168438D02*
X899983Y168230D01*
X900275Y168105D01*
X900650Y168063D01*
X901025Y168146D01*
X901317Y168313D01*
X901525Y168605D01*
X901567Y168938D01*
X901483Y169271D01*
X901275Y169480D01*
X900983Y169646D01*
X900692Y169688D01*
X900400Y169646D01*
X900025Y169480D01*
X900150Y170563D01*
X901275D01*
G01X901369Y165847D02*
Y158247D01*
X889969D01*
Y165847D01*
X901369D01*
G01X857245Y161924D02*
Y164424D01*
X858286D01*
X858620Y164299D01*
X858828Y164132D01*
X858911Y163799D01*
X858828Y163466D01*
X858578Y163257D01*
X858286Y163132D01*
X857245D01*
G01X858286D02*
X858911Y161924D01*
G01X861178D02*
Y164424D01*
X860678Y163924D01*
G01Y161924D02*
X861678D01*
G01X863361Y162299D02*
X863611Y162091D01*
X863903Y161966D01*
X864278Y161924D01*
X864653Y162007D01*
X864945Y162174D01*
X865153Y162466D01*
X865195Y162799D01*
X865111Y163132D01*
X864903Y163341D01*
X864611Y163507D01*
X864320Y163549D01*
X864028Y163507D01*
X863653Y163341D01*
X863778Y164424D01*
X864903D01*
G01X867295Y161924D02*
X867378Y162466D01*
X867503Y162924D01*
X867670Y163341D01*
X867878Y163799D01*
X868211Y164424D01*
X866545D01*
G01X869528Y165924D02*
Y161924D01*
X876928D01*
G01X907296Y175854D02*
Y178354D01*
X908337D01*
X908671Y178229D01*
X908879Y178062D01*
X908962Y177729D01*
X908879Y177396D01*
X908629Y177187D01*
X908337Y177062D01*
X907296D01*
G01X908337D02*
X908962Y175854D01*
G01X911229D02*
Y178354D01*
X910729Y177854D01*
G01Y175854D02*
X911729D01*
G01X913412Y176229D02*
X913662Y176021D01*
X913954Y175896D01*
X914329Y175854D01*
X914704Y175937D01*
X914996Y176104D01*
X915204Y176396D01*
X915246Y176729D01*
X915162Y177062D01*
X914954Y177271D01*
X914662Y177437D01*
X914371Y177479D01*
X914079Y177437D01*
X913704Y177271D01*
X913829Y178354D01*
X914954D01*
G01X917429Y175854D02*
X917721Y175896D01*
X918054Y176021D01*
X918262Y176229D01*
X918346Y176521D01*
X918262Y176812D01*
X918012Y177062D01*
X917637Y177187D01*
X917221D01*
X916971Y177271D01*
X916762Y177479D01*
X916679Y177771D01*
X916804Y178062D01*
X917096Y178271D01*
X917429Y178354D01*
X917762Y178271D01*
X918054Y178062D01*
X918179Y177771D01*
X918096Y177479D01*
X917887Y177271D01*
X917637Y177187D01*
X917221D01*
X916846Y177062D01*
X916596Y176812D01*
X916512Y176521D01*
X916596Y176229D01*
X916804Y176021D01*
X917137Y175896D01*
X917429Y175854D01*
G01X920528Y170424D02*
Y166424D01*
X927928D01*
G01X857245Y157924D02*
Y160424D01*
X858286D01*
X858620Y160299D01*
X858828Y160132D01*
X858911Y159799D01*
X858828Y159466D01*
X858578Y159257D01*
X858286Y159132D01*
X857245D01*
G01X858286D02*
X858911Y157924D01*
G01X861178D02*
Y160424D01*
X860678Y159924D01*
G01Y157924D02*
X861678D01*
G01X863361Y158299D02*
X863611Y158091D01*
X863903Y157966D01*
X864278Y157924D01*
X864653Y158007D01*
X864945Y158174D01*
X865153Y158466D01*
X865195Y158799D01*
X865111Y159132D01*
X864903Y159341D01*
X864611Y159507D01*
X864320Y159549D01*
X864028Y159507D01*
X863653Y159341D01*
X863778Y160424D01*
X864903D01*
G01X866670Y158216D02*
X866961Y158007D01*
X867295Y157924D01*
X867628Y158007D01*
X867920Y158257D01*
X868128Y158632D01*
X868211Y159007D01*
Y159466D01*
X868128Y159841D01*
X867920Y160174D01*
X867670Y160341D01*
X867378Y160424D01*
X867045Y160341D01*
X866795Y160174D01*
X866628Y159924D01*
X866545Y159591D01*
X866628Y159299D01*
X866836Y159007D01*
X867086Y158841D01*
X867378Y158799D01*
X867711Y158882D01*
X867961Y159091D01*
X868211Y159466D01*
G01X869528Y161924D02*
Y157924D01*
X876928D01*
G01X907296Y171854D02*
Y174354D01*
X908337D01*
X908671Y174229D01*
X908879Y174062D01*
X908962Y173729D01*
X908879Y173396D01*
X908629Y173187D01*
X908337Y173062D01*
X907296D01*
G01X908337D02*
X908962Y171854D01*
G01X911229D02*
Y174354D01*
X910729Y173854D01*
G01Y171854D02*
X911729D01*
G01X913537Y172896D02*
X913829Y173187D01*
X914079Y173354D01*
X914412Y173437D01*
X914704Y173354D01*
X914912Y173187D01*
X915079Y172937D01*
X915121Y172646D01*
X915079Y172396D01*
X914912Y172146D01*
X914662Y171937D01*
X914371Y171854D01*
X914037Y171937D01*
X913746Y172187D01*
X913579Y172562D01*
X913537Y172979D01*
X913621Y173521D01*
X913746Y173812D01*
X913954Y174104D01*
X914246Y174312D01*
X914537Y174354D01*
X914829Y174271D01*
X915037Y174062D01*
G01X917429Y174354D02*
X917096Y174271D01*
X916846Y174062D01*
X916679Y173812D01*
X916554Y173479D01*
X916512Y173104D01*
X916554Y172729D01*
X916679Y172396D01*
X916846Y172146D01*
X917096Y171937D01*
X917429Y171854D01*
X917762Y171937D01*
X918012Y172146D01*
X918179Y172396D01*
X918304Y172729D01*
X918346Y173104D01*
X918304Y173479D01*
X918179Y173812D01*
X918012Y174062D01*
X917762Y174271D01*
X917429Y174354D01*
G01X920528Y166424D02*
Y162424D01*
X927928D01*
G01X848143Y201293D02*
X845643D01*
Y202334D01*
X845768Y202668D01*
X845935Y202876D01*
X846268Y202959D01*
X846601Y202876D01*
X846810Y202626D01*
X846935Y202334D01*
Y201293D01*
G01Y202334D02*
X848143Y202959D01*
G01X847643Y204309D02*
X847935Y204559D01*
X848101Y204893D01*
X848143Y205268D01*
X848101Y205601D01*
X847893Y205934D01*
X847643Y206143D01*
X847393Y206184D01*
X847101Y206101D01*
X846893Y205809D01*
X846810Y205518D01*
Y205143D01*
G01Y205518D02*
X846685Y205768D01*
X846476Y205976D01*
X846226Y206059D01*
X845976Y205976D01*
X845768Y205768D01*
X845643Y205393D01*
X845685Y205018D01*
X845851Y204643D01*
G01X847643Y207409D02*
X847935Y207659D01*
X848101Y207993D01*
X848143Y208368D01*
X848101Y208701D01*
X847893Y209034D01*
X847643Y209243D01*
X847393Y209284D01*
X847101Y209201D01*
X846893Y208909D01*
X846810Y208618D01*
Y208243D01*
G01Y208618D02*
X846685Y208868D01*
X846476Y209076D01*
X846226Y209159D01*
X845976Y209076D01*
X845768Y208868D01*
X845643Y208493D01*
X845685Y208118D01*
X845851Y207743D01*
G01X845643Y211426D02*
X845726Y211093D01*
X845935Y210843D01*
X846185Y210676D01*
X846518Y210551D01*
X846893Y210509D01*
X847268Y210551D01*
X847601Y210676D01*
X847851Y210843D01*
X848060Y211093D01*
X848143Y211426D01*
X848060Y211759D01*
X847851Y212009D01*
X847601Y212176D01*
X847268Y212301D01*
X846893Y212343D01*
X846518Y212301D01*
X846185Y212176D01*
X845935Y212009D01*
X845726Y211759D01*
X845643Y211426D01*
G01X843643Y201293D02*
X841143D01*
Y202334D01*
X841268Y202668D01*
X841435Y202876D01*
X841768Y202959D01*
X842101Y202876D01*
X842310Y202626D01*
X842435Y202334D01*
Y201293D01*
G01Y202334D02*
X843643Y202959D01*
G01X843143Y204309D02*
X843435Y204559D01*
X843601Y204893D01*
X843643Y205268D01*
X843601Y205601D01*
X843393Y205934D01*
X843143Y206143D01*
X842893Y206184D01*
X842601Y206101D01*
X842393Y205809D01*
X842310Y205518D01*
Y205143D01*
G01Y205518D02*
X842185Y205768D01*
X841976Y205976D01*
X841726Y206059D01*
X841476Y205976D01*
X841268Y205768D01*
X841143Y205393D01*
X841185Y205018D01*
X841351Y204643D01*
G01X843143Y207409D02*
X843435Y207659D01*
X843601Y207993D01*
X843643Y208368D01*
X843601Y208701D01*
X843393Y209034D01*
X843143Y209243D01*
X842893Y209284D01*
X842601Y209201D01*
X842393Y208909D01*
X842310Y208618D01*
Y208243D01*
G01Y208618D02*
X842185Y208868D01*
X841976Y209076D01*
X841726Y209159D01*
X841476Y209076D01*
X841268Y208868D01*
X841143Y208493D01*
X841185Y208118D01*
X841351Y207743D01*
G01X843268Y210509D02*
X843476Y210759D01*
X843601Y211051D01*
X843643Y211426D01*
X843560Y211801D01*
X843393Y212093D01*
X843101Y212301D01*
X842768Y212343D01*
X842435Y212259D01*
X842226Y212051D01*
X842060Y211759D01*
X842018Y211468D01*
X842060Y211176D01*
X842226Y210801D01*
X841143Y210926D01*
Y212051D01*
G01X907067Y179980D02*
Y182480D01*
X908108D01*
X908442Y182355D01*
X908650Y182188D01*
X908733Y181855D01*
X908650Y181522D01*
X908400Y181313D01*
X908108Y181188D01*
X907067D01*
G01X908108D02*
X908733Y179980D01*
G01X911000D02*
Y182480D01*
X910500Y181980D01*
G01Y179980D02*
X911500D01*
G01X913183Y180355D02*
X913433Y180147D01*
X913725Y180022D01*
X914100Y179980D01*
X914475Y180063D01*
X914767Y180230D01*
X914975Y180522D01*
X915017Y180855D01*
X914933Y181188D01*
X914725Y181397D01*
X914433Y181563D01*
X914142Y181605D01*
X913850Y181563D01*
X913475Y181397D01*
X913600Y182480D01*
X914725D01*
G01X916408Y181022D02*
X916700Y181313D01*
X916950Y181480D01*
X917283Y181563D01*
X917575Y181480D01*
X917783Y181313D01*
X917950Y181063D01*
X917992Y180772D01*
X917950Y180522D01*
X917783Y180272D01*
X917533Y180063D01*
X917242Y179980D01*
X916908Y180063D01*
X916617Y180313D01*
X916450Y180688D01*
X916408Y181105D01*
X916492Y181647D01*
X916617Y181938D01*
X916825Y182230D01*
X917117Y182438D01*
X917408Y182480D01*
X917700Y182397D01*
X917908Y182188D01*
G01X920299Y174550D02*
Y170550D01*
X927699D01*
G01X872969Y185817D02*
Y347017D01*
X886569D01*
Y359967D01*
X904769D01*
Y347017D01*
X933669D01*
Y336667D01*
X926969D01*
Y196167D01*
X933669D01*
Y185817D01*
X904769D01*
Y172867D01*
X886569D01*
Y185817D01*
X872969D01*
G01X843367Y249792D02*
X843117Y249917D01*
X842825Y250000D01*
X842492D01*
X842117Y249875D01*
X841825Y249667D01*
X841617Y249417D01*
X841450Y249000D01*
X841408Y248625D01*
X841492Y248250D01*
X841617Y248000D01*
X841867Y247750D01*
X842158Y247583D01*
X842450Y247500D01*
X842742D01*
X843033Y247583D01*
X843283Y247708D01*
X843492Y247875D01*
G01X845550Y247500D02*
Y250000D01*
X845050Y249500D01*
G01Y247500D02*
X846050D01*
G01X847858Y248542D02*
X848150Y248833D01*
X848400Y249000D01*
X848733Y249083D01*
X849025Y249000D01*
X849233Y248833D01*
X849400Y248583D01*
X849442Y248292D01*
X849400Y248042D01*
X849233Y247792D01*
X848983Y247583D01*
X848692Y247500D01*
X848358Y247583D01*
X848067Y247833D01*
X847900Y248208D01*
X847858Y248625D01*
X847942Y249167D01*
X848067Y249458D01*
X848275Y249750D01*
X848567Y249958D01*
X848858Y250000D01*
X849150Y249917D01*
X849358Y249708D01*
G01X851750Y247500D02*
X852042Y247542D01*
X852375Y247667D01*
X852583Y247875D01*
X852667Y248167D01*
X852583Y248458D01*
X852333Y248708D01*
X851958Y248833D01*
X851542D01*
X851292Y248917D01*
X851083Y249125D01*
X851000Y249417D01*
X851125Y249708D01*
X851417Y249917D01*
X851750Y250000D01*
X852083Y249917D01*
X852375Y249708D01*
X852500Y249417D01*
X852417Y249125D01*
X852208Y248917D01*
X851958Y248833D01*
X851542D01*
X851167Y248708D01*
X850917Y248458D01*
X850833Y248167D01*
X850917Y247875D01*
X851125Y247667D01*
X851458Y247542D01*
X851750Y247500D01*
G01X843266Y253842D02*
X843016Y253967D01*
X842724Y254050D01*
X842391D01*
X842016Y253925D01*
X841724Y253717D01*
X841516Y253467D01*
X841349Y253050D01*
X841307Y252675D01*
X841391Y252300D01*
X841516Y252050D01*
X841766Y251800D01*
X842057Y251633D01*
X842349Y251550D01*
X842641D01*
X842932Y251633D01*
X843182Y251758D01*
X843391Y251925D01*
G01X845449Y251550D02*
Y254050D01*
X844949Y253550D01*
G01Y251550D02*
X845949D01*
G01X847757Y252592D02*
X848049Y252883D01*
X848299Y253050D01*
X848632Y253133D01*
X848924Y253050D01*
X849132Y252883D01*
X849299Y252633D01*
X849341Y252342D01*
X849299Y252092D01*
X849132Y251842D01*
X848882Y251633D01*
X848591Y251550D01*
X848257Y251633D01*
X847966Y251883D01*
X847799Y252258D01*
X847757Y252675D01*
X847841Y253217D01*
X847966Y253508D01*
X848174Y253800D01*
X848466Y254008D01*
X848757Y254050D01*
X849049Y253967D01*
X849257Y253758D01*
G01X850941Y251842D02*
X851232Y251633D01*
X851566Y251550D01*
X851899Y251633D01*
X852191Y251883D01*
X852399Y252258D01*
X852482Y252633D01*
Y253092D01*
X852399Y253467D01*
X852191Y253800D01*
X851941Y253967D01*
X851649Y254050D01*
X851316Y253967D01*
X851066Y253800D01*
X850899Y253550D01*
X850816Y253217D01*
X850899Y252925D01*
X851107Y252633D01*
X851357Y252467D01*
X851649Y252425D01*
X851982Y252508D01*
X852232Y252717D01*
X852482Y253092D01*
G01X866208Y271767D02*
X866083Y271517D01*
X866000Y271225D01*
Y270892D01*
X866125Y270517D01*
X866333Y270225D01*
X866583Y270017D01*
X867000Y269850D01*
X867375Y269808D01*
X867750Y269892D01*
X868000Y270017D01*
X868250Y270267D01*
X868417Y270558D01*
X868500Y270850D01*
Y271142D01*
X868417Y271433D01*
X868292Y271683D01*
X868125Y271892D01*
G01X868500Y273950D02*
X866000D01*
X866500Y273450D01*
G01X868500D02*
Y274450D01*
G01Y276967D02*
X867958Y277050D01*
X867500Y277175D01*
X867083Y277342D01*
X866625Y277550D01*
X866000Y277883D01*
Y276217D01*
G01X868500Y280150D02*
X868458Y280442D01*
X868333Y280775D01*
X868125Y280983D01*
X867833Y281067D01*
X867542Y280983D01*
X867292Y280733D01*
X867167Y280358D01*
Y279942D01*
X867083Y279692D01*
X866875Y279483D01*
X866583Y279400D01*
X866292Y279525D01*
X866083Y279817D01*
X866000Y280150D01*
X866083Y280483D01*
X866292Y280775D01*
X866583Y280900D01*
X866875Y280817D01*
X867083Y280608D01*
X867167Y280358D01*
Y279942D01*
X867292Y279567D01*
X867542Y279317D01*
X867833Y279233D01*
X868125Y279317D01*
X868333Y279525D01*
X868458Y279858D01*
X868500Y280150D01*
G01X866707Y303817D02*
X866582Y303567D01*
X866499Y303275D01*
Y302942D01*
X866624Y302567D01*
X866832Y302275D01*
X867082Y302067D01*
X867499Y301900D01*
X867874Y301858D01*
X868249Y301942D01*
X868499Y302067D01*
X868749Y302317D01*
X868916Y302608D01*
X868999Y302900D01*
Y303192D01*
X868916Y303483D01*
X868791Y303733D01*
X868624Y303942D01*
G01X868999Y306000D02*
X866499D01*
X866999Y305500D01*
G01X868999D02*
Y306500D01*
G01Y309017D02*
X868457Y309100D01*
X867999Y309225D01*
X867582Y309392D01*
X867124Y309600D01*
X866499Y309933D01*
Y308267D01*
G01X866916Y311408D02*
X866666Y311658D01*
X866541Y311950D01*
X866499Y312283D01*
X866582Y312700D01*
X866791Y312992D01*
X867041Y313075D01*
X867291Y313033D01*
X867499Y312867D01*
X867916Y312033D01*
X868207Y311658D01*
X868624Y311408D01*
X868999Y311325D01*
Y313075D01*
G01X864499Y285067D02*
X861999D01*
Y286108D01*
X862124Y286442D01*
X862291Y286650D01*
X862624Y286733D01*
X862957Y286650D01*
X863166Y286400D01*
X863291Y286108D01*
Y285067D01*
G01Y286108D02*
X864499Y286733D01*
G01Y289000D02*
X861999D01*
X862499Y288500D01*
G01X864499D02*
Y289500D01*
G01X863457Y291308D02*
X863166Y291600D01*
X862999Y291850D01*
X862916Y292183D01*
X862999Y292475D01*
X863166Y292683D01*
X863416Y292850D01*
X863707Y292892D01*
X863957Y292850D01*
X864207Y292683D01*
X864416Y292433D01*
X864499Y292142D01*
X864416Y291808D01*
X864166Y291517D01*
X863791Y291350D01*
X863374Y291308D01*
X862832Y291392D01*
X862541Y291517D01*
X862249Y291725D01*
X862041Y292017D01*
X861999Y292308D01*
X862082Y292600D01*
X862291Y292808D01*
G01X864499Y295200D02*
X861999D01*
X862499Y294700D01*
G01X864499D02*
Y295700D01*
G01X860228Y283624D02*
Y296624D01*
G01X851017Y262000D02*
Y264500D01*
X852058D01*
X852392Y264375D01*
X852600Y264208D01*
X852683Y263875D01*
X852600Y263542D01*
X852350Y263333D01*
X852058Y263208D01*
X851017D01*
G01X852058D02*
X852683Y262000D01*
G01X854950D02*
Y264500D01*
X854450Y264000D01*
G01Y262000D02*
X855450D01*
G01X857258Y263042D02*
X857550Y263333D01*
X857800Y263500D01*
X858133Y263583D01*
X858425Y263500D01*
X858633Y263333D01*
X858800Y263083D01*
X858842Y262792D01*
X858800Y262542D01*
X858633Y262292D01*
X858383Y262083D01*
X858092Y262000D01*
X857758Y262083D01*
X857467Y262333D01*
X857300Y262708D01*
X857258Y263125D01*
X857342Y263667D01*
X857467Y263958D01*
X857675Y264250D01*
X857967Y264458D01*
X858258Y264500D01*
X858550Y264417D01*
X858758Y264208D01*
G01X860358Y264083D02*
X860608Y264333D01*
X860900Y264458D01*
X861233Y264500D01*
X861650Y264417D01*
X861942Y264208D01*
X862025Y263958D01*
X861983Y263708D01*
X861817Y263500D01*
X860983Y263083D01*
X860608Y262792D01*
X860358Y262375D01*
X860275Y262000D01*
X862025D01*
G01X843778Y282924D02*
Y278924D01*
X851178D01*
G01X851017Y258000D02*
Y260500D01*
X852058D01*
X852392Y260375D01*
X852600Y260208D01*
X852683Y259875D01*
X852600Y259542D01*
X852350Y259333D01*
X852058Y259208D01*
X851017D01*
G01X852058D02*
X852683Y258000D01*
G01X854033Y258500D02*
X854283Y258208D01*
X854617Y258042D01*
X854992Y258000D01*
X855325Y258042D01*
X855658Y258250D01*
X855867Y258500D01*
X855908Y258750D01*
X855825Y259042D01*
X855533Y259250D01*
X855242Y259333D01*
X854867D01*
G01X855242D02*
X855492Y259458D01*
X855700Y259667D01*
X855783Y259917D01*
X855700Y260167D01*
X855492Y260375D01*
X855117Y260500D01*
X854742Y260458D01*
X854367Y260292D01*
G01X857967Y258000D02*
X858050Y258542D01*
X858175Y259000D01*
X858342Y259417D01*
X858550Y259875D01*
X858883Y260500D01*
X857217D01*
G01X861650Y258000D02*
Y260500D01*
X860108Y258708D01*
X862192D01*
G01X851200Y274800D02*
Y278800D01*
X843800D01*
G01X864500Y270017D02*
X862000D01*
Y271058D01*
X862125Y271392D01*
X862292Y271600D01*
X862625Y271683D01*
X862958Y271600D01*
X863167Y271350D01*
X863292Y271058D01*
Y270017D01*
G01Y271058D02*
X864500Y271683D01*
G01Y273950D02*
X862000D01*
X862500Y273450D01*
G01X864500D02*
Y274450D01*
G01X863458Y276258D02*
X863167Y276550D01*
X863000Y276800D01*
X862917Y277133D01*
X863000Y277425D01*
X863167Y277633D01*
X863417Y277800D01*
X863708Y277842D01*
X863958Y277800D01*
X864208Y277633D01*
X864417Y277383D01*
X864500Y277092D01*
X864417Y276758D01*
X864167Y276467D01*
X863792Y276300D01*
X863375Y276258D01*
X862833Y276342D01*
X862542Y276467D01*
X862250Y276675D01*
X862042Y276967D01*
X862000Y277258D01*
X862083Y277550D01*
X862292Y277758D01*
G01X864500Y280067D02*
X863958Y280150D01*
X863500Y280275D01*
X863083Y280442D01*
X862625Y280650D01*
X862000Y280983D01*
Y279317D01*
G01X862708Y305767D02*
X862583Y305517D01*
X862500Y305225D01*
Y304892D01*
X862625Y304517D01*
X862833Y304225D01*
X863083Y304017D01*
X863500Y303850D01*
X863875Y303808D01*
X864250Y303892D01*
X864500Y304017D01*
X864750Y304267D01*
X864917Y304558D01*
X865000Y304850D01*
Y305142D01*
X864917Y305433D01*
X864792Y305683D01*
X864625Y305892D01*
G01X865000Y307950D02*
X862500D01*
X863000Y307450D01*
G01X865000D02*
Y308450D01*
G01Y310967D02*
X864458Y311050D01*
X864000Y311175D01*
X863583Y311342D01*
X863125Y311550D01*
X862500Y311883D01*
Y310217D01*
G01X864500Y313233D02*
X864792Y313483D01*
X864958Y313817D01*
X865000Y314192D01*
X864958Y314525D01*
X864750Y314858D01*
X864500Y315067D01*
X864250Y315108D01*
X863958Y315025D01*
X863750Y314733D01*
X863667Y314442D01*
Y314067D01*
G01Y314442D02*
X863542Y314692D01*
X863333Y314900D01*
X863083Y314983D01*
X862833Y314900D01*
X862625Y314692D01*
X862500Y314317D01*
X862542Y313942D01*
X862708Y313567D01*
G01X846999Y298250D02*
Y303750D01*
G01X854999Y298250D02*
X846999D01*
G01X854999Y303750D02*
Y298250D01*
G01Y315850D02*
Y310350D01*
G01X846999D02*
Y315850D01*
G01X843200Y264200D02*
Y278200D01*
G01X864129Y351493D02*
X864004Y351243D01*
X863921Y350951D01*
Y350618D01*
X864046Y350243D01*
X864254Y349951D01*
X864504Y349743D01*
X864921Y349576D01*
X865296Y349534D01*
X865671Y349618D01*
X865921Y349743D01*
X866171Y349993D01*
X866338Y350284D01*
X866421Y350576D01*
Y350868D01*
X866338Y351159D01*
X866213Y351409D01*
X866046Y351618D01*
G01X866421Y353676D02*
X863921D01*
X864421Y353176D01*
G01X866421D02*
Y354176D01*
G01Y356693D02*
X865879Y356776D01*
X865421Y356901D01*
X865004Y357068D01*
X864546Y357276D01*
X863921Y357609D01*
Y355943D01*
G01X866129Y359168D02*
X866338Y359459D01*
X866421Y359793D01*
X866338Y360126D01*
X866088Y360418D01*
X865713Y360626D01*
X865338Y360709D01*
X864879D01*
X864504Y360626D01*
X864171Y360418D01*
X864004Y360168D01*
X863921Y359876D01*
X864004Y359543D01*
X864171Y359293D01*
X864421Y359126D01*
X864754Y359043D01*
X865046Y359126D01*
X865338Y359334D01*
X865504Y359584D01*
X865546Y359876D01*
X865463Y360209D01*
X865254Y360459D01*
X864879Y360709D01*
G01X868499Y317567D02*
X865999D01*
Y318608D01*
X866124Y318942D01*
X866291Y319150D01*
X866624Y319233D01*
X866957Y319150D01*
X867166Y318900D01*
X867291Y318608D01*
Y317567D01*
G01Y318608D02*
X868499Y319233D01*
G01Y321500D02*
X865999D01*
X866499Y321000D01*
G01X868499D02*
Y322000D01*
G01X867457Y323808D02*
X867166Y324100D01*
X866999Y324350D01*
X866916Y324683D01*
X866999Y324975D01*
X867166Y325183D01*
X867416Y325350D01*
X867707Y325392D01*
X867957Y325350D01*
X868207Y325183D01*
X868416Y324933D01*
X868499Y324642D01*
X868416Y324308D01*
X868166Y324017D01*
X867791Y323850D01*
X867374Y323808D01*
X866832Y323892D01*
X866541Y324017D01*
X866249Y324225D01*
X866041Y324517D01*
X865999Y324808D01*
X866082Y325100D01*
X866291Y325308D01*
G01X867999Y326783D02*
X868291Y327033D01*
X868457Y327367D01*
X868499Y327742D01*
X868457Y328075D01*
X868249Y328408D01*
X867999Y328617D01*
X867749Y328658D01*
X867457Y328575D01*
X867249Y328283D01*
X867166Y327992D01*
Y327617D01*
G01Y327992D02*
X867041Y328242D01*
X866832Y328450D01*
X866582Y328533D01*
X866332Y328450D01*
X866124Y328242D01*
X865999Y327867D01*
X866041Y327492D01*
X866207Y327117D01*
G01X863728Y317424D02*
Y330424D01*
G01X844800Y338000D02*
Y332500D01*
G01Y350100D02*
Y344600D01*
G01X848208Y354467D02*
X848083Y354217D01*
X848000Y353925D01*
Y353592D01*
X848125Y353217D01*
X848333Y352925D01*
X848583Y352717D01*
X849000Y352550D01*
X849375Y352508D01*
X849750Y352592D01*
X850000Y352717D01*
X850250Y352967D01*
X850417Y353258D01*
X850500Y353550D01*
Y353842D01*
X850417Y354133D01*
X850292Y354383D01*
X850125Y354592D01*
G01X850500Y356650D02*
X848000D01*
X848500Y356150D01*
G01X850500D02*
Y357150D01*
G01Y359667D02*
X849958Y359750D01*
X849500Y359875D01*
X849083Y360042D01*
X848625Y360250D01*
X848000Y360583D01*
Y358917D01*
G01X849458Y362058D02*
X849167Y362350D01*
X849000Y362600D01*
X848917Y362933D01*
X849000Y363225D01*
X849167Y363433D01*
X849417Y363600D01*
X849708Y363642D01*
X849958Y363600D01*
X850208Y363433D01*
X850417Y363183D01*
X850500Y362892D01*
X850417Y362558D01*
X850167Y362267D01*
X849792Y362100D01*
X849375Y362058D01*
X848833Y362142D01*
X848542Y362267D01*
X848250Y362475D01*
X848042Y362767D01*
X848000Y363058D01*
X848083Y363350D01*
X848292Y363558D01*
G01X845500Y332500D02*
Y338000D01*
G01X853500Y332500D02*
X845500D01*
G01X853500Y338000D02*
Y332500D01*
G01Y350100D02*
Y344600D01*
G01X845500Y350100D02*
X853500D01*
G01X845500Y344600D02*
Y350100D01*
G01X856908Y354467D02*
X856783Y354217D01*
X856700Y353925D01*
Y353592D01*
X856825Y353217D01*
X857033Y352925D01*
X857283Y352717D01*
X857700Y352550D01*
X858075Y352508D01*
X858450Y352592D01*
X858700Y352717D01*
X858950Y352967D01*
X859117Y353258D01*
X859200Y353550D01*
Y353842D01*
X859117Y354133D01*
X858992Y354383D01*
X858825Y354592D01*
G01X859200Y356650D02*
X856700D01*
X857200Y356150D01*
G01X859200D02*
Y357150D01*
G01Y359667D02*
X858658Y359750D01*
X858200Y359875D01*
X857783Y360042D01*
X857325Y360250D01*
X856700Y360583D01*
Y358917D01*
G01X859200Y362767D02*
X858658Y362850D01*
X858200Y362975D01*
X857783Y363142D01*
X857325Y363350D01*
X856700Y363683D01*
Y362017D01*
G01X854200Y332500D02*
Y338000D01*
G01X862200Y332500D02*
X854200D01*
G01X862200Y338000D02*
Y332500D01*
G01Y350100D02*
Y344600D01*
G01X854200Y350100D02*
X862200D01*
G01X854200Y344600D02*
Y350100D01*
G01X846999Y315850D02*
X854999D01*
G01X860499Y535550D02*
Y545550D01*
G01X867499D02*
Y535550D01*
G01Y540550D02*
X860499D01*
G01X870932Y535550D02*
Y545550D01*
X874266D01*
X875599Y545050D01*
X876599Y544383D01*
X877432Y543383D01*
X878099Y542216D01*
X878266Y540550D01*
X878099Y538883D01*
X877432Y537717D01*
X876599Y536716D01*
X875599Y536050D01*
X874266Y535550D01*
X870932D01*
G01X881532D02*
Y545550D01*
X884866D01*
X886199Y545050D01*
X887199Y544383D01*
X888032Y543383D01*
X888699Y542216D01*
X888866Y540550D01*
X888699Y538883D01*
X888032Y537717D01*
X887199Y536716D01*
X886199Y536050D01*
X884866Y535550D01*
X881532D01*
G01X892132Y537550D02*
X893132Y536383D01*
X894465Y535717D01*
X895966Y535550D01*
X897299Y535717D01*
X898632Y536550D01*
X899466Y537550D01*
X899632Y538550D01*
X899299Y539716D01*
X898132Y540550D01*
X896966Y540883D01*
X895466D01*
G01X896966D02*
X897966Y541383D01*
X898799Y542216D01*
X899132Y543217D01*
X898799Y544217D01*
X897966Y545050D01*
X896466Y545550D01*
X894966Y545383D01*
X893466Y544717D01*
G01X901399Y532217D02*
X911399D01*
G01X913666Y545550D02*
Y535550D01*
X920332D01*
G01X930932D02*
X924266D01*
Y545550D01*
X930932D01*
G01X928266Y540717D02*
X924266D01*
G01X934532Y535550D02*
Y545550D01*
X937866D01*
X939199Y545050D01*
X940199Y544383D01*
X941032Y543383D01*
X941699Y542216D01*
X941866Y540550D01*
X941699Y538883D01*
X941032Y537717D01*
X940199Y536716D01*
X939199Y536050D01*
X937866Y535550D01*
X934532D01*
G01X890918Y555493D02*
Y552993D01*
X892584D01*
G01X895684D02*
X894018D01*
Y555493D01*
X895684D01*
G01X895018Y554285D02*
X894018D01*
G01X897034Y552993D02*
Y555493D01*
X897868D01*
X898201Y555368D01*
X898451Y555201D01*
X898659Y554951D01*
X898826Y554660D01*
X898868Y554243D01*
X898826Y553826D01*
X898659Y553535D01*
X898451Y553285D01*
X898201Y553118D01*
X897868Y552993D01*
X897034D01*
G01X901551D02*
Y555493D01*
X900009Y553701D01*
X902093D01*
G01X868200Y562154D02*
Y564654D01*
X869241D01*
X869575Y564529D01*
X869783Y564362D01*
X869866Y564029D01*
X869783Y563696D01*
X869533Y563487D01*
X869241Y563362D01*
X868200D01*
G01X869241D02*
X869866Y562154D01*
G01X872133D02*
Y564654D01*
X871633Y564154D01*
G01Y562154D02*
X872633D01*
G01X875733D02*
Y564654D01*
X874191Y562862D01*
X876275D01*
G01X877416Y562529D02*
X877666Y562321D01*
X877958Y562196D01*
X878333Y562154D01*
X878708Y562237D01*
X879000Y562404D01*
X879208Y562696D01*
X879250Y563029D01*
X879166Y563362D01*
X878958Y563571D01*
X878666Y563737D01*
X878375Y563779D01*
X878083Y563737D01*
X877708Y563571D01*
X877833Y564654D01*
X878958D01*
G01X881299Y567050D02*
Y563050D01*
X888699D01*
G01X903246Y564882D02*
Y560882D01*
X910646D01*
G01X909516Y552050D02*
Y554550D01*
X910557D01*
X910891Y554425D01*
X911099Y554258D01*
X911182Y553925D01*
X911099Y553592D01*
X910849Y553383D01*
X910557Y553258D01*
X909516D01*
G01X910557D02*
X911182Y552050D01*
G01X913949D02*
Y554550D01*
X912407Y552758D01*
X914491D01*
G01X915841Y552342D02*
X916132Y552133D01*
X916466Y552050D01*
X916799Y552133D01*
X917091Y552383D01*
X917299Y552758D01*
X917382Y553133D01*
Y553592D01*
X917299Y553967D01*
X917091Y554300D01*
X916841Y554467D01*
X916549Y554550D01*
X916216Y554467D01*
X915966Y554300D01*
X915799Y554050D01*
X915716Y553717D01*
X915799Y553425D01*
X916007Y553133D01*
X916257Y552967D01*
X916549Y552925D01*
X916882Y553008D01*
X917132Y553217D01*
X917382Y553592D01*
G01X919649Y552050D02*
Y554550D01*
X919149Y554050D01*
G01Y552050D02*
X920149D01*
G01X918099Y555800D02*
Y559800D01*
X910699D01*
G01X911299Y560400D02*
X925299D01*
G01X911299Y573400D02*
Y560400D01*
G01X842963Y631674D02*
X842713Y631799D01*
X842421Y631882D01*
X842088D01*
X841713Y631757D01*
X841421Y631549D01*
X841213Y631299D01*
X841046Y630882D01*
X841004Y630507D01*
X841088Y630132D01*
X841213Y629882D01*
X841463Y629632D01*
X841754Y629465D01*
X842046Y629382D01*
X842338D01*
X842629Y629465D01*
X842879Y629590D01*
X843088Y629757D01*
G01X845146Y629382D02*
Y631882D01*
X844646Y631382D01*
G01Y629382D02*
X845646D01*
G01X847329Y629757D02*
X847579Y629549D01*
X847871Y629424D01*
X848246Y629382D01*
X848621Y629465D01*
X848913Y629632D01*
X849121Y629924D01*
X849163Y630257D01*
X849079Y630590D01*
X848871Y630799D01*
X848579Y630965D01*
X848288Y631007D01*
X847996Y630965D01*
X847621Y630799D01*
X847746Y631882D01*
X848871D01*
G01X851346D02*
X851013Y631799D01*
X850763Y631590D01*
X850596Y631340D01*
X850471Y631007D01*
X850429Y630632D01*
X850471Y630257D01*
X850596Y629924D01*
X850763Y629674D01*
X851013Y629465D01*
X851346Y629382D01*
X851679Y629465D01*
X851929Y629674D01*
X852096Y629924D01*
X852221Y630257D01*
X852263Y630632D01*
X852221Y631007D01*
X852096Y631340D01*
X851929Y631590D01*
X851679Y631799D01*
X851346Y631882D01*
G01X842766Y635842D02*
X842516Y635967D01*
X842224Y636050D01*
X841891D01*
X841516Y635925D01*
X841224Y635717D01*
X841016Y635467D01*
X840849Y635050D01*
X840807Y634675D01*
X840891Y634300D01*
X841016Y634050D01*
X841266Y633800D01*
X841557Y633633D01*
X841849Y633550D01*
X842141D01*
X842432Y633633D01*
X842682Y633758D01*
X842891Y633925D01*
G01X844949Y633550D02*
Y636050D01*
X844449Y635550D01*
G01Y633550D02*
X845449D01*
G01X847132Y633925D02*
X847382Y633717D01*
X847674Y633592D01*
X848049Y633550D01*
X848424Y633633D01*
X848716Y633800D01*
X848924Y634092D01*
X848966Y634425D01*
X848882Y634758D01*
X848674Y634967D01*
X848382Y635133D01*
X848091Y635175D01*
X847799Y635133D01*
X847424Y634967D01*
X847549Y636050D01*
X848674D01*
G01X851149Y633550D02*
Y636050D01*
X850649Y635550D01*
G01Y633550D02*
X851649D01*
G01X901369Y571359D02*
Y563759D01*
X889969D01*
Y571359D01*
X901369D01*
G01X907463Y583882D02*
Y586382D01*
X908504D01*
X908838Y586257D01*
X909046Y586090D01*
X909129Y585757D01*
X909046Y585424D01*
X908796Y585215D01*
X908504Y585090D01*
X907463D01*
G01X908504D02*
X909129Y583882D01*
G01X911396D02*
Y586382D01*
X910896Y585882D01*
G01Y583882D02*
X911896D01*
G01X914996D02*
Y586382D01*
X913454Y584590D01*
X915538D01*
G01X916804Y585965D02*
X917054Y586215D01*
X917346Y586340D01*
X917679Y586382D01*
X918096Y586299D01*
X918388Y586090D01*
X918471Y585840D01*
X918429Y585590D01*
X918263Y585382D01*
X917429Y584965D01*
X917054Y584674D01*
X916804Y584257D01*
X916721Y583882D01*
X918471D01*
G01X903246Y572882D02*
Y568882D01*
X910646D01*
G01X869215Y572335D02*
Y574835D01*
X870256D01*
X870590Y574710D01*
X870798Y574543D01*
X870881Y574210D01*
X870798Y573877D01*
X870548Y573668D01*
X870256Y573543D01*
X869215D01*
G01X870256D02*
X870881Y572335D01*
G01X873148D02*
Y574835D01*
X872648Y574335D01*
G01Y572335D02*
X873648D01*
G01X876748D02*
Y574835D01*
X875206Y573043D01*
X877290D01*
G01X878431Y572835D02*
X878681Y572543D01*
X879015Y572377D01*
X879390Y572335D01*
X879723Y572377D01*
X880056Y572585D01*
X880265Y572835D01*
X880306Y573085D01*
X880223Y573377D01*
X879931Y573585D01*
X879640Y573668D01*
X879265D01*
G01X879640D02*
X879890Y573793D01*
X880098Y574002D01*
X880181Y574252D01*
X880098Y574502D01*
X879890Y574710D01*
X879515Y574835D01*
X879140Y574793D01*
X878765Y574627D01*
G01X881299Y572550D02*
Y568550D01*
X888699D01*
G01X907463Y579882D02*
Y582382D01*
X908504D01*
X908838Y582257D01*
X909046Y582090D01*
X909129Y581757D01*
X909046Y581424D01*
X908796Y581215D01*
X908504Y581090D01*
X907463D01*
G01X908504D02*
X909129Y579882D01*
G01X911396D02*
Y582382D01*
X910896Y581882D01*
G01Y579882D02*
X911896D01*
G01X914996D02*
Y582382D01*
X913454Y580590D01*
X915538D01*
G01X918096Y579882D02*
Y582382D01*
X916554Y580590D01*
X918638D01*
G01X903246Y568882D02*
Y564882D01*
X910646D01*
G01X907463Y575882D02*
Y578382D01*
X908504D01*
X908838Y578257D01*
X909046Y578090D01*
X909129Y577757D01*
X909046Y577424D01*
X908796Y577215D01*
X908504Y577090D01*
X907463D01*
G01X908504D02*
X909129Y575882D01*
G01X911396D02*
Y578382D01*
X910896Y577882D01*
G01Y575882D02*
X911896D01*
G01X914996D02*
Y578382D01*
X913454Y576590D01*
X915538D01*
G01X916804Y576924D02*
X917096Y577215D01*
X917346Y577382D01*
X917679Y577465D01*
X917971Y577382D01*
X918179Y577215D01*
X918346Y576965D01*
X918388Y576674D01*
X918346Y576424D01*
X918179Y576174D01*
X917929Y575965D01*
X917638Y575882D01*
X917304Y575965D01*
X917013Y576215D01*
X916846Y576590D01*
X916804Y577007D01*
X916888Y577549D01*
X917013Y577840D01*
X917221Y578132D01*
X917513Y578340D01*
X917804Y578382D01*
X918096Y578299D01*
X918304Y578090D01*
G01X925299Y573400D02*
X911299D01*
G01X872969Y591329D02*
Y752529D01*
X886569D01*
Y765479D01*
X904769D01*
Y752529D01*
X933669D01*
Y742179D01*
X926969D01*
Y601679D01*
X933669D01*
Y591329D01*
X904769D01*
Y578379D01*
X886569D01*
Y591329D01*
X872969D01*
G01X842410Y655358D02*
X842160Y655483D01*
X841868Y655566D01*
X841535D01*
X841160Y655441D01*
X840868Y655233D01*
X840660Y654983D01*
X840493Y654566D01*
X840451Y654191D01*
X840535Y653816D01*
X840660Y653566D01*
X840910Y653316D01*
X841201Y653149D01*
X841493Y653066D01*
X841785D01*
X842076Y653149D01*
X842326Y653274D01*
X842535Y653441D01*
G01X844593Y653066D02*
Y655566D01*
X844093Y655066D01*
G01Y653066D02*
X845093D01*
G01X846776Y653441D02*
X847026Y653233D01*
X847318Y653108D01*
X847693Y653066D01*
X848068Y653149D01*
X848360Y653316D01*
X848568Y653608D01*
X848610Y653941D01*
X848526Y654274D01*
X848318Y654483D01*
X848026Y654649D01*
X847735Y654691D01*
X847443Y654649D01*
X847068Y654483D01*
X847193Y655566D01*
X848318D01*
G01X850001Y655149D02*
X850251Y655399D01*
X850543Y655524D01*
X850876Y655566D01*
X851293Y655483D01*
X851585Y655274D01*
X851668Y655024D01*
X851626Y654774D01*
X851460Y654566D01*
X850626Y654149D01*
X850251Y653858D01*
X850001Y653441D01*
X849918Y653066D01*
X851668D01*
G01X842713Y659526D02*
X842463Y659651D01*
X842171Y659734D01*
X841838D01*
X841463Y659609D01*
X841171Y659401D01*
X840963Y659151D01*
X840796Y658734D01*
X840754Y658359D01*
X840838Y657984D01*
X840963Y657734D01*
X841213Y657484D01*
X841504Y657317D01*
X841796Y657234D01*
X842088D01*
X842379Y657317D01*
X842629Y657442D01*
X842838Y657609D01*
G01X844896Y657234D02*
Y659734D01*
X844396Y659234D01*
G01Y657234D02*
X845396D01*
G01X847079Y657609D02*
X847329Y657401D01*
X847621Y657276D01*
X847996Y657234D01*
X848371Y657317D01*
X848663Y657484D01*
X848871Y657776D01*
X848913Y658109D01*
X848829Y658442D01*
X848621Y658651D01*
X848329Y658817D01*
X848038Y658859D01*
X847746Y658817D01*
X847371Y658651D01*
X847496Y659734D01*
X848621D01*
G01X850179Y657734D02*
X850429Y657442D01*
X850763Y657276D01*
X851138Y657234D01*
X851471Y657276D01*
X851804Y657484D01*
X852013Y657734D01*
X852054Y657984D01*
X851971Y658276D01*
X851679Y658484D01*
X851388Y658567D01*
X851013D01*
G01X851388D02*
X851638Y658692D01*
X851846Y658901D01*
X851929Y659151D01*
X851846Y659401D01*
X851638Y659609D01*
X851263Y659734D01*
X850888Y659692D01*
X850513Y659526D01*
G01X865208Y673767D02*
X865083Y673517D01*
X865000Y673225D01*
Y672892D01*
X865125Y672517D01*
X865333Y672225D01*
X865583Y672017D01*
X866000Y671850D01*
X866375Y671808D01*
X866750Y671892D01*
X867000Y672017D01*
X867250Y672267D01*
X867417Y672558D01*
X867500Y672850D01*
Y673142D01*
X867417Y673433D01*
X867292Y673683D01*
X867125Y673892D01*
G01X867500Y675950D02*
X865000D01*
X865500Y675450D01*
G01X867500D02*
Y676450D01*
G01X867125Y678133D02*
X867333Y678383D01*
X867458Y678675D01*
X867500Y679050D01*
X867417Y679425D01*
X867250Y679717D01*
X866958Y679925D01*
X866625Y679967D01*
X866292Y679883D01*
X866083Y679675D01*
X865917Y679383D01*
X865875Y679092D01*
X865917Y678800D01*
X866083Y678425D01*
X865000Y678550D01*
Y679675D01*
G01X866458Y681358D02*
X866167Y681650D01*
X866000Y681900D01*
X865917Y682233D01*
X866000Y682525D01*
X866167Y682733D01*
X866417Y682900D01*
X866708Y682942D01*
X866958Y682900D01*
X867208Y682733D01*
X867417Y682483D01*
X867500Y682192D01*
X867417Y681858D01*
X867167Y681567D01*
X866792Y681400D01*
X866375Y681358D01*
X865833Y681442D01*
X865542Y681567D01*
X865250Y681775D01*
X865042Y682067D01*
X865000Y682358D01*
X865083Y682650D01*
X865292Y682858D01*
G01X867708Y705267D02*
X867583Y705017D01*
X867500Y704725D01*
Y704392D01*
X867625Y704017D01*
X867833Y703725D01*
X868083Y703517D01*
X868500Y703350D01*
X868875Y703308D01*
X869250Y703392D01*
X869500Y703517D01*
X869750Y703767D01*
X869917Y704058D01*
X870000Y704350D01*
Y704642D01*
X869917Y704933D01*
X869792Y705183D01*
X869625Y705392D01*
G01X870000Y707450D02*
X867500D01*
X868000Y706950D01*
G01X870000D02*
Y707950D01*
G01X869625Y709633D02*
X869833Y709883D01*
X869958Y710175D01*
X870000Y710550D01*
X869917Y710925D01*
X869750Y711217D01*
X869458Y711425D01*
X869125Y711467D01*
X868792Y711383D01*
X868583Y711175D01*
X868417Y710883D01*
X868375Y710592D01*
X868417Y710300D01*
X868583Y709925D01*
X867500Y710050D01*
Y711175D01*
G01X870000Y714150D02*
X867500D01*
X869292Y712608D01*
Y714692D01*
G01X865768Y686581D02*
X863268D01*
Y687622D01*
X863393Y687956D01*
X863560Y688164D01*
X863893Y688247D01*
X864226Y688164D01*
X864435Y687914D01*
X864560Y687622D01*
Y686581D01*
G01Y687622D02*
X865768Y688247D01*
G01Y690514D02*
X863268D01*
X863768Y690014D01*
G01X865768D02*
Y691014D01*
G01X865393Y692697D02*
X865601Y692947D01*
X865726Y693239D01*
X865768Y693614D01*
X865685Y693989D01*
X865518Y694281D01*
X865226Y694489D01*
X864893Y694531D01*
X864560Y694447D01*
X864351Y694239D01*
X864185Y693947D01*
X864143Y693656D01*
X864185Y693364D01*
X864351Y692989D01*
X863268Y693114D01*
Y694239D01*
G01X865768Y696714D02*
X863268D01*
X863768Y696214D01*
G01X865768D02*
Y697214D01*
G01X858446Y684682D02*
Y697682D01*
G01X865999Y719567D02*
X863499D01*
Y720608D01*
X863624Y720942D01*
X863791Y721150D01*
X864124Y721233D01*
X864457Y721150D01*
X864666Y720900D01*
X864791Y720608D01*
Y719567D01*
G01Y720608D02*
X865999Y721233D01*
G01Y723500D02*
X863499D01*
X863999Y723000D01*
G01X865999D02*
Y724000D01*
G01X865624Y725683D02*
X865832Y725933D01*
X865957Y726225D01*
X865999Y726600D01*
X865916Y726975D01*
X865749Y727267D01*
X865457Y727475D01*
X865124Y727517D01*
X864791Y727433D01*
X864582Y727225D01*
X864416Y726933D01*
X864374Y726642D01*
X864416Y726350D01*
X864582Y725975D01*
X863499Y726100D01*
Y727225D01*
G01X865999Y730200D02*
X863499D01*
X865291Y728658D01*
Y730742D01*
G01X861499Y718050D02*
Y731050D01*
G01X857517Y667000D02*
Y669500D01*
X858558D01*
X858892Y669375D01*
X859100Y669208D01*
X859183Y668875D01*
X859100Y668542D01*
X858850Y668333D01*
X858558Y668208D01*
X857517D01*
G01X858558D02*
X859183Y667000D01*
G01X861450D02*
Y669500D01*
X860950Y669000D01*
G01Y667000D02*
X861950D01*
G01X863633Y667375D02*
X863883Y667167D01*
X864175Y667042D01*
X864550Y667000D01*
X864925Y667083D01*
X865217Y667250D01*
X865425Y667542D01*
X865467Y667875D01*
X865383Y668208D01*
X865175Y668417D01*
X864883Y668583D01*
X864592Y668625D01*
X864300Y668583D01*
X863925Y668417D01*
X864050Y669500D01*
X865175D01*
G01X867650D02*
X867317Y669417D01*
X867067Y669208D01*
X866900Y668958D01*
X866775Y668625D01*
X866733Y668250D01*
X866775Y667875D01*
X866900Y667542D01*
X867067Y667292D01*
X867317Y667083D01*
X867650Y667000D01*
X867983Y667083D01*
X868233Y667292D01*
X868400Y667542D01*
X868525Y667875D01*
X868567Y668250D01*
X868525Y668625D01*
X868400Y668958D01*
X868233Y669208D01*
X867983Y669417D01*
X867650Y669500D01*
G01X842496Y683882D02*
Y679882D01*
X849896D01*
G01X857517Y663000D02*
Y665500D01*
X858558D01*
X858892Y665375D01*
X859100Y665208D01*
X859183Y664875D01*
X859100Y664542D01*
X858850Y664333D01*
X858558Y664208D01*
X857517D01*
G01X858558D02*
X859183Y663000D01*
G01X860533Y663500D02*
X860783Y663208D01*
X861117Y663042D01*
X861492Y663000D01*
X861825Y663042D01*
X862158Y663250D01*
X862367Y663500D01*
X862408Y663750D01*
X862325Y664042D01*
X862033Y664250D01*
X861742Y664333D01*
X861367D01*
G01X861742D02*
X861992Y664458D01*
X862200Y664667D01*
X862283Y664917D01*
X862200Y665167D01*
X861992Y665375D01*
X861617Y665500D01*
X861242Y665458D01*
X860867Y665292D01*
G01X863758Y664042D02*
X864050Y664333D01*
X864300Y664500D01*
X864633Y664583D01*
X864925Y664500D01*
X865133Y664333D01*
X865300Y664083D01*
X865342Y663792D01*
X865300Y663542D01*
X865133Y663292D01*
X864883Y663083D01*
X864592Y663000D01*
X864258Y663083D01*
X863967Y663333D01*
X863800Y663708D01*
X863758Y664125D01*
X863842Y664667D01*
X863967Y664958D01*
X864175Y665250D01*
X864467Y665458D01*
X864758Y665500D01*
X865050Y665417D01*
X865258Y665208D01*
G01X866942Y663292D02*
X867233Y663083D01*
X867567Y663000D01*
X867900Y663083D01*
X868192Y663333D01*
X868400Y663708D01*
X868483Y664083D01*
Y664542D01*
X868400Y664917D01*
X868192Y665250D01*
X867942Y665417D01*
X867650Y665500D01*
X867317Y665417D01*
X867067Y665250D01*
X866900Y665000D01*
X866817Y664667D01*
X866900Y664375D01*
X867108Y664083D01*
X867358Y663917D01*
X867650Y663875D01*
X867983Y663958D01*
X868233Y664167D01*
X868483Y664542D01*
G01X849900Y675700D02*
Y679700D01*
X842500D01*
G01X863500Y672017D02*
X861000D01*
Y673058D01*
X861125Y673392D01*
X861292Y673600D01*
X861625Y673683D01*
X861958Y673600D01*
X862167Y673350D01*
X862292Y673058D01*
Y672017D01*
G01Y673058D02*
X863500Y673683D01*
G01Y675950D02*
X861000D01*
X861500Y675450D01*
G01X863500D02*
Y676450D01*
G01X863125Y678133D02*
X863333Y678383D01*
X863458Y678675D01*
X863500Y679050D01*
X863417Y679425D01*
X863250Y679717D01*
X862958Y679925D01*
X862625Y679967D01*
X862292Y679883D01*
X862083Y679675D01*
X861917Y679383D01*
X861875Y679092D01*
X861917Y678800D01*
X862083Y678425D01*
X861000Y678550D01*
Y679675D01*
G01X861417Y681358D02*
X861167Y681608D01*
X861042Y681900D01*
X861000Y682233D01*
X861083Y682650D01*
X861292Y682942D01*
X861542Y683025D01*
X861792Y682983D01*
X862000Y682817D01*
X862417Y681983D01*
X862708Y681608D01*
X863125Y681358D01*
X863500Y681275D01*
Y683025D01*
G01X859500Y704350D02*
X862000D01*
G01X859500Y703392D02*
Y705308D01*
G01X862000Y706617D02*
X859500D01*
Y707617D01*
X859625Y707950D01*
X859917Y708200D01*
X860250Y708283D01*
X860583Y708200D01*
X860833Y707992D01*
X860958Y707617D01*
Y706617D01*
G01X859917Y709758D02*
X859667Y710008D01*
X859542Y710300D01*
X859500Y710633D01*
X859583Y711050D01*
X859792Y711342D01*
X860042Y711425D01*
X860292Y711383D01*
X860500Y711217D01*
X860917Y710383D01*
X861208Y710008D01*
X861625Y709758D01*
X862000Y709675D01*
Y711425D01*
G01Y713650D02*
X861958Y713942D01*
X861833Y714275D01*
X861625Y714483D01*
X861333Y714567D01*
X861042Y714483D01*
X860792Y714233D01*
X860667Y713858D01*
Y713442D01*
X860583Y713192D01*
X860375Y712983D01*
X860083Y712900D01*
X859792Y713025D01*
X859583Y713317D01*
X859500Y713650D01*
X859583Y713983D01*
X859792Y714275D01*
X860083Y714400D01*
X860375Y714317D01*
X860583Y714108D01*
X860667Y713858D01*
Y713442D01*
X860792Y713067D01*
X861042Y712817D01*
X861333Y712733D01*
X861625Y712817D01*
X861833Y713025D01*
X861958Y713358D01*
X862000Y713650D01*
G01X863708Y705267D02*
X863583Y705017D01*
X863500Y704725D01*
Y704392D01*
X863625Y704017D01*
X863833Y703725D01*
X864083Y703517D01*
X864500Y703350D01*
X864875Y703308D01*
X865250Y703392D01*
X865500Y703517D01*
X865750Y703767D01*
X865917Y704058D01*
X866000Y704350D01*
Y704642D01*
X865917Y704933D01*
X865792Y705183D01*
X865625Y705392D01*
G01X866000Y707450D02*
X863500D01*
X864000Y706950D01*
G01X866000D02*
Y707950D01*
G01X865625Y709633D02*
X865833Y709883D01*
X865958Y710175D01*
X866000Y710550D01*
X865917Y710925D01*
X865750Y711217D01*
X865458Y711425D01*
X865125Y711467D01*
X864792Y711383D01*
X864583Y711175D01*
X864417Y710883D01*
X864375Y710592D01*
X864417Y710300D01*
X864583Y709925D01*
X863500Y710050D01*
Y711175D01*
G01X865625Y712733D02*
X865833Y712983D01*
X865958Y713275D01*
X866000Y713650D01*
X865917Y714025D01*
X865750Y714317D01*
X865458Y714525D01*
X865125Y714567D01*
X864792Y714483D01*
X864583Y714275D01*
X864417Y713983D01*
X864375Y713692D01*
X864417Y713400D01*
X864583Y713025D01*
X863500Y713150D01*
Y714275D01*
G01X844696Y699582D02*
Y705082D01*
G01X852696Y699582D02*
X844696D01*
G01X852696Y705082D02*
Y699582D01*
G01Y717182D02*
Y711682D01*
G01X844696Y717182D02*
X852696D01*
G01X844696Y711682D02*
Y717182D01*
G01X841800Y666900D02*
Y680900D01*
G01X861907Y752517D02*
X861782Y752267D01*
X861699Y751975D01*
Y751642D01*
X861824Y751267D01*
X862032Y750975D01*
X862282Y750767D01*
X862699Y750600D01*
X863074Y750558D01*
X863449Y750642D01*
X863699Y750767D01*
X863949Y751017D01*
X864116Y751308D01*
X864199Y751600D01*
Y751892D01*
X864116Y752183D01*
X863991Y752433D01*
X863824Y752642D01*
G01X864199Y754700D02*
X861699D01*
X862199Y754200D01*
G01X864199D02*
Y755200D01*
G01X863157Y757008D02*
X862866Y757300D01*
X862699Y757550D01*
X862616Y757883D01*
X862699Y758175D01*
X862866Y758383D01*
X863116Y758550D01*
X863407Y758592D01*
X863657Y758550D01*
X863907Y758383D01*
X864116Y758133D01*
X864199Y757842D01*
X864116Y757508D01*
X863866Y757217D01*
X863491Y757050D01*
X863074Y757008D01*
X862532Y757092D01*
X862241Y757217D01*
X861949Y757425D01*
X861741Y757717D01*
X861699Y758008D01*
X861782Y758300D01*
X861991Y758508D01*
G01X863699Y759983D02*
X863991Y760233D01*
X864157Y760567D01*
X864199Y760942D01*
X864157Y761275D01*
X863949Y761608D01*
X863699Y761817D01*
X863449Y761858D01*
X863157Y761775D01*
X862949Y761483D01*
X862866Y761192D01*
Y760817D01*
G01Y761192D02*
X862741Y761442D01*
X862532Y761650D01*
X862282Y761733D01*
X862032Y761650D01*
X861824Y761442D01*
X861699Y761067D01*
X861741Y760692D01*
X861907Y760317D01*
G01X842796Y738782D02*
Y733282D01*
G01Y750882D02*
Y745382D01*
G01X846204Y755249D02*
X846079Y754999D01*
X845996Y754707D01*
Y754374D01*
X846121Y753999D01*
X846329Y753707D01*
X846579Y753499D01*
X846996Y753332D01*
X847371Y753290D01*
X847746Y753374D01*
X847996Y753499D01*
X848246Y753749D01*
X848413Y754040D01*
X848496Y754332D01*
Y754624D01*
X848413Y754915D01*
X848288Y755165D01*
X848121Y755374D01*
G01X848496Y757432D02*
X845996D01*
X846496Y756932D01*
G01X848496D02*
Y757932D01*
G01X847454Y759740D02*
X847163Y760032D01*
X846996Y760282D01*
X846913Y760615D01*
X846996Y760907D01*
X847163Y761115D01*
X847413Y761282D01*
X847704Y761324D01*
X847954Y761282D01*
X848204Y761115D01*
X848413Y760865D01*
X848496Y760574D01*
X848413Y760240D01*
X848163Y759949D01*
X847788Y759782D01*
X847371Y759740D01*
X846829Y759824D01*
X846538Y759949D01*
X846246Y760157D01*
X846038Y760449D01*
X845996Y760740D01*
X846079Y761032D01*
X846288Y761240D01*
G01X848496Y763632D02*
X845996D01*
X846496Y763132D01*
G01X848496D02*
Y764132D01*
G01X843496Y733282D02*
Y738782D01*
G01X851496Y733282D02*
X843496D01*
G01X851496Y738782D02*
Y733282D01*
G01Y750882D02*
Y745382D01*
G01X843496Y750882D02*
X851496D01*
G01X843496Y745382D02*
Y750882D01*
G01X854904Y755249D02*
X854779Y754999D01*
X854696Y754707D01*
Y754374D01*
X854821Y753999D01*
X855029Y753707D01*
X855279Y753499D01*
X855696Y753332D01*
X856071Y753290D01*
X856446Y753374D01*
X856696Y753499D01*
X856946Y753749D01*
X857113Y754040D01*
X857196Y754332D01*
Y754624D01*
X857113Y754915D01*
X856988Y755165D01*
X856821Y755374D01*
G01X857196Y757432D02*
X854696D01*
X855196Y756932D01*
G01X857196D02*
Y757932D01*
G01X856154Y759740D02*
X855863Y760032D01*
X855696Y760282D01*
X855613Y760615D01*
X855696Y760907D01*
X855863Y761115D01*
X856113Y761282D01*
X856404Y761324D01*
X856654Y761282D01*
X856904Y761115D01*
X857113Y760865D01*
X857196Y760574D01*
X857113Y760240D01*
X856863Y759949D01*
X856488Y759782D01*
X856071Y759740D01*
X855529Y759824D01*
X855238Y759949D01*
X854946Y760157D01*
X854738Y760449D01*
X854696Y760740D01*
X854779Y761032D01*
X854988Y761240D01*
G01X855113Y762840D02*
X854863Y763090D01*
X854738Y763382D01*
X854696Y763715D01*
X854779Y764132D01*
X854988Y764424D01*
X855238Y764507D01*
X855488Y764465D01*
X855696Y764299D01*
X856113Y763465D01*
X856404Y763090D01*
X856821Y762840D01*
X857196Y762757D01*
Y764507D01*
G01X852196Y733282D02*
Y738782D01*
G01X860196Y733282D02*
X852196D01*
G01X860196Y738782D02*
Y733282D01*
G01Y750882D02*
Y745382D01*
G01X852196Y750882D02*
X860196D01*
G01X852196Y745382D02*
Y750882D01*
G01X861999Y937550D02*
Y947550D01*
G01X868999D02*
Y937550D01*
G01Y942550D02*
X861999D01*
G01X872432Y937550D02*
Y947550D01*
X875766D01*
X877099Y947050D01*
X878099Y946383D01*
X878932Y945383D01*
X879599Y944216D01*
X879766Y942550D01*
X879599Y940883D01*
X878932Y939717D01*
X878099Y938716D01*
X877099Y938050D01*
X875766Y937550D01*
X872432D01*
G01X883032D02*
Y947550D01*
X886366D01*
X887699Y947050D01*
X888699Y946383D01*
X889532Y945383D01*
X890199Y944216D01*
X890366Y942550D01*
X890199Y940883D01*
X889532Y939717D01*
X888699Y938716D01*
X887699Y938050D01*
X886366Y937550D01*
X883032D01*
G01X894132Y945883D02*
X895132Y946883D01*
X896299Y947383D01*
X897632Y947550D01*
X899299Y947217D01*
X900466Y946383D01*
X900799Y945383D01*
X900632Y944383D01*
X899966Y943550D01*
X896632Y941883D01*
X895132Y940717D01*
X894132Y939050D01*
X893799Y937550D01*
X900799D01*
G01X902899Y934217D02*
X912899D01*
G01X915166Y947550D02*
Y937550D01*
X921832D01*
G01X932432D02*
X925766D01*
Y947550D01*
X932432D01*
G01X929766Y942717D02*
X925766D01*
G01X936032Y937550D02*
Y947550D01*
X939366D01*
X940699Y947050D01*
X941699Y946383D01*
X942532Y945383D01*
X943199Y944216D01*
X943366Y942550D01*
X943199Y940883D01*
X942532Y939717D01*
X941699Y938716D01*
X940699Y938050D01*
X939366Y937550D01*
X936032D01*
G01X890990Y960037D02*
Y957537D01*
X892656D01*
G01X895756D02*
X894090D01*
Y960037D01*
X895756D01*
G01X895090Y958829D02*
X894090D01*
G01X897106Y957537D02*
Y960037D01*
X897940D01*
X898273Y959912D01*
X898523Y959745D01*
X898731Y959495D01*
X898898Y959204D01*
X898940Y958787D01*
X898898Y958370D01*
X898731Y958079D01*
X898523Y957829D01*
X898273Y957662D01*
X897940Y957537D01*
X897106D01*
G01X900206Y958037D02*
X900456Y957745D01*
X900790Y957579D01*
X901165Y957537D01*
X901498Y957579D01*
X901831Y957787D01*
X902040Y958037D01*
X902081Y958287D01*
X901998Y958579D01*
X901706Y958787D01*
X901415Y958870D01*
X901040D01*
G01X901415D02*
X901665Y958995D01*
X901873Y959204D01*
X901956Y959454D01*
X901873Y959704D01*
X901665Y959912D01*
X901290Y960037D01*
X900915Y959995D01*
X900540Y959829D01*
G01X901369Y976871D02*
Y969271D01*
X889969D01*
Y976871D01*
X901369D01*
G01X903133Y976392D02*
Y972392D01*
X910533D01*
G01X866165Y969625D02*
Y972125D01*
X867206D01*
X867540Y972000D01*
X867748Y971833D01*
X867831Y971500D01*
X867748Y971167D01*
X867498Y970958D01*
X867206Y970833D01*
X866165D01*
G01X867206D02*
X867831Y969625D01*
G01X870098D02*
Y972125D01*
X869598Y971625D01*
G01Y969625D02*
X870598D01*
G01X872406Y971708D02*
X872656Y971958D01*
X872948Y972083D01*
X873281Y972125D01*
X873698Y972042D01*
X873990Y971833D01*
X874073Y971583D01*
X874031Y971333D01*
X873865Y971125D01*
X873031Y970708D01*
X872656Y970417D01*
X872406Y970000D01*
X872323Y969625D01*
X874073D01*
G01X875590Y969917D02*
X875881Y969708D01*
X876215Y969625D01*
X876548Y969708D01*
X876840Y969958D01*
X877048Y970333D01*
X877131Y970708D01*
Y971167D01*
X877048Y971542D01*
X876840Y971875D01*
X876590Y972042D01*
X876298Y972125D01*
X875965Y972042D01*
X875715Y971875D01*
X875548Y971625D01*
X875465Y971292D01*
X875548Y971000D01*
X875756Y970708D01*
X876006Y970542D01*
X876298Y970500D01*
X876631Y970583D01*
X876881Y970792D01*
X877131Y971167D01*
G01X881133Y977892D02*
Y973892D01*
X888533D01*
G01X903133Y972392D02*
Y968392D01*
X910533D01*
G01X866165Y965625D02*
Y968125D01*
X867206D01*
X867540Y968000D01*
X867748Y967833D01*
X867831Y967500D01*
X867748Y967167D01*
X867498Y966958D01*
X867206Y966833D01*
X866165D01*
G01X867206D02*
X867831Y965625D01*
G01X870098D02*
Y968125D01*
X869598Y967625D01*
G01Y965625D02*
X870598D01*
G01X872281Y966125D02*
X872531Y965833D01*
X872865Y965667D01*
X873240Y965625D01*
X873573Y965667D01*
X873906Y965875D01*
X874115Y966125D01*
X874156Y966375D01*
X874073Y966667D01*
X873781Y966875D01*
X873490Y966958D01*
X873115D01*
G01X873490D02*
X873740Y967083D01*
X873948Y967292D01*
X874031Y967542D01*
X873948Y967792D01*
X873740Y968000D01*
X873365Y968125D01*
X872990Y968083D01*
X872615Y967917D01*
G01X876298Y965625D02*
Y968125D01*
X875798Y967625D01*
G01Y965625D02*
X876798D01*
G01X881133Y973892D02*
Y969892D01*
X888533D01*
G01X903133Y968392D02*
Y964392D01*
X910533D01*
G01X910016Y956550D02*
Y959050D01*
X911057D01*
X911391Y958925D01*
X911599Y958758D01*
X911682Y958425D01*
X911599Y958092D01*
X911349Y957883D01*
X911057Y957758D01*
X910016D01*
G01X911057D02*
X911682Y956550D01*
G01X914449D02*
Y959050D01*
X912907Y957258D01*
X914991D01*
G01X916341Y956842D02*
X916632Y956633D01*
X916966Y956550D01*
X917299Y956633D01*
X917591Y956883D01*
X917799Y957258D01*
X917882Y957633D01*
Y958092D01*
X917799Y958467D01*
X917591Y958800D01*
X917341Y958967D01*
X917049Y959050D01*
X916716Y958967D01*
X916466Y958800D01*
X916299Y958550D01*
X916216Y958217D01*
X916299Y957925D01*
X916507Y957633D01*
X916757Y957467D01*
X917049Y957425D01*
X917382Y957508D01*
X917632Y957717D01*
X917882Y958092D01*
G01X920149Y959050D02*
X919816Y958967D01*
X919566Y958758D01*
X919399Y958508D01*
X919274Y958175D01*
X919232Y957800D01*
X919274Y957425D01*
X919399Y957092D01*
X919566Y956842D01*
X919816Y956633D01*
X920149Y956550D01*
X920482Y956633D01*
X920732Y956842D01*
X920899Y957092D01*
X921024Y957425D01*
X921066Y957800D01*
X921024Y958175D01*
X920899Y958508D01*
X920732Y958758D01*
X920482Y958967D01*
X920149Y959050D01*
G01X918599Y960100D02*
Y964100D01*
X911199D01*
G01X911299Y964600D02*
X925299D01*
G01X911299Y977600D02*
Y964600D01*
G01X843600Y1036684D02*
X843350Y1036809D01*
X843058Y1036892D01*
X842725D01*
X842350Y1036767D01*
X842058Y1036559D01*
X841850Y1036309D01*
X841683Y1035892D01*
X841641Y1035517D01*
X841725Y1035142D01*
X841850Y1034892D01*
X842100Y1034642D01*
X842391Y1034475D01*
X842683Y1034392D01*
X842975D01*
X843266Y1034475D01*
X843516Y1034600D01*
X843725Y1034767D01*
G01X845783Y1034392D02*
Y1036892D01*
X845283Y1036392D01*
G01Y1034392D02*
X846283D01*
G01X847966Y1034892D02*
X848216Y1034600D01*
X848550Y1034434D01*
X848925Y1034392D01*
X849258Y1034434D01*
X849591Y1034642D01*
X849800Y1034892D01*
X849841Y1035142D01*
X849758Y1035434D01*
X849466Y1035642D01*
X849175Y1035725D01*
X848800D01*
G01X849175D02*
X849425Y1035850D01*
X849633Y1036059D01*
X849716Y1036309D01*
X849633Y1036559D01*
X849425Y1036767D01*
X849050Y1036892D01*
X848675Y1036850D01*
X848300Y1036684D01*
G01X852483Y1034392D02*
Y1036892D01*
X850941Y1035100D01*
X853025D01*
G01X843600Y1040184D02*
X843350Y1040309D01*
X843058Y1040392D01*
X842725D01*
X842350Y1040267D01*
X842058Y1040059D01*
X841850Y1039809D01*
X841683Y1039392D01*
X841641Y1039017D01*
X841725Y1038642D01*
X841850Y1038392D01*
X842100Y1038142D01*
X842391Y1037975D01*
X842683Y1037892D01*
X842975D01*
X843266Y1037975D01*
X843516Y1038100D01*
X843725Y1038267D01*
G01X845783Y1037892D02*
Y1040392D01*
X845283Y1039892D01*
G01Y1037892D02*
X846283D01*
G01X847966Y1038392D02*
X848216Y1038100D01*
X848550Y1037934D01*
X848925Y1037892D01*
X849258Y1037934D01*
X849591Y1038142D01*
X849800Y1038392D01*
X849841Y1038642D01*
X849758Y1038934D01*
X849466Y1039142D01*
X849175Y1039225D01*
X848800D01*
G01X849175D02*
X849425Y1039350D01*
X849633Y1039559D01*
X849716Y1039809D01*
X849633Y1040059D01*
X849425Y1040267D01*
X849050Y1040392D01*
X848675Y1040350D01*
X848300Y1040184D01*
G01X851066Y1038267D02*
X851316Y1038059D01*
X851608Y1037934D01*
X851983Y1037892D01*
X852358Y1037975D01*
X852650Y1038142D01*
X852858Y1038434D01*
X852900Y1038767D01*
X852816Y1039100D01*
X852608Y1039309D01*
X852316Y1039475D01*
X852025Y1039517D01*
X851733Y1039475D01*
X851358Y1039309D01*
X851483Y1040392D01*
X852608D01*
G01X853600Y1053184D02*
X853350Y1053309D01*
X853058Y1053392D01*
X852725D01*
X852350Y1053267D01*
X852058Y1053059D01*
X851850Y1052809D01*
X851683Y1052392D01*
X851641Y1052017D01*
X851725Y1051642D01*
X851850Y1051392D01*
X852100Y1051142D01*
X852391Y1050975D01*
X852683Y1050892D01*
X852975D01*
X853266Y1050975D01*
X853516Y1051100D01*
X853725Y1051267D01*
G01X855783Y1050892D02*
Y1053392D01*
X855283Y1052892D01*
G01Y1050892D02*
X856283D01*
G01X857966Y1051392D02*
X858216Y1051100D01*
X858550Y1050934D01*
X858925Y1050892D01*
X859258Y1050934D01*
X859591Y1051142D01*
X859800Y1051392D01*
X859841Y1051642D01*
X859758Y1051934D01*
X859466Y1052142D01*
X859175Y1052225D01*
X858800D01*
G01X859175D02*
X859425Y1052350D01*
X859633Y1052559D01*
X859716Y1052809D01*
X859633Y1053059D01*
X859425Y1053267D01*
X859050Y1053392D01*
X858675Y1053350D01*
X858300Y1053184D01*
G01X861191Y1051934D02*
X861483Y1052225D01*
X861733Y1052392D01*
X862066Y1052475D01*
X862358Y1052392D01*
X862566Y1052225D01*
X862733Y1051975D01*
X862775Y1051684D01*
X862733Y1051434D01*
X862566Y1051184D01*
X862316Y1050975D01*
X862025Y1050892D01*
X861691Y1050975D01*
X861400Y1051225D01*
X861233Y1051600D01*
X861191Y1052017D01*
X861275Y1052559D01*
X861400Y1052850D01*
X861608Y1053142D01*
X861900Y1053350D01*
X862191Y1053392D01*
X862483Y1053309D01*
X862691Y1053100D01*
G01X853266Y1056842D02*
X853016Y1056967D01*
X852724Y1057050D01*
X852391D01*
X852016Y1056925D01*
X851724Y1056717D01*
X851516Y1056467D01*
X851349Y1056050D01*
X851307Y1055675D01*
X851391Y1055300D01*
X851516Y1055050D01*
X851766Y1054800D01*
X852057Y1054633D01*
X852349Y1054550D01*
X852641D01*
X852932Y1054633D01*
X853182Y1054758D01*
X853391Y1054925D01*
G01X855449Y1054550D02*
Y1057050D01*
X854949Y1056550D01*
G01Y1054550D02*
X855949D01*
G01X857632Y1055050D02*
X857882Y1054758D01*
X858216Y1054592D01*
X858591Y1054550D01*
X858924Y1054592D01*
X859257Y1054800D01*
X859466Y1055050D01*
X859507Y1055300D01*
X859424Y1055592D01*
X859132Y1055800D01*
X858841Y1055883D01*
X858466D01*
G01X858841D02*
X859091Y1056008D01*
X859299Y1056217D01*
X859382Y1056467D01*
X859299Y1056717D01*
X859091Y1056925D01*
X858716Y1057050D01*
X858341Y1057008D01*
X857966Y1056842D01*
G01X861566Y1054550D02*
X861649Y1055092D01*
X861774Y1055550D01*
X861941Y1055967D01*
X862149Y1056425D01*
X862482Y1057050D01*
X860816D01*
G01X907850Y988392D02*
Y990892D01*
X908891D01*
X909225Y990767D01*
X909433Y990600D01*
X909516Y990267D01*
X909433Y989934D01*
X909183Y989725D01*
X908891Y989600D01*
X907850D01*
G01X908891D02*
X909516Y988392D01*
G01X911783D02*
Y990892D01*
X911283Y990392D01*
G01Y988392D02*
X912283D01*
G01X914091Y990475D02*
X914341Y990725D01*
X914633Y990850D01*
X914966Y990892D01*
X915383Y990809D01*
X915675Y990600D01*
X915758Y990350D01*
X915716Y990100D01*
X915550Y989892D01*
X914716Y989475D01*
X914341Y989184D01*
X914091Y988767D01*
X914008Y988392D01*
X915758D01*
G01X917983D02*
X918275Y988434D01*
X918608Y988559D01*
X918816Y988767D01*
X918900Y989059D01*
X918816Y989350D01*
X918566Y989600D01*
X918191Y989725D01*
X917775D01*
X917525Y989809D01*
X917316Y990017D01*
X917233Y990309D01*
X917358Y990600D01*
X917650Y990809D01*
X917983Y990892D01*
X918316Y990809D01*
X918608Y990600D01*
X918733Y990309D01*
X918650Y990017D01*
X918441Y989809D01*
X918191Y989725D01*
X917775D01*
X917400Y989600D01*
X917150Y989350D01*
X917066Y989059D01*
X917150Y988767D01*
X917358Y988559D01*
X917691Y988434D01*
X917983Y988392D01*
G01X907850Y984392D02*
Y986892D01*
X908891D01*
X909225Y986767D01*
X909433Y986600D01*
X909516Y986267D01*
X909433Y985934D01*
X909183Y985725D01*
X908891Y985600D01*
X907850D01*
G01X908891D02*
X909516Y984392D01*
G01X911783D02*
Y986892D01*
X911283Y986392D01*
G01Y984392D02*
X912283D01*
G01X913966Y984892D02*
X914216Y984600D01*
X914550Y984434D01*
X914925Y984392D01*
X915258Y984434D01*
X915591Y984642D01*
X915800Y984892D01*
X915841Y985142D01*
X915758Y985434D01*
X915466Y985642D01*
X915175Y985725D01*
X914800D01*
G01X915175D02*
X915425Y985850D01*
X915633Y986059D01*
X915716Y986309D01*
X915633Y986559D01*
X915425Y986767D01*
X915050Y986892D01*
X914675Y986850D01*
X914300Y986684D01*
G01X917983Y986892D02*
X917650Y986809D01*
X917400Y986600D01*
X917233Y986350D01*
X917108Y986017D01*
X917066Y985642D01*
X917108Y985267D01*
X917233Y984934D01*
X917400Y984684D01*
X917650Y984475D01*
X917983Y984392D01*
X918316Y984475D01*
X918566Y984684D01*
X918733Y984934D01*
X918858Y985267D01*
X918900Y985642D01*
X918858Y986017D01*
X918733Y986350D01*
X918566Y986600D01*
X918316Y986809D01*
X917983Y986892D01*
G01X907850Y980392D02*
Y982892D01*
X908891D01*
X909225Y982767D01*
X909433Y982600D01*
X909516Y982267D01*
X909433Y981934D01*
X909183Y981725D01*
X908891Y981600D01*
X907850D01*
G01X908891D02*
X909516Y980392D01*
G01X911783D02*
Y982892D01*
X911283Y982392D01*
G01Y980392D02*
X912283D01*
G01X913966Y980892D02*
X914216Y980600D01*
X914550Y980434D01*
X914925Y980392D01*
X915258Y980434D01*
X915591Y980642D01*
X915800Y980892D01*
X915841Y981142D01*
X915758Y981434D01*
X915466Y981642D01*
X915175Y981725D01*
X914800D01*
G01X915175D02*
X915425Y981850D01*
X915633Y982059D01*
X915716Y982309D01*
X915633Y982559D01*
X915425Y982767D01*
X915050Y982892D01*
X914675Y982850D01*
X914300Y982684D01*
G01X917191Y982475D02*
X917441Y982725D01*
X917733Y982850D01*
X918066Y982892D01*
X918483Y982809D01*
X918775Y982600D01*
X918858Y982350D01*
X918816Y982100D01*
X918650Y981892D01*
X917816Y981475D01*
X917441Y981184D01*
X917191Y980767D01*
X917108Y980392D01*
X918858D01*
G01X925299Y977600D02*
X911299D01*
G01X872969Y996841D02*
Y1158041D01*
X886569D01*
Y1170991D01*
X904769D01*
Y1158041D01*
X933669D01*
Y1147691D01*
X926969D01*
Y1007191D01*
X933669D01*
Y996841D01*
X904769D01*
Y983891D01*
X886569D01*
Y996841D01*
X872969D01*
G01X864708Y1077267D02*
X864583Y1077017D01*
X864500Y1076725D01*
Y1076392D01*
X864625Y1076017D01*
X864833Y1075725D01*
X865083Y1075517D01*
X865500Y1075350D01*
X865875Y1075308D01*
X866250Y1075392D01*
X866500Y1075517D01*
X866750Y1075767D01*
X866917Y1076058D01*
X867000Y1076350D01*
Y1076642D01*
X866917Y1076933D01*
X866792Y1077183D01*
X866625Y1077392D01*
G01X867000Y1079450D02*
X864500D01*
X865000Y1078950D01*
G01X867000D02*
Y1079950D01*
G01Y1083050D02*
X864500D01*
X866292Y1081508D01*
Y1083592D01*
G01X867000Y1085567D02*
X866458Y1085650D01*
X866000Y1085775D01*
X865583Y1085942D01*
X865125Y1086150D01*
X864500Y1086483D01*
Y1084817D01*
G01X863707Y1110817D02*
X863582Y1110567D01*
X863499Y1110275D01*
Y1109942D01*
X863624Y1109567D01*
X863832Y1109275D01*
X864082Y1109067D01*
X864499Y1108900D01*
X864874Y1108858D01*
X865249Y1108942D01*
X865499Y1109067D01*
X865749Y1109317D01*
X865916Y1109608D01*
X865999Y1109900D01*
Y1110192D01*
X865916Y1110483D01*
X865791Y1110733D01*
X865624Y1110942D01*
G01X865999Y1113000D02*
X863499D01*
X863999Y1112500D01*
G01X865999D02*
Y1113500D01*
G01X865499Y1115183D02*
X865791Y1115433D01*
X865957Y1115767D01*
X865999Y1116142D01*
X865957Y1116475D01*
X865749Y1116808D01*
X865499Y1117017D01*
X865249Y1117058D01*
X864957Y1116975D01*
X864749Y1116683D01*
X864666Y1116392D01*
Y1116017D01*
G01Y1116392D02*
X864541Y1116642D01*
X864332Y1116850D01*
X864082Y1116933D01*
X863832Y1116850D01*
X863624Y1116642D01*
X863499Y1116267D01*
X863541Y1115892D01*
X863707Y1115517D01*
G01X865999Y1119200D02*
X865957Y1119492D01*
X865832Y1119825D01*
X865624Y1120033D01*
X865332Y1120117D01*
X865041Y1120033D01*
X864791Y1119783D01*
X864666Y1119408D01*
Y1118992D01*
X864582Y1118742D01*
X864374Y1118533D01*
X864082Y1118450D01*
X863791Y1118575D01*
X863582Y1118867D01*
X863499Y1119200D01*
X863582Y1119533D01*
X863791Y1119825D01*
X864082Y1119950D01*
X864374Y1119867D01*
X864582Y1119658D01*
X864666Y1119408D01*
Y1118992D01*
X864791Y1118617D01*
X865041Y1118367D01*
X865332Y1118283D01*
X865624Y1118367D01*
X865832Y1118575D01*
X865957Y1118908D01*
X865999Y1119200D01*
G01X867989Y1091535D02*
X865489D01*
Y1092576D01*
X865614Y1092910D01*
X865781Y1093118D01*
X866114Y1093201D01*
X866447Y1093118D01*
X866656Y1092868D01*
X866781Y1092576D01*
Y1091535D01*
G01Y1092576D02*
X867989Y1093201D01*
G01Y1095468D02*
X865489D01*
X865989Y1094968D01*
G01X867989D02*
Y1095968D01*
G01X867489Y1097651D02*
X867781Y1097901D01*
X867947Y1098235D01*
X867989Y1098610D01*
X867947Y1098943D01*
X867739Y1099276D01*
X867489Y1099485D01*
X867239Y1099526D01*
X866947Y1099443D01*
X866739Y1099151D01*
X866656Y1098860D01*
Y1098485D01*
G01Y1098860D02*
X866531Y1099110D01*
X866322Y1099318D01*
X866072Y1099401D01*
X865822Y1099318D01*
X865614Y1099110D01*
X865489Y1098735D01*
X865531Y1098360D01*
X865697Y1097985D01*
G01X867989Y1102168D02*
X865489D01*
X867281Y1100626D01*
Y1102710D01*
G01X858583Y1090192D02*
Y1103192D01*
G01X866999Y1124067D02*
X864499D01*
Y1125108D01*
X864624Y1125442D01*
X864791Y1125650D01*
X865124Y1125733D01*
X865457Y1125650D01*
X865666Y1125400D01*
X865791Y1125108D01*
Y1124067D01*
G01Y1125108D02*
X866999Y1125733D01*
G01Y1128000D02*
X864499D01*
X864999Y1127500D01*
G01X866999D02*
Y1128500D01*
G01X866499Y1130183D02*
X866791Y1130433D01*
X866957Y1130767D01*
X866999Y1131142D01*
X866957Y1131475D01*
X866749Y1131808D01*
X866499Y1132017D01*
X866249Y1132058D01*
X865957Y1131975D01*
X865749Y1131683D01*
X865666Y1131392D01*
Y1131017D01*
G01Y1131392D02*
X865541Y1131642D01*
X865332Y1131850D01*
X865082Y1131933D01*
X864832Y1131850D01*
X864624Y1131642D01*
X864499Y1131267D01*
X864541Y1130892D01*
X864707Y1130517D01*
G01X866999Y1134200D02*
X866957Y1134492D01*
X866832Y1134825D01*
X866624Y1135033D01*
X866332Y1135117D01*
X866041Y1135033D01*
X865791Y1134783D01*
X865666Y1134408D01*
Y1133992D01*
X865582Y1133742D01*
X865374Y1133533D01*
X865082Y1133450D01*
X864791Y1133575D01*
X864582Y1133867D01*
X864499Y1134200D01*
X864582Y1134533D01*
X864791Y1134825D01*
X865082Y1134950D01*
X865374Y1134867D01*
X865582Y1134658D01*
X865666Y1134408D01*
Y1133992D01*
X865791Y1133617D01*
X866041Y1133367D01*
X866332Y1133283D01*
X866624Y1133367D01*
X866832Y1133575D01*
X866957Y1133908D01*
X866999Y1134200D01*
G01X861999Y1123050D02*
Y1136050D01*
G01X842133Y1089392D02*
Y1085392D01*
X849533D01*
G01X849500Y1081200D02*
Y1085200D01*
X842100D01*
G01X863000Y1075517D02*
X860500D01*
Y1076558D01*
X860625Y1076892D01*
X860792Y1077100D01*
X861125Y1077183D01*
X861458Y1077100D01*
X861667Y1076850D01*
X861792Y1076558D01*
Y1075517D01*
G01Y1076558D02*
X863000Y1077183D01*
G01Y1079450D02*
X860500D01*
X861000Y1078950D01*
G01X863000D02*
Y1079950D01*
G01X862500Y1081633D02*
X862792Y1081883D01*
X862958Y1082217D01*
X863000Y1082592D01*
X862958Y1082925D01*
X862750Y1083258D01*
X862500Y1083467D01*
X862250Y1083508D01*
X861958Y1083425D01*
X861750Y1083133D01*
X861667Y1082842D01*
Y1082467D01*
G01Y1082842D02*
X861542Y1083092D01*
X861333Y1083300D01*
X861083Y1083383D01*
X860833Y1083300D01*
X860625Y1083092D01*
X860500Y1082717D01*
X860542Y1082342D01*
X860708Y1081967D01*
G01X862708Y1084942D02*
X862917Y1085233D01*
X863000Y1085567D01*
X862917Y1085900D01*
X862667Y1086192D01*
X862292Y1086400D01*
X861917Y1086483D01*
X861458D01*
X861083Y1086400D01*
X860750Y1086192D01*
X860583Y1085942D01*
X860500Y1085650D01*
X860583Y1085317D01*
X860750Y1085067D01*
X861000Y1084900D01*
X861333Y1084817D01*
X861625Y1084900D01*
X861917Y1085108D01*
X862083Y1085358D01*
X862125Y1085650D01*
X862042Y1085983D01*
X861833Y1086233D01*
X861458Y1086483D01*
G01X842833Y1143592D02*
Y1138092D01*
G01X843533D02*
Y1143592D01*
G01X851533Y1138092D02*
X843533D01*
G01X851533Y1143592D02*
Y1138092D01*
G01X852233D02*
Y1143592D01*
G01X860233Y1138092D02*
X852233D01*
G01X860233Y1143592D02*
Y1138092D01*
G01X859208Y1110767D02*
X859083Y1110517D01*
X859000Y1110225D01*
Y1109892D01*
X859125Y1109517D01*
X859333Y1109225D01*
X859583Y1109017D01*
X860000Y1108850D01*
X860375Y1108808D01*
X860750Y1108892D01*
X861000Y1109017D01*
X861250Y1109267D01*
X861417Y1109558D01*
X861500Y1109850D01*
Y1110142D01*
X861417Y1110433D01*
X861292Y1110683D01*
X861125Y1110892D01*
G01X861500Y1112950D02*
X859000D01*
X859500Y1112450D01*
G01X861500D02*
Y1113450D01*
G01X861000Y1115133D02*
X861292Y1115383D01*
X861458Y1115717D01*
X861500Y1116092D01*
X861458Y1116425D01*
X861250Y1116758D01*
X861000Y1116967D01*
X860750Y1117008D01*
X860458Y1116925D01*
X860250Y1116633D01*
X860167Y1116342D01*
Y1115967D01*
G01Y1116342D02*
X860042Y1116592D01*
X859833Y1116800D01*
X859583Y1116883D01*
X859333Y1116800D01*
X859125Y1116592D01*
X859000Y1116217D01*
X859042Y1115842D01*
X859208Y1115467D01*
G01X861208Y1118442D02*
X861417Y1118733D01*
X861500Y1119067D01*
X861417Y1119400D01*
X861167Y1119692D01*
X860792Y1119900D01*
X860417Y1119983D01*
X859958D01*
X859583Y1119900D01*
X859250Y1119692D01*
X859083Y1119442D01*
X859000Y1119150D01*
X859083Y1118817D01*
X859250Y1118567D01*
X859500Y1118400D01*
X859833Y1118317D01*
X860125Y1118400D01*
X860417Y1118608D01*
X860583Y1118858D01*
X860625Y1119150D01*
X860542Y1119483D01*
X860333Y1119733D01*
X859958Y1119983D01*
G01X844413Y1104313D02*
Y1109813D01*
G01X852413Y1104313D02*
X844413D01*
G01X852413Y1109813D02*
Y1104313D01*
G01Y1121913D02*
Y1116413D01*
G01X844413Y1121913D02*
X852413D01*
G01X844413Y1116413D02*
Y1121913D01*
G01X841500Y1072500D02*
Y1086500D01*
G01X861807Y1155817D02*
X861682Y1155567D01*
X861599Y1155275D01*
Y1154942D01*
X861724Y1154567D01*
X861932Y1154275D01*
X862182Y1154067D01*
X862599Y1153900D01*
X862974Y1153858D01*
X863349Y1153942D01*
X863599Y1154067D01*
X863849Y1154317D01*
X864016Y1154608D01*
X864099Y1154900D01*
Y1155192D01*
X864016Y1155483D01*
X863891Y1155733D01*
X863724Y1155942D01*
G01X864099Y1158000D02*
X861599D01*
X862099Y1157500D01*
G01X864099D02*
Y1158500D01*
G01Y1161600D02*
X861599D01*
X863391Y1160058D01*
Y1162142D01*
G01X863057Y1163408D02*
X862766Y1163700D01*
X862599Y1163950D01*
X862516Y1164283D01*
X862599Y1164575D01*
X862766Y1164783D01*
X863016Y1164950D01*
X863307Y1164992D01*
X863557Y1164950D01*
X863807Y1164783D01*
X864016Y1164533D01*
X864099Y1164242D01*
X864016Y1163908D01*
X863766Y1163617D01*
X863391Y1163450D01*
X862974Y1163408D01*
X862432Y1163492D01*
X862141Y1163617D01*
X861849Y1163825D01*
X861641Y1164117D01*
X861599Y1164408D01*
X861682Y1164700D01*
X861891Y1164908D01*
G01X842833Y1155692D02*
Y1150192D01*
G01X846241Y1160059D02*
X846116Y1159809D01*
X846033Y1159517D01*
Y1159184D01*
X846158Y1158809D01*
X846366Y1158517D01*
X846616Y1158309D01*
X847033Y1158142D01*
X847408Y1158100D01*
X847783Y1158184D01*
X848033Y1158309D01*
X848283Y1158559D01*
X848450Y1158850D01*
X848533Y1159142D01*
Y1159434D01*
X848450Y1159725D01*
X848325Y1159975D01*
X848158Y1160184D01*
G01X848533Y1162242D02*
X846033D01*
X846533Y1161742D01*
G01X848533D02*
Y1162742D01*
G01Y1165842D02*
X846033D01*
X847825Y1164300D01*
Y1166384D01*
G01X848533Y1168942D02*
X846033D01*
X847825Y1167400D01*
Y1169484D01*
G01X851533Y1155692D02*
Y1150192D01*
G01X843533Y1155692D02*
X851533D01*
G01X843533Y1150192D02*
Y1155692D01*
G01X854941Y1160059D02*
X854816Y1159809D01*
X854733Y1159517D01*
Y1159184D01*
X854858Y1158809D01*
X855066Y1158517D01*
X855316Y1158309D01*
X855733Y1158142D01*
X856108Y1158100D01*
X856483Y1158184D01*
X856733Y1158309D01*
X856983Y1158559D01*
X857150Y1158850D01*
X857233Y1159142D01*
Y1159434D01*
X857150Y1159725D01*
X857025Y1159975D01*
X856858Y1160184D01*
G01X857233Y1162242D02*
X854733D01*
X855233Y1161742D01*
G01X857233D02*
Y1162742D01*
G01Y1165842D02*
X854733D01*
X856525Y1164300D01*
Y1166384D01*
G01X856858Y1167525D02*
X857066Y1167775D01*
X857191Y1168067D01*
X857233Y1168442D01*
X857150Y1168817D01*
X856983Y1169109D01*
X856691Y1169317D01*
X856358Y1169359D01*
X856025Y1169275D01*
X855816Y1169067D01*
X855650Y1168775D01*
X855608Y1168484D01*
X855650Y1168192D01*
X855816Y1167817D01*
X854733Y1167942D01*
Y1169067D01*
G01X860233Y1155692D02*
Y1150192D01*
G01X852233Y1155692D02*
X860233D01*
G01X852233Y1150192D02*
Y1155692D01*
G01X914499Y1373550D02*
Y1383550D01*
G01X921499D02*
Y1373550D01*
G01Y1378550D02*
X914499D01*
G01X924932Y1373550D02*
Y1383550D01*
X928266D01*
X929599Y1383050D01*
X930599Y1382383D01*
X931432Y1381383D01*
X932099Y1380216D01*
X932266Y1378550D01*
X932099Y1376883D01*
X931432Y1375717D01*
X930599Y1374716D01*
X929599Y1374050D01*
X928266Y1373550D01*
X924932D01*
G01X935532D02*
Y1383550D01*
X938866D01*
X940199Y1383050D01*
X941199Y1382383D01*
X942032Y1381383D01*
X942699Y1380216D01*
X942866Y1378550D01*
X942699Y1376883D01*
X942032Y1375717D01*
X941199Y1374716D01*
X940199Y1374050D01*
X938866Y1373550D01*
X935532D01*
G01X949799D02*
Y1383550D01*
X947799Y1381550D01*
G01Y1373550D02*
X951799D01*
G01X955399Y1370217D02*
X965399D01*
G01X967666Y1383550D02*
Y1373550D01*
X974332D01*
G01X984932D02*
X978266D01*
Y1383550D01*
X984932D01*
G01X982266Y1378717D02*
X978266D01*
G01X988532Y1373550D02*
Y1383550D01*
X991866D01*
X993199Y1383050D01*
X994199Y1382383D01*
X995032Y1381383D01*
X995699Y1380216D01*
X995866Y1378550D01*
X995699Y1376883D01*
X995032Y1375717D01*
X994199Y1374716D01*
X993199Y1374050D01*
X991866Y1373550D01*
X988532D01*
G01X892017Y1371063D02*
Y1368563D01*
X893683D01*
G01X896783D02*
X895117D01*
Y1371063D01*
X896783D01*
G01X896117Y1369855D02*
X895117D01*
G01X898133Y1368563D02*
Y1371063D01*
X898967D01*
X899300Y1370938D01*
X899550Y1370771D01*
X899758Y1370521D01*
X899925Y1370230D01*
X899967Y1369813D01*
X899925Y1369396D01*
X899758Y1369105D01*
X899550Y1368855D01*
X899300Y1368688D01*
X898967Y1368563D01*
X898133D01*
G01X901358Y1370646D02*
X901608Y1370896D01*
X901900Y1371021D01*
X902233Y1371063D01*
X902650Y1370980D01*
X902942Y1370771D01*
X903025Y1370521D01*
X902983Y1370271D01*
X902817Y1370063D01*
X901983Y1369646D01*
X901608Y1369355D01*
X901358Y1368938D01*
X901275Y1368563D01*
X903025D01*
G01X901369Y1382383D02*
Y1374783D01*
X889969D01*
Y1382383D01*
X901369D01*
G01X874616Y1344750D02*
Y1347250D01*
X875657D01*
X875991Y1347125D01*
X876199Y1346958D01*
X876282Y1346625D01*
X876199Y1346292D01*
X875949Y1346083D01*
X875657Y1345958D01*
X874616D01*
G01X875657D02*
X876282Y1344750D01*
G01X878549D02*
Y1347250D01*
X878049Y1346750D01*
G01Y1344750D02*
X879049D01*
G01X881649D02*
Y1347250D01*
X881149Y1346750D01*
G01Y1344750D02*
X882149D01*
G01X885249D02*
Y1347250D01*
X883707Y1345458D01*
X885791D01*
G01X875199Y1357550D02*
Y1361550D01*
X867799D01*
G01X865344Y1388296D02*
Y1390796D01*
X866385D01*
X866719Y1390671D01*
X866927Y1390504D01*
X867010Y1390171D01*
X866927Y1389838D01*
X866677Y1389629D01*
X866385Y1389504D01*
X865344D01*
G01X866385D02*
X867010Y1388296D01*
G01X869277D02*
Y1390796D01*
X868777Y1390296D01*
G01Y1388296D02*
X869777D01*
G01X872377D02*
Y1390796D01*
X871877Y1390296D01*
G01Y1388296D02*
X872877D01*
G01X874560Y1388671D02*
X874810Y1388463D01*
X875102Y1388338D01*
X875477Y1388296D01*
X875852Y1388379D01*
X876144Y1388546D01*
X876352Y1388838D01*
X876394Y1389171D01*
X876310Y1389504D01*
X876102Y1389713D01*
X875810Y1389879D01*
X875519Y1389921D01*
X875227Y1389879D01*
X874852Y1389713D01*
X874977Y1390796D01*
X876102D01*
G01X868127Y1381796D02*
Y1377796D01*
X875527D01*
G01X865344Y1384296D02*
Y1386796D01*
X866385D01*
X866719Y1386671D01*
X866927Y1386504D01*
X867010Y1386171D01*
X866927Y1385838D01*
X866677Y1385629D01*
X866385Y1385504D01*
X865344D01*
G01X866385D02*
X867010Y1384296D01*
G01X869277D02*
Y1386796D01*
X868777Y1386296D01*
G01Y1384296D02*
X869777D01*
G01X872377D02*
Y1386796D01*
X871877Y1386296D01*
G01Y1384296D02*
X872877D01*
G01X875394D02*
X875477Y1384838D01*
X875602Y1385296D01*
X875769Y1385713D01*
X875977Y1386171D01*
X876310Y1386796D01*
X874644D01*
G01X868127Y1377796D02*
Y1373796D01*
X875527D01*
G01X874616Y1352750D02*
Y1355250D01*
X875657D01*
X875991Y1355125D01*
X876199Y1354958D01*
X876282Y1354625D01*
X876199Y1354292D01*
X875949Y1354083D01*
X875657Y1353958D01*
X874616D01*
G01X875657D02*
X876282Y1352750D01*
G01X878549D02*
Y1355250D01*
X878049Y1354750D01*
G01Y1352750D02*
X879049D01*
G01X881649D02*
Y1355250D01*
X881149Y1354750D01*
G01Y1352750D02*
X882149D01*
G01X884749D02*
X885041Y1352792D01*
X885374Y1352917D01*
X885582Y1353125D01*
X885666Y1353417D01*
X885582Y1353708D01*
X885332Y1353958D01*
X884957Y1354083D01*
X884541D01*
X884291Y1354167D01*
X884082Y1354375D01*
X883999Y1354667D01*
X884124Y1354958D01*
X884416Y1355167D01*
X884749Y1355250D01*
X885082Y1355167D01*
X885374Y1354958D01*
X885499Y1354667D01*
X885416Y1354375D01*
X885207Y1354167D01*
X884957Y1354083D01*
X884541D01*
X884166Y1353958D01*
X883916Y1353708D01*
X883832Y1353417D01*
X883916Y1353125D01*
X884124Y1352917D01*
X884457Y1352792D01*
X884749Y1352750D01*
G01X875199Y1365550D02*
Y1369550D01*
X867799D01*
G01X874616Y1348750D02*
Y1351250D01*
X875657D01*
X875991Y1351125D01*
X876199Y1350958D01*
X876282Y1350625D01*
X876199Y1350292D01*
X875949Y1350083D01*
X875657Y1349958D01*
X874616D01*
G01X875657D02*
X876282Y1348750D01*
G01X878549D02*
Y1351250D01*
X878049Y1350750D01*
G01Y1348750D02*
X879049D01*
G01X881649D02*
Y1351250D01*
X881149Y1350750D01*
G01Y1348750D02*
X882149D01*
G01X883957Y1349792D02*
X884249Y1350083D01*
X884499Y1350250D01*
X884832Y1350333D01*
X885124Y1350250D01*
X885332Y1350083D01*
X885499Y1349833D01*
X885541Y1349542D01*
X885499Y1349292D01*
X885332Y1349042D01*
X885082Y1348833D01*
X884791Y1348750D01*
X884457Y1348833D01*
X884166Y1349083D01*
X883999Y1349458D01*
X883957Y1349875D01*
X884041Y1350417D01*
X884166Y1350708D01*
X884374Y1351000D01*
X884666Y1351208D01*
X884957Y1351250D01*
X885249Y1351167D01*
X885457Y1350958D01*
G01X875199Y1361550D02*
Y1365550D01*
X867799D01*
G01X852017Y1376500D02*
Y1379000D01*
X853058D01*
X853392Y1378875D01*
X853600Y1378708D01*
X853683Y1378375D01*
X853600Y1378042D01*
X853350Y1377833D01*
X853058Y1377708D01*
X852017D01*
G01X853058D02*
X853683Y1376500D01*
G01X856450D02*
Y1379000D01*
X854908Y1377208D01*
X856992D01*
G01X859050Y1376500D02*
X859342Y1376542D01*
X859675Y1376667D01*
X859883Y1376875D01*
X859967Y1377167D01*
X859883Y1377458D01*
X859633Y1377708D01*
X859258Y1377833D01*
X858842D01*
X858592Y1377917D01*
X858383Y1378125D01*
X858300Y1378417D01*
X858425Y1378708D01*
X858717Y1378917D01*
X859050Y1379000D01*
X859383Y1378917D01*
X859675Y1378708D01*
X859800Y1378417D01*
X859717Y1378125D01*
X859508Y1377917D01*
X859258Y1377833D01*
X858842D01*
X858467Y1377708D01*
X858217Y1377458D01*
X858133Y1377167D01*
X858217Y1376875D01*
X858425Y1376667D01*
X858758Y1376542D01*
X859050Y1376500D01*
G01X861442Y1376792D02*
X861733Y1376583D01*
X862067Y1376500D01*
X862400Y1376583D01*
X862692Y1376833D01*
X862900Y1377208D01*
X862983Y1377583D01*
Y1378042D01*
X862900Y1378417D01*
X862692Y1378750D01*
X862442Y1378917D01*
X862150Y1379000D01*
X861817Y1378917D01*
X861567Y1378750D01*
X861400Y1378500D01*
X861317Y1378167D01*
X861400Y1377875D01*
X861608Y1377583D01*
X861858Y1377417D01*
X862150Y1377375D01*
X862483Y1377458D01*
X862733Y1377667D01*
X862983Y1378042D01*
G01X856399Y1374200D02*
Y1370200D01*
X863799D01*
G01X855399Y1350550D02*
X855066Y1350592D01*
X854774Y1350758D01*
X854524Y1351008D01*
X854357Y1351300D01*
X854274Y1351633D01*
Y1351967D01*
X854357Y1352300D01*
X854524Y1352592D01*
X854774Y1352842D01*
X855066Y1353008D01*
X855399Y1353050D01*
X855732Y1353008D01*
X856024Y1352842D01*
X856274Y1352592D01*
X856441Y1352300D01*
X856524Y1351967D01*
Y1351633D01*
X856441Y1351300D01*
X856274Y1351008D01*
X856024Y1350758D01*
X855732Y1350592D01*
X855399Y1350550D01*
G01X855732Y1351217D02*
X856232Y1350550D01*
G01X857582Y1351050D02*
X857832Y1350758D01*
X858166Y1350592D01*
X858541Y1350550D01*
X858874Y1350592D01*
X859207Y1350800D01*
X859416Y1351050D01*
X859457Y1351300D01*
X859374Y1351592D01*
X859082Y1351800D01*
X858791Y1351883D01*
X858416D01*
G01X858791D02*
X859041Y1352008D01*
X859249Y1352217D01*
X859332Y1352467D01*
X859249Y1352717D01*
X859041Y1352925D01*
X858666Y1353050D01*
X858291Y1353008D01*
X857916Y1352842D01*
G01X860682Y1350925D02*
X860932Y1350717D01*
X861224Y1350592D01*
X861599Y1350550D01*
X861974Y1350633D01*
X862266Y1350800D01*
X862474Y1351092D01*
X862516Y1351425D01*
X862432Y1351758D01*
X862224Y1351967D01*
X861932Y1352133D01*
X861641Y1352175D01*
X861349Y1352133D01*
X860974Y1351967D01*
X861099Y1353050D01*
X862224D01*
G01X867199Y1369300D02*
X853199D01*
G01X867199Y1356300D02*
Y1369300D01*
G01X853199Y1356300D02*
X867199D01*
G01X853199Y1369300D02*
Y1356300D01*
G01X872969Y1402353D02*
Y1563553D01*
X886569D01*
Y1576503D01*
X904769D01*
Y1563553D01*
X933669D01*
Y1553203D01*
X926969D01*
Y1412703D01*
X933669D01*
Y1402353D01*
X904769D01*
Y1389403D01*
X886569D01*
Y1402353D01*
X872969D01*
G01X844594Y1441588D02*
X844344Y1441713D01*
X844052Y1441796D01*
X843719D01*
X843344Y1441671D01*
X843052Y1441463D01*
X842844Y1441213D01*
X842677Y1440796D01*
X842635Y1440421D01*
X842719Y1440046D01*
X842844Y1439796D01*
X843094Y1439546D01*
X843385Y1439379D01*
X843677Y1439296D01*
X843969D01*
X844260Y1439379D01*
X844510Y1439504D01*
X844719Y1439671D01*
G01X846777Y1439296D02*
Y1441796D01*
X846277Y1441296D01*
G01Y1439296D02*
X847277D01*
G01X849877D02*
Y1441796D01*
X849377Y1441296D01*
G01Y1439296D02*
X850377D01*
G01X852977D02*
X853269Y1439338D01*
X853602Y1439463D01*
X853810Y1439671D01*
X853894Y1439963D01*
X853810Y1440254D01*
X853560Y1440504D01*
X853185Y1440629D01*
X852769D01*
X852519Y1440713D01*
X852310Y1440921D01*
X852227Y1441213D01*
X852352Y1441504D01*
X852644Y1441713D01*
X852977Y1441796D01*
X853310Y1441713D01*
X853602Y1441504D01*
X853727Y1441213D01*
X853644Y1440921D01*
X853435Y1440713D01*
X853185Y1440629D01*
X852769D01*
X852394Y1440504D01*
X852144Y1440254D01*
X852060Y1439963D01*
X852144Y1439671D01*
X852352Y1439463D01*
X852685Y1439338D01*
X852977Y1439296D01*
G01X844766Y1445342D02*
X844516Y1445467D01*
X844224Y1445550D01*
X843891D01*
X843516Y1445425D01*
X843224Y1445217D01*
X843016Y1444967D01*
X842849Y1444550D01*
X842807Y1444175D01*
X842891Y1443800D01*
X843016Y1443550D01*
X843266Y1443300D01*
X843557Y1443133D01*
X843849Y1443050D01*
X844141D01*
X844432Y1443133D01*
X844682Y1443258D01*
X844891Y1443425D01*
G01X846949Y1443050D02*
Y1445550D01*
X846449Y1445050D01*
G01Y1443050D02*
X847449D01*
G01X850049D02*
Y1445550D01*
X849549Y1445050D01*
G01Y1443050D02*
X850549D01*
G01X852441Y1443342D02*
X852732Y1443133D01*
X853066Y1443050D01*
X853399Y1443133D01*
X853691Y1443383D01*
X853899Y1443758D01*
X853982Y1444133D01*
Y1444592D01*
X853899Y1444967D01*
X853691Y1445300D01*
X853441Y1445467D01*
X853149Y1445550D01*
X852816Y1445467D01*
X852566Y1445300D01*
X852399Y1445050D01*
X852316Y1444717D01*
X852399Y1444425D01*
X852607Y1444133D01*
X852857Y1443967D01*
X853149Y1443925D01*
X853482Y1444008D01*
X853732Y1444217D01*
X853982Y1444592D01*
G01X844094Y1466588D02*
X843844Y1466713D01*
X843552Y1466796D01*
X843219D01*
X842844Y1466671D01*
X842552Y1466463D01*
X842344Y1466213D01*
X842177Y1465796D01*
X842135Y1465421D01*
X842219Y1465046D01*
X842344Y1464796D01*
X842594Y1464546D01*
X842885Y1464379D01*
X843177Y1464296D01*
X843469D01*
X843760Y1464379D01*
X844010Y1464504D01*
X844219Y1464671D01*
G01X846277Y1464296D02*
Y1466796D01*
X845777Y1466296D01*
G01Y1464296D02*
X846777D01*
G01X848585Y1466379D02*
X848835Y1466629D01*
X849127Y1466754D01*
X849460Y1466796D01*
X849877Y1466713D01*
X850169Y1466504D01*
X850252Y1466254D01*
X850210Y1466004D01*
X850044Y1465796D01*
X849210Y1465379D01*
X848835Y1465088D01*
X848585Y1464671D01*
X848502Y1464296D01*
X850252D01*
G01X852477Y1466796D02*
X852144Y1466713D01*
X851894Y1466504D01*
X851727Y1466254D01*
X851602Y1465921D01*
X851560Y1465546D01*
X851602Y1465171D01*
X851727Y1464838D01*
X851894Y1464588D01*
X852144Y1464379D01*
X852477Y1464296D01*
X852810Y1464379D01*
X853060Y1464588D01*
X853227Y1464838D01*
X853352Y1465171D01*
X853394Y1465546D01*
X853352Y1465921D01*
X853227Y1466254D01*
X853060Y1466504D01*
X852810Y1466713D01*
X852477Y1466796D01*
G01X843766Y1470342D02*
X843516Y1470467D01*
X843224Y1470550D01*
X842891D01*
X842516Y1470425D01*
X842224Y1470217D01*
X842016Y1469967D01*
X841849Y1469550D01*
X841807Y1469175D01*
X841891Y1468800D01*
X842016Y1468550D01*
X842266Y1468300D01*
X842557Y1468133D01*
X842849Y1468050D01*
X843141D01*
X843432Y1468133D01*
X843682Y1468258D01*
X843891Y1468425D01*
G01X845949Y1468050D02*
Y1470550D01*
X845449Y1470050D01*
G01Y1468050D02*
X846449D01*
G01X848257Y1470133D02*
X848507Y1470383D01*
X848799Y1470508D01*
X849132Y1470550D01*
X849549Y1470467D01*
X849841Y1470258D01*
X849924Y1470008D01*
X849882Y1469758D01*
X849716Y1469550D01*
X848882Y1469133D01*
X848507Y1468842D01*
X848257Y1468425D01*
X848174Y1468050D01*
X849924D01*
G01X852149D02*
Y1470550D01*
X851649Y1470050D01*
G01Y1468050D02*
X852649D01*
G01X850517Y1472500D02*
Y1475000D01*
X851558D01*
X851892Y1474875D01*
X852100Y1474708D01*
X852183Y1474375D01*
X852100Y1474042D01*
X851850Y1473833D01*
X851558Y1473708D01*
X850517D01*
G01X851558D02*
X852183Y1472500D01*
G01X853533Y1473000D02*
X853783Y1472708D01*
X854117Y1472542D01*
X854492Y1472500D01*
X854825Y1472542D01*
X855158Y1472750D01*
X855367Y1473000D01*
X855408Y1473250D01*
X855325Y1473542D01*
X855033Y1473750D01*
X854742Y1473833D01*
X854367D01*
G01X854742D02*
X854992Y1473958D01*
X855200Y1474167D01*
X855283Y1474417D01*
X855200Y1474667D01*
X854992Y1474875D01*
X854617Y1475000D01*
X854242Y1474958D01*
X853867Y1474792D01*
G01X856633Y1472875D02*
X856883Y1472667D01*
X857175Y1472542D01*
X857550Y1472500D01*
X857925Y1472583D01*
X858217Y1472750D01*
X858425Y1473042D01*
X858467Y1473375D01*
X858383Y1473708D01*
X858175Y1473917D01*
X857883Y1474083D01*
X857592Y1474125D01*
X857300Y1474083D01*
X856925Y1473917D01*
X857050Y1475000D01*
X858175D01*
G01X859733Y1473000D02*
X859983Y1472708D01*
X860317Y1472542D01*
X860692Y1472500D01*
X861025Y1472542D01*
X861358Y1472750D01*
X861567Y1473000D01*
X861608Y1473250D01*
X861525Y1473542D01*
X861233Y1473750D01*
X860942Y1473833D01*
X860567D01*
G01X860942D02*
X861192Y1473958D01*
X861400Y1474167D01*
X861483Y1474417D01*
X861400Y1474667D01*
X861192Y1474875D01*
X860817Y1475000D01*
X860442Y1474958D01*
X860067Y1474792D01*
G01X866708Y1483267D02*
X866583Y1483017D01*
X866500Y1482725D01*
Y1482392D01*
X866625Y1482017D01*
X866833Y1481725D01*
X867083Y1481517D01*
X867500Y1481350D01*
X867875Y1481308D01*
X868250Y1481392D01*
X868500Y1481517D01*
X868750Y1481767D01*
X868917Y1482058D01*
X869000Y1482350D01*
Y1482642D01*
X868917Y1482933D01*
X868792Y1483183D01*
X868625Y1483392D01*
G01X869000Y1485450D02*
X866500D01*
X867000Y1484950D01*
G01X869000D02*
Y1485950D01*
G01X868500Y1487633D02*
X868792Y1487883D01*
X868958Y1488217D01*
X869000Y1488592D01*
X868958Y1488925D01*
X868750Y1489258D01*
X868500Y1489467D01*
X868250Y1489508D01*
X867958Y1489425D01*
X867750Y1489133D01*
X867667Y1488842D01*
Y1488467D01*
G01Y1488842D02*
X867542Y1489092D01*
X867333Y1489300D01*
X867083Y1489383D01*
X866833Y1489300D01*
X866625Y1489092D01*
X866500Y1488717D01*
X866542Y1488342D01*
X866708Y1487967D01*
G01X869000Y1491650D02*
X866500D01*
X867000Y1491150D01*
G01X869000D02*
Y1492150D01*
G01X867207Y1515317D02*
X867082Y1515067D01*
X866999Y1514775D01*
Y1514442D01*
X867124Y1514067D01*
X867332Y1513775D01*
X867582Y1513567D01*
X867999Y1513400D01*
X868374Y1513358D01*
X868749Y1513442D01*
X868999Y1513567D01*
X869249Y1513817D01*
X869416Y1514108D01*
X869499Y1514400D01*
Y1514692D01*
X869416Y1514983D01*
X869291Y1515233D01*
X869124Y1515442D01*
G01X869499Y1517500D02*
X866999D01*
X867499Y1517000D01*
G01X869499D02*
Y1518000D01*
G01X867416Y1519808D02*
X867166Y1520058D01*
X867041Y1520350D01*
X866999Y1520683D01*
X867082Y1521100D01*
X867291Y1521392D01*
X867541Y1521475D01*
X867791Y1521433D01*
X867999Y1521267D01*
X868416Y1520433D01*
X868707Y1520058D01*
X869124Y1519808D01*
X869499Y1519725D01*
Y1521475D01*
G01X867416Y1522908D02*
X867166Y1523158D01*
X867041Y1523450D01*
X866999Y1523783D01*
X867082Y1524200D01*
X867291Y1524492D01*
X867541Y1524575D01*
X867791Y1524533D01*
X867999Y1524367D01*
X868416Y1523533D01*
X868707Y1523158D01*
X869124Y1522908D01*
X869499Y1522825D01*
Y1524575D01*
G01X864908Y1558367D02*
X864783Y1558117D01*
X864700Y1557825D01*
Y1557492D01*
X864825Y1557117D01*
X865033Y1556825D01*
X865283Y1556617D01*
X865700Y1556450D01*
X866075Y1556408D01*
X866450Y1556492D01*
X866700Y1556617D01*
X866950Y1556867D01*
X867117Y1557158D01*
X867200Y1557450D01*
Y1557742D01*
X867117Y1558033D01*
X866992Y1558283D01*
X866825Y1558492D01*
G01X867200Y1560550D02*
X864700D01*
X865200Y1560050D01*
G01X867200D02*
Y1561050D01*
G01X866700Y1562733D02*
X866992Y1562983D01*
X867158Y1563317D01*
X867200Y1563692D01*
X867158Y1564025D01*
X866950Y1564358D01*
X866700Y1564567D01*
X866450Y1564608D01*
X866158Y1564525D01*
X865950Y1564233D01*
X865867Y1563942D01*
Y1563567D01*
G01Y1563942D02*
X865742Y1564192D01*
X865533Y1564400D01*
X865283Y1564483D01*
X865033Y1564400D01*
X864825Y1564192D01*
X864700Y1563817D01*
X864742Y1563442D01*
X864908Y1563067D01*
G01X864700Y1566750D02*
X864783Y1566417D01*
X864992Y1566167D01*
X865242Y1566000D01*
X865575Y1565875D01*
X865950Y1565833D01*
X866325Y1565875D01*
X866658Y1566000D01*
X866908Y1566167D01*
X867117Y1566417D01*
X867200Y1566750D01*
X867117Y1567083D01*
X866908Y1567333D01*
X866658Y1567500D01*
X866325Y1567625D01*
X865950Y1567667D01*
X865575Y1567625D01*
X865242Y1567500D01*
X864992Y1567333D01*
X864783Y1567083D01*
X864700Y1566750D01*
G01X865499Y1496067D02*
X862999D01*
Y1497108D01*
X863124Y1497442D01*
X863291Y1497650D01*
X863624Y1497733D01*
X863957Y1497650D01*
X864166Y1497400D01*
X864291Y1497108D01*
Y1496067D01*
G01Y1497108D02*
X865499Y1497733D01*
G01Y1500000D02*
X862999D01*
X863499Y1499500D01*
G01X865499D02*
Y1500500D01*
G01X863416Y1502308D02*
X863166Y1502558D01*
X863041Y1502850D01*
X862999Y1503183D01*
X863082Y1503600D01*
X863291Y1503892D01*
X863541Y1503975D01*
X863791Y1503933D01*
X863999Y1503767D01*
X864416Y1502933D01*
X864707Y1502558D01*
X865124Y1502308D01*
X865499Y1502225D01*
Y1503975D01*
G01Y1506200D02*
X862999D01*
X863499Y1505700D01*
G01X865499D02*
Y1506700D01*
G01X860327Y1495096D02*
Y1508096D01*
G01X868999Y1529567D02*
X866499D01*
Y1530608D01*
X866624Y1530942D01*
X866791Y1531150D01*
X867124Y1531233D01*
X867457Y1531150D01*
X867666Y1530900D01*
X867791Y1530608D01*
Y1529567D01*
G01Y1530608D02*
X868999Y1531233D01*
G01Y1533500D02*
X866499D01*
X866999Y1533000D01*
G01X868999D02*
Y1534000D01*
G01X866916Y1535808D02*
X866666Y1536058D01*
X866541Y1536350D01*
X866499Y1536683D01*
X866582Y1537100D01*
X866791Y1537392D01*
X867041Y1537475D01*
X867291Y1537433D01*
X867499Y1537267D01*
X867916Y1536433D01*
X868207Y1536058D01*
X868624Y1535808D01*
X868999Y1535725D01*
Y1537475D01*
G01Y1540200D02*
X866499D01*
X868291Y1538658D01*
Y1540742D01*
G01X864827Y1527796D02*
Y1540796D01*
G01X850517Y1476500D02*
Y1479000D01*
X851558D01*
X851892Y1478875D01*
X852100Y1478708D01*
X852183Y1478375D01*
X852100Y1478042D01*
X851850Y1477833D01*
X851558Y1477708D01*
X850517D01*
G01X851558D02*
X852183Y1476500D01*
G01X854450D02*
Y1479000D01*
X853950Y1478500D01*
G01Y1476500D02*
X854950D01*
G01X856758Y1478583D02*
X857008Y1478833D01*
X857300Y1478958D01*
X857633Y1479000D01*
X858050Y1478917D01*
X858342Y1478708D01*
X858425Y1478458D01*
X858383Y1478208D01*
X858217Y1478000D01*
X857383Y1477583D01*
X857008Y1477292D01*
X856758Y1476875D01*
X856675Y1476500D01*
X858425D01*
G01X859733Y1477000D02*
X859983Y1476708D01*
X860317Y1476542D01*
X860692Y1476500D01*
X861025Y1476542D01*
X861358Y1476750D01*
X861567Y1477000D01*
X861608Y1477250D01*
X861525Y1477542D01*
X861233Y1477750D01*
X860942Y1477833D01*
X860567D01*
G01X860942D02*
X861192Y1477958D01*
X861400Y1478167D01*
X861483Y1478417D01*
X861400Y1478667D01*
X861192Y1478875D01*
X860817Y1479000D01*
X860442Y1478958D01*
X860067Y1478792D01*
G01X844127Y1494296D02*
Y1490296D01*
X851527D01*
G01X851500Y1486100D02*
Y1490100D01*
X844100D01*
G01X865000Y1481517D02*
X862500D01*
Y1482558D01*
X862625Y1482892D01*
X862792Y1483100D01*
X863125Y1483183D01*
X863458Y1483100D01*
X863667Y1482850D01*
X863792Y1482558D01*
Y1481517D01*
G01Y1482558D02*
X865000Y1483183D01*
G01Y1485450D02*
X862500D01*
X863000Y1484950D01*
G01X865000D02*
Y1485950D01*
G01X862917Y1487758D02*
X862667Y1488008D01*
X862542Y1488300D01*
X862500Y1488633D01*
X862583Y1489050D01*
X862792Y1489342D01*
X863042Y1489425D01*
X863292Y1489383D01*
X863500Y1489217D01*
X863917Y1488383D01*
X864208Y1488008D01*
X864625Y1487758D01*
X865000Y1487675D01*
Y1489425D01*
G01X864625Y1490733D02*
X864833Y1490983D01*
X864958Y1491275D01*
X865000Y1491650D01*
X864917Y1492025D01*
X864750Y1492317D01*
X864458Y1492525D01*
X864125Y1492567D01*
X863792Y1492483D01*
X863583Y1492275D01*
X863417Y1491983D01*
X863375Y1491692D01*
X863417Y1491400D01*
X863583Y1491025D01*
X862500Y1491150D01*
Y1492275D01*
G01X845500Y1547500D02*
Y1542000D01*
G01Y1559600D02*
Y1554100D01*
G01X846200Y1542000D02*
Y1547500D01*
G01X854200Y1542000D02*
X846200D01*
G01X854200Y1547500D02*
Y1542000D01*
G01Y1559600D02*
Y1554100D01*
G01X846200D02*
Y1559600D01*
G01X854900Y1542000D02*
Y1547500D01*
G01X862900Y1542000D02*
X854900D01*
G01X862900Y1547500D02*
Y1542000D01*
G01Y1559600D02*
Y1554100D01*
G01X854900D02*
Y1559600D01*
G01X862708Y1515267D02*
X862583Y1515017D01*
X862500Y1514725D01*
Y1514392D01*
X862625Y1514017D01*
X862833Y1513725D01*
X863083Y1513517D01*
X863500Y1513350D01*
X863875Y1513308D01*
X864250Y1513392D01*
X864500Y1513517D01*
X864750Y1513767D01*
X864917Y1514058D01*
X865000Y1514350D01*
Y1514642D01*
X864917Y1514933D01*
X864792Y1515183D01*
X864625Y1515392D01*
G01X865000Y1517450D02*
X862500D01*
X863000Y1516950D01*
G01X865000D02*
Y1517950D01*
G01X862917Y1519758D02*
X862667Y1520008D01*
X862542Y1520300D01*
X862500Y1520633D01*
X862583Y1521050D01*
X862792Y1521342D01*
X863042Y1521425D01*
X863292Y1521383D01*
X863500Y1521217D01*
X863917Y1520383D01*
X864208Y1520008D01*
X864625Y1519758D01*
X865000Y1519675D01*
Y1521425D01*
G01X864500Y1522733D02*
X864792Y1522983D01*
X864958Y1523317D01*
X865000Y1523692D01*
X864958Y1524025D01*
X864750Y1524358D01*
X864500Y1524567D01*
X864250Y1524608D01*
X863958Y1524525D01*
X863750Y1524233D01*
X863667Y1523942D01*
Y1523567D01*
G01Y1523942D02*
X863542Y1524192D01*
X863333Y1524400D01*
X863083Y1524483D01*
X862833Y1524400D01*
X862625Y1524192D01*
X862500Y1523817D01*
X862542Y1523442D01*
X862708Y1523067D01*
G01X846827Y1508996D02*
Y1514496D01*
G01X854827Y1508996D02*
X846827D01*
G01X854827Y1514496D02*
Y1508996D01*
G01Y1526596D02*
Y1521096D01*
G01X846827Y1526596D02*
X854827D01*
G01X846827Y1521096D02*
Y1526596D01*
G01X843400Y1475800D02*
Y1489800D01*
G01X848908Y1563467D02*
X848783Y1563217D01*
X848700Y1562925D01*
Y1562592D01*
X848825Y1562217D01*
X849033Y1561925D01*
X849283Y1561717D01*
X849700Y1561550D01*
X850075Y1561508D01*
X850450Y1561592D01*
X850700Y1561717D01*
X850950Y1561967D01*
X851117Y1562258D01*
X851200Y1562550D01*
Y1562842D01*
X851117Y1563133D01*
X850992Y1563383D01*
X850825Y1563592D01*
G01X851200Y1565650D02*
X848700D01*
X849200Y1565150D01*
G01X851200D02*
Y1566150D01*
G01X849117Y1567958D02*
X848867Y1568208D01*
X848742Y1568500D01*
X848700Y1568833D01*
X848783Y1569250D01*
X848992Y1569542D01*
X849242Y1569625D01*
X849492Y1569583D01*
X849700Y1569417D01*
X850117Y1568583D01*
X850408Y1568208D01*
X850825Y1567958D01*
X851200Y1567875D01*
Y1569625D01*
G01Y1571850D02*
X851158Y1572142D01*
X851033Y1572475D01*
X850825Y1572683D01*
X850533Y1572767D01*
X850242Y1572683D01*
X849992Y1572433D01*
X849867Y1572058D01*
Y1571642D01*
X849783Y1571392D01*
X849575Y1571183D01*
X849283Y1571100D01*
X848992Y1571225D01*
X848783Y1571517D01*
X848700Y1571850D01*
X848783Y1572183D01*
X848992Y1572475D01*
X849283Y1572600D01*
X849575Y1572517D01*
X849783Y1572308D01*
X849867Y1572058D01*
Y1571642D01*
X849992Y1571267D01*
X850242Y1571017D01*
X850533Y1570933D01*
X850825Y1571017D01*
X851033Y1571225D01*
X851158Y1571558D01*
X851200Y1571850D01*
G01X846200Y1559600D02*
X854200D01*
G01X857608Y1563467D02*
X857483Y1563217D01*
X857400Y1562925D01*
Y1562592D01*
X857525Y1562217D01*
X857733Y1561925D01*
X857983Y1561717D01*
X858400Y1561550D01*
X858775Y1561508D01*
X859150Y1561592D01*
X859400Y1561717D01*
X859650Y1561967D01*
X859817Y1562258D01*
X859900Y1562550D01*
Y1562842D01*
X859817Y1563133D01*
X859692Y1563383D01*
X859525Y1563592D01*
G01X859900Y1565650D02*
X857400D01*
X857900Y1565150D01*
G01X859900D02*
Y1566150D01*
G01X857817Y1567958D02*
X857567Y1568208D01*
X857442Y1568500D01*
X857400Y1568833D01*
X857483Y1569250D01*
X857692Y1569542D01*
X857942Y1569625D01*
X858192Y1569583D01*
X858400Y1569417D01*
X858817Y1568583D01*
X859108Y1568208D01*
X859525Y1567958D01*
X859900Y1567875D01*
Y1569625D01*
G01X859608Y1571142D02*
X859817Y1571433D01*
X859900Y1571767D01*
X859817Y1572100D01*
X859567Y1572392D01*
X859192Y1572600D01*
X858817Y1572683D01*
X858358D01*
X857983Y1572600D01*
X857650Y1572392D01*
X857483Y1572142D01*
X857400Y1571850D01*
X857483Y1571517D01*
X857650Y1571267D01*
X857900Y1571100D01*
X858233Y1571017D01*
X858525Y1571100D01*
X858817Y1571308D01*
X858983Y1571558D01*
X859025Y1571850D01*
X858942Y1572183D01*
X858733Y1572433D01*
X858358Y1572683D01*
G01X854900Y1559600D02*
X862900D01*
G01X899983Y1721000D02*
Y1723500D01*
X900817D01*
X901150Y1723375D01*
X901400Y1723208D01*
X901608Y1722958D01*
X901775Y1722667D01*
X901817Y1722250D01*
X901775Y1721833D01*
X901608Y1721542D01*
X901400Y1721292D01*
X901150Y1721125D01*
X900817Y1721000D01*
X899983D01*
G01X904000D02*
Y1723500D01*
X903500Y1723000D01*
G01Y1721000D02*
X904500D01*
G01X907600D02*
Y1723500D01*
X906058Y1721708D01*
X908142D01*
G01X886500Y1723600D02*
X874500D01*
Y1719400D01*
X886500D01*
G01Y1723600D02*
Y1719400D01*
G01X870000Y1693517D02*
X867500D01*
Y1694517D01*
X867625Y1694850D01*
X867917Y1695100D01*
X868250Y1695183D01*
X868583Y1695100D01*
X868833Y1694892D01*
X868958Y1694517D01*
Y1693517D01*
G01X867708Y1698367D02*
X867583Y1698117D01*
X867500Y1697825D01*
Y1697492D01*
X867625Y1697117D01*
X867833Y1696825D01*
X868083Y1696617D01*
X868500Y1696450D01*
X868875Y1696408D01*
X869250Y1696492D01*
X869500Y1696617D01*
X869750Y1696867D01*
X869917Y1697158D01*
X870000Y1697450D01*
Y1697742D01*
X869917Y1698033D01*
X869792Y1698283D01*
X869625Y1698492D01*
G01X870000Y1701050D02*
X867500D01*
X869292Y1699508D01*
Y1701592D01*
G01X870000Y1703650D02*
X867500D01*
X868000Y1703150D01*
G01X870000D02*
Y1704150D01*
G01X911017Y1721000D02*
Y1723500D01*
X912017D01*
X912350Y1723375D01*
X912600Y1723083D01*
X912683Y1722750D01*
X912600Y1722417D01*
X912392Y1722167D01*
X912017Y1722042D01*
X911017D01*
G01X915867Y1723292D02*
X915617Y1723417D01*
X915325Y1723500D01*
X914992D01*
X914617Y1723375D01*
X914325Y1723167D01*
X914117Y1722917D01*
X913950Y1722500D01*
X913908Y1722125D01*
X913992Y1721750D01*
X914117Y1721500D01*
X914367Y1721250D01*
X914658Y1721083D01*
X914950Y1721000D01*
X915242D01*
X915533Y1721083D01*
X915783Y1721208D01*
X915992Y1721375D01*
G01X918550Y1721000D02*
Y1723500D01*
X917008Y1721708D01*
X919092D01*
G01X921650Y1721000D02*
Y1723500D01*
X920108Y1721708D01*
X922192D01*
G01X906500Y1694517D02*
X904000D01*
Y1695517D01*
X904125Y1695850D01*
X904417Y1696100D01*
X904750Y1696183D01*
X905083Y1696100D01*
X905333Y1695892D01*
X905458Y1695517D01*
Y1694517D01*
G01X904208Y1699367D02*
X904083Y1699117D01*
X904000Y1698825D01*
Y1698492D01*
X904125Y1698117D01*
X904333Y1697825D01*
X904583Y1697617D01*
X905000Y1697450D01*
X905375Y1697408D01*
X905750Y1697492D01*
X906000Y1697617D01*
X906250Y1697867D01*
X906417Y1698158D01*
X906500Y1698450D01*
Y1698742D01*
X906417Y1699033D01*
X906292Y1699283D01*
X906125Y1699492D01*
G01X906500Y1702050D02*
X904000D01*
X905792Y1700508D01*
Y1702592D01*
G01X904417Y1703858D02*
X904167Y1704108D01*
X904042Y1704400D01*
X904000Y1704733D01*
X904083Y1705150D01*
X904292Y1705442D01*
X904542Y1705525D01*
X904792Y1705483D01*
X905000Y1705317D01*
X905417Y1704483D01*
X905708Y1704108D01*
X906125Y1703858D01*
X906500Y1703775D01*
Y1705525D01*
G01X902000Y1694517D02*
X899500D01*
Y1695517D01*
X899625Y1695850D01*
X899917Y1696100D01*
X900250Y1696183D01*
X900583Y1696100D01*
X900833Y1695892D01*
X900958Y1695517D01*
Y1694517D01*
G01X902000Y1697617D02*
X899500D01*
Y1698658D01*
X899625Y1698992D01*
X899792Y1699200D01*
X900125Y1699283D01*
X900458Y1699200D01*
X900667Y1698950D01*
X900792Y1698658D01*
Y1697617D01*
G01Y1698658D02*
X902000Y1699283D01*
G01X901625Y1700633D02*
X901833Y1700883D01*
X901958Y1701175D01*
X902000Y1701550D01*
X901917Y1701925D01*
X901750Y1702217D01*
X901458Y1702425D01*
X901125Y1702467D01*
X900792Y1702383D01*
X900583Y1702175D01*
X900417Y1701883D01*
X900375Y1701592D01*
X900417Y1701300D01*
X900583Y1700925D01*
X899500Y1701050D01*
Y1702175D01*
G01X901625Y1703733D02*
X901833Y1703983D01*
X901958Y1704275D01*
X902000Y1704650D01*
X901917Y1705025D01*
X901750Y1705317D01*
X901458Y1705525D01*
X901125Y1705567D01*
X900792Y1705483D01*
X900583Y1705275D01*
X900417Y1704983D01*
X900375Y1704692D01*
X900417Y1704400D01*
X900583Y1704025D01*
X899500Y1704150D01*
Y1705275D01*
G01X891700Y1710100D02*
X887700D01*
Y1702700D01*
G01X906517Y1715500D02*
Y1718000D01*
X907517D01*
X907850Y1717875D01*
X908100Y1717583D01*
X908183Y1717250D01*
X908100Y1716917D01*
X907892Y1716667D01*
X907517Y1716542D01*
X906517D01*
G01X909617Y1715500D02*
Y1718000D01*
X910658D01*
X910992Y1717875D01*
X911200Y1717708D01*
X911283Y1717375D01*
X911200Y1717042D01*
X910950Y1716833D01*
X910658Y1716708D01*
X909617D01*
G01X910658D02*
X911283Y1715500D01*
G01X912633Y1715875D02*
X912883Y1715667D01*
X913175Y1715542D01*
X913550Y1715500D01*
X913925Y1715583D01*
X914217Y1715750D01*
X914425Y1716042D01*
X914467Y1716375D01*
X914383Y1716708D01*
X914175Y1716917D01*
X913883Y1717083D01*
X913592Y1717125D01*
X913300Y1717083D01*
X912925Y1716917D01*
X913050Y1718000D01*
X914175D01*
G01X917150Y1715500D02*
Y1718000D01*
X915608Y1716208D01*
X917692D01*
G01X877017Y1684000D02*
Y1686500D01*
X878017D01*
X878350Y1686375D01*
X878600Y1686083D01*
X878683Y1685750D01*
X878600Y1685417D01*
X878392Y1685167D01*
X878017Y1685042D01*
X877017D01*
G01X880117Y1684000D02*
Y1686500D01*
X881158D01*
X881492Y1686375D01*
X881700Y1686208D01*
X881783Y1685875D01*
X881700Y1685542D01*
X881450Y1685333D01*
X881158Y1685208D01*
X880117D01*
G01X881158D02*
X881783Y1684000D01*
G01X883133Y1684375D02*
X883383Y1684167D01*
X883675Y1684042D01*
X884050Y1684000D01*
X884425Y1684083D01*
X884717Y1684250D01*
X884925Y1684542D01*
X884967Y1684875D01*
X884883Y1685208D01*
X884675Y1685417D01*
X884383Y1685583D01*
X884092Y1685625D01*
X883800Y1685583D01*
X883425Y1685417D01*
X883550Y1686500D01*
X884675D01*
G01X886358Y1685042D02*
X886650Y1685333D01*
X886900Y1685500D01*
X887233Y1685583D01*
X887525Y1685500D01*
X887733Y1685333D01*
X887900Y1685083D01*
X887942Y1684792D01*
X887900Y1684542D01*
X887733Y1684292D01*
X887483Y1684083D01*
X887192Y1684000D01*
X886858Y1684083D01*
X886567Y1684333D01*
X886400Y1684708D01*
X886358Y1685125D01*
X886442Y1685667D01*
X886567Y1685958D01*
X886775Y1686250D01*
X887067Y1686458D01*
X887358Y1686500D01*
X887650Y1686417D01*
X887858Y1686208D01*
G01X876983Y1690500D02*
Y1688708D01*
X877150Y1688333D01*
X877483Y1688083D01*
X877900Y1688000D01*
X878317Y1688083D01*
X878650Y1688333D01*
X878817Y1688708D01*
Y1690500D01*
G01X880083Y1688375D02*
X880333Y1688167D01*
X880625Y1688042D01*
X881000Y1688000D01*
X881375Y1688083D01*
X881667Y1688250D01*
X881875Y1688542D01*
X881917Y1688875D01*
X881833Y1689208D01*
X881625Y1689417D01*
X881333Y1689583D01*
X881042Y1689625D01*
X880750Y1689583D01*
X880375Y1689417D01*
X880500Y1690500D01*
X881625D01*
G01X884600Y1688000D02*
Y1690500D01*
X883058Y1688708D01*
X885142D01*
G01X873600Y1709199D02*
X872000Y1707599D01*
G01Y1710799D02*
X873600Y1709199D01*
G01X872000Y1711499D02*
Y1706899D01*
G01X886500Y1711499D02*
X872000D01*
G01X886500Y1706899D02*
Y1711499D01*
G01X872000Y1706899D02*
X886500D01*
G01X851067Y1699500D02*
Y1702000D01*
X852067D01*
X852400Y1701875D01*
X852650Y1701583D01*
X852733Y1701250D01*
X852650Y1700917D01*
X852442Y1700667D01*
X852067Y1700542D01*
X851067D01*
G01X854167Y1702000D02*
Y1699500D01*
X855833D01*
G01X858017D02*
X858100Y1700042D01*
X858225Y1700500D01*
X858392Y1700917D01*
X858600Y1701375D01*
X858933Y1702000D01*
X857267D01*
G01X860665Y1737100D02*
X867301Y1730464D01*
Y1713036D01*
X860665Y1706400D01*
X847537D01*
X840901Y1713036D01*
Y1730464D01*
X847537Y1737100D01*
X860665D01*
G01X862500Y1749000D02*
Y1759000D01*
G01X869500D02*
Y1749000D01*
G01Y1754000D02*
X862500D01*
G01X872933Y1749000D02*
Y1759000D01*
X876267D01*
X877600Y1758500D01*
X878600Y1757833D01*
X879433Y1756833D01*
X880100Y1755666D01*
X880267Y1754000D01*
X880100Y1752333D01*
X879433Y1751167D01*
X878600Y1750166D01*
X877600Y1749500D01*
X876267Y1749000D01*
X872933D01*
G01X883533D02*
Y1759000D01*
X886867D01*
X888200Y1758500D01*
X889200Y1757833D01*
X890033Y1756833D01*
X890700Y1755666D01*
X890867Y1754000D01*
X890700Y1752333D01*
X890033Y1751167D01*
X889200Y1750166D01*
X888200Y1749500D01*
X886867Y1749000D01*
X883533D01*
G01X897800Y1759000D02*
X896466Y1758667D01*
X895467Y1757833D01*
X894800Y1756833D01*
X894300Y1755500D01*
X894133Y1754000D01*
X894300Y1752500D01*
X894800Y1751167D01*
X895467Y1750166D01*
X896466Y1749333D01*
X897800Y1749000D01*
X899133Y1749333D01*
X900133Y1750166D01*
X900800Y1751167D01*
X901300Y1752500D01*
X901467Y1754000D01*
X901300Y1755500D01*
X900800Y1756833D01*
X900133Y1757833D01*
X899133Y1758667D01*
X897800Y1759000D01*
G01X903400Y1745667D02*
X913400D01*
G01X915667Y1759000D02*
Y1749000D01*
X922333D01*
G01X932933D02*
X926267D01*
Y1759000D01*
X932933D01*
G01X930267Y1754167D02*
X926267D01*
G01X936533Y1749000D02*
Y1759000D01*
X939867D01*
X941200Y1758500D01*
X942200Y1757833D01*
X943033Y1756833D01*
X943700Y1755666D01*
X943867Y1754000D01*
X943700Y1752333D01*
X943033Y1751167D01*
X942200Y1750166D01*
X941200Y1749500D01*
X939867Y1749000D01*
X936533D01*
G01X902017Y1736500D02*
Y1739000D01*
X903017D01*
X903350Y1738875D01*
X903600Y1738583D01*
X903683Y1738250D01*
X903600Y1737917D01*
X903392Y1737667D01*
X903017Y1737542D01*
X902017D01*
G01X905117Y1736500D02*
Y1739000D01*
X906158D01*
X906492Y1738875D01*
X906700Y1738708D01*
X906783Y1738375D01*
X906700Y1738042D01*
X906450Y1737833D01*
X906158Y1737708D01*
X905117D01*
G01X906158D02*
X906783Y1736500D01*
G01X908258Y1737542D02*
X908550Y1737833D01*
X908800Y1738000D01*
X909133Y1738083D01*
X909425Y1738000D01*
X909633Y1737833D01*
X909800Y1737583D01*
X909842Y1737292D01*
X909800Y1737042D01*
X909633Y1736792D01*
X909383Y1736583D01*
X909092Y1736500D01*
X908758Y1736583D01*
X908467Y1736833D01*
X908300Y1737208D01*
X908258Y1737625D01*
X908342Y1738167D01*
X908467Y1738458D01*
X908675Y1738750D01*
X908967Y1738958D01*
X909258Y1739000D01*
X909550Y1738917D01*
X909758Y1738708D01*
G01X911233Y1737000D02*
X911483Y1736708D01*
X911817Y1736542D01*
X912192Y1736500D01*
X912525Y1736542D01*
X912858Y1736750D01*
X913067Y1737000D01*
X913108Y1737250D01*
X913025Y1737542D01*
X912733Y1737750D01*
X912442Y1737833D01*
X912067D01*
G01X912442D02*
X912692Y1737958D01*
X912900Y1738167D01*
X912983Y1738417D01*
X912900Y1738667D01*
X912692Y1738875D01*
X912317Y1739000D01*
X911942Y1738958D01*
X911567Y1738792D01*
G01X844266Y1793342D02*
X844016Y1793467D01*
X843724Y1793550D01*
X843391D01*
X843016Y1793425D01*
X842724Y1793217D01*
X842516Y1792967D01*
X842349Y1792550D01*
X842307Y1792175D01*
X842391Y1791800D01*
X842516Y1791550D01*
X842766Y1791300D01*
X843057Y1791133D01*
X843349Y1791050D01*
X843641D01*
X843932Y1791133D01*
X844182Y1791258D01*
X844391Y1791425D01*
G01X845532Y1791550D02*
X845782Y1791258D01*
X846116Y1791092D01*
X846491Y1791050D01*
X846824Y1791092D01*
X847157Y1791300D01*
X847366Y1791550D01*
X847407Y1791800D01*
X847324Y1792092D01*
X847032Y1792300D01*
X846741Y1792383D01*
X846366D01*
G01X846741D02*
X846991Y1792508D01*
X847199Y1792717D01*
X847282Y1792967D01*
X847199Y1793217D01*
X846991Y1793425D01*
X846616Y1793550D01*
X846241Y1793508D01*
X845866Y1793342D01*
G01X850049Y1791050D02*
Y1793550D01*
X848507Y1791758D01*
X850591D01*
G01X851857Y1793133D02*
X852107Y1793383D01*
X852399Y1793508D01*
X852732Y1793550D01*
X853149Y1793467D01*
X853441Y1793258D01*
X853524Y1793008D01*
X853482Y1792758D01*
X853316Y1792550D01*
X852482Y1792133D01*
X852107Y1791842D01*
X851857Y1791425D01*
X851774Y1791050D01*
X853524D01*
G01X889517Y1769063D02*
Y1766563D01*
X891183D01*
G01X894283D02*
X892617D01*
Y1769063D01*
X894283D01*
G01X893617Y1767855D02*
X892617D01*
G01X895633Y1766563D02*
Y1769063D01*
X896467D01*
X896800Y1768938D01*
X897050Y1768771D01*
X897258Y1768521D01*
X897425Y1768230D01*
X897467Y1767813D01*
X897425Y1767396D01*
X897258Y1767105D01*
X897050Y1766855D01*
X896800Y1766688D01*
X896467Y1766563D01*
X895633D01*
G01X899650D02*
Y1769063D01*
X899150Y1768563D01*
G01Y1766563D02*
X900150D01*
G01X901369Y1787894D02*
Y1780294D01*
X889969D01*
Y1787894D01*
X901369D01*
G01X908581Y1802713D02*
Y1805213D01*
X909622D01*
X909956Y1805088D01*
X910164Y1804921D01*
X910247Y1804588D01*
X910164Y1804255D01*
X909914Y1804046D01*
X909622Y1803921D01*
X908581D01*
G01X909622D02*
X910247Y1802713D01*
G01X912514D02*
Y1805213D01*
X912014Y1804713D01*
G01Y1802713D02*
X913014D01*
G01X915614Y1805213D02*
X915281Y1805130D01*
X915031Y1804921D01*
X914864Y1804671D01*
X914739Y1804338D01*
X914697Y1803963D01*
X914739Y1803588D01*
X914864Y1803255D01*
X915031Y1803005D01*
X915281Y1802796D01*
X915614Y1802713D01*
X915947Y1802796D01*
X916197Y1803005D01*
X916364Y1803255D01*
X916489Y1803588D01*
X916531Y1803963D01*
X916489Y1804338D01*
X916364Y1804671D01*
X916197Y1804921D01*
X915947Y1805130D01*
X915614Y1805213D01*
G01X918714Y1802713D02*
Y1805213D01*
X918214Y1804713D01*
G01Y1802713D02*
X919214D01*
G01X902864Y1787613D02*
Y1783613D01*
X910264D01*
G01X868117Y1784800D02*
Y1787300D01*
X869158D01*
X869492Y1787175D01*
X869700Y1787008D01*
X869783Y1786675D01*
X869700Y1786342D01*
X869450Y1786133D01*
X869158Y1786008D01*
X868117D01*
G01X869158D02*
X869783Y1784800D01*
G01X872050D02*
Y1787300D01*
X871550Y1786800D01*
G01Y1784800D02*
X872550D01*
G01X875150Y1787300D02*
X874817Y1787217D01*
X874567Y1787008D01*
X874400Y1786758D01*
X874275Y1786425D01*
X874233Y1786050D01*
X874275Y1785675D01*
X874400Y1785342D01*
X874567Y1785092D01*
X874817Y1784883D01*
X875150Y1784800D01*
X875483Y1784883D01*
X875733Y1785092D01*
X875900Y1785342D01*
X876025Y1785675D01*
X876067Y1786050D01*
X876025Y1786425D01*
X875900Y1786758D01*
X875733Y1787008D01*
X875483Y1787217D01*
X875150Y1787300D01*
G01X877458Y1786883D02*
X877708Y1787133D01*
X878000Y1787258D01*
X878333Y1787300D01*
X878750Y1787217D01*
X879042Y1787008D01*
X879125Y1786758D01*
X879083Y1786508D01*
X878917Y1786300D01*
X878083Y1785883D01*
X877708Y1785592D01*
X877458Y1785175D01*
X877375Y1784800D01*
X879125D01*
G01X880900Y1788300D02*
Y1784300D01*
X888300D01*
G01X908581Y1798713D02*
Y1801213D01*
X909622D01*
X909956Y1801088D01*
X910164Y1800921D01*
X910247Y1800588D01*
X910164Y1800255D01*
X909914Y1800046D01*
X909622Y1799921D01*
X908581D01*
G01X909622D02*
X910247Y1798713D01*
G01X912514D02*
Y1801213D01*
X912014Y1800713D01*
G01Y1798713D02*
X913014D01*
G01X915614Y1801213D02*
X915281Y1801130D01*
X915031Y1800921D01*
X914864Y1800671D01*
X914739Y1800338D01*
X914697Y1799963D01*
X914739Y1799588D01*
X914864Y1799255D01*
X915031Y1799005D01*
X915281Y1798796D01*
X915614Y1798713D01*
X915947Y1798796D01*
X916197Y1799005D01*
X916364Y1799255D01*
X916489Y1799588D01*
X916531Y1799963D01*
X916489Y1800338D01*
X916364Y1800671D01*
X916197Y1800921D01*
X915947Y1801130D01*
X915614Y1801213D01*
G01X917797Y1799213D02*
X918047Y1798921D01*
X918381Y1798755D01*
X918756Y1798713D01*
X919089Y1798755D01*
X919422Y1798963D01*
X919631Y1799213D01*
X919672Y1799463D01*
X919589Y1799755D01*
X919297Y1799963D01*
X919006Y1800046D01*
X918631D01*
G01X919006D02*
X919256Y1800171D01*
X919464Y1800380D01*
X919547Y1800630D01*
X919464Y1800880D01*
X919256Y1801088D01*
X918881Y1801213D01*
X918506Y1801171D01*
X918131Y1801005D01*
G01X902864Y1783613D02*
Y1779613D01*
X910264D01*
G01X868081Y1780713D02*
Y1783213D01*
X869122D01*
X869456Y1783088D01*
X869664Y1782921D01*
X869747Y1782588D01*
X869664Y1782255D01*
X869414Y1782046D01*
X869122Y1781921D01*
X868081D01*
G01X869122D02*
X869747Y1780713D01*
G01X872014D02*
Y1783213D01*
X871514Y1782713D01*
G01Y1780713D02*
X872514D01*
G01X875114Y1783213D02*
X874781Y1783130D01*
X874531Y1782921D01*
X874364Y1782671D01*
X874239Y1782338D01*
X874197Y1781963D01*
X874239Y1781588D01*
X874364Y1781255D01*
X874531Y1781005D01*
X874781Y1780796D01*
X875114Y1780713D01*
X875447Y1780796D01*
X875697Y1781005D01*
X875864Y1781255D01*
X875989Y1781588D01*
X876031Y1781963D01*
X875989Y1782338D01*
X875864Y1782671D01*
X875697Y1782921D01*
X875447Y1783130D01*
X875114Y1783213D01*
G01X878714Y1780713D02*
Y1783213D01*
X877172Y1781421D01*
X879256D01*
G01X880864Y1784213D02*
Y1780213D01*
X888264D01*
G01X908581Y1794713D02*
Y1797213D01*
X909622D01*
X909956Y1797088D01*
X910164Y1796921D01*
X910247Y1796588D01*
X910164Y1796255D01*
X909914Y1796046D01*
X909622Y1795921D01*
X908581D01*
G01X909622D02*
X910247Y1794713D01*
G01X912514D02*
Y1797213D01*
X912014Y1796713D01*
G01Y1794713D02*
X913014D01*
G01X915614Y1797213D02*
X915281Y1797130D01*
X915031Y1796921D01*
X914864Y1796671D01*
X914739Y1796338D01*
X914697Y1795963D01*
X914739Y1795588D01*
X914864Y1795255D01*
X915031Y1795005D01*
X915281Y1794796D01*
X915614Y1794713D01*
X915947Y1794796D01*
X916197Y1795005D01*
X916364Y1795255D01*
X916489Y1795588D01*
X916531Y1795963D01*
X916489Y1796338D01*
X916364Y1796671D01*
X916197Y1796921D01*
X915947Y1797130D01*
X915614Y1797213D01*
G01X917797Y1795088D02*
X918047Y1794880D01*
X918339Y1794755D01*
X918714Y1794713D01*
X919089Y1794796D01*
X919381Y1794963D01*
X919589Y1795255D01*
X919631Y1795588D01*
X919547Y1795921D01*
X919339Y1796130D01*
X919047Y1796296D01*
X918756Y1796338D01*
X918464Y1796296D01*
X918089Y1796130D01*
X918214Y1797213D01*
X919339D01*
G01X902864Y1779613D02*
Y1775613D01*
X910264D01*
G01X895017Y1726500D02*
Y1729000D01*
X896017D01*
X896350Y1728875D01*
X896600Y1728583D01*
X896683Y1728250D01*
X896600Y1727917D01*
X896392Y1727667D01*
X896017Y1727542D01*
X895017D01*
G01X898117Y1726500D02*
Y1729000D01*
X899158D01*
X899492Y1728875D01*
X899700Y1728708D01*
X899783Y1728375D01*
X899700Y1728042D01*
X899450Y1727833D01*
X899158Y1727708D01*
X898117D01*
G01X899158D02*
X899783Y1726500D01*
G01X901133Y1726875D02*
X901383Y1726667D01*
X901675Y1726542D01*
X902050Y1726500D01*
X902425Y1726583D01*
X902717Y1726750D01*
X902925Y1727042D01*
X902967Y1727375D01*
X902883Y1727708D01*
X902675Y1727917D01*
X902383Y1728083D01*
X902092Y1728125D01*
X901800Y1728083D01*
X901425Y1727917D01*
X901550Y1729000D01*
X902675D01*
G01X904358Y1728583D02*
X904608Y1728833D01*
X904900Y1728958D01*
X905233Y1729000D01*
X905650Y1728917D01*
X905942Y1728708D01*
X906025Y1728458D01*
X905983Y1728208D01*
X905817Y1728000D01*
X904983Y1727583D01*
X904608Y1727292D01*
X904358Y1726875D01*
X904275Y1726500D01*
X906025D01*
G01X875901Y1729450D02*
Y1725450D01*
X883301D01*
G01X909017Y1726500D02*
Y1729000D01*
X910017D01*
X910350Y1728875D01*
X910600Y1728583D01*
X910683Y1728250D01*
X910600Y1727917D01*
X910392Y1727667D01*
X910017Y1727542D01*
X909017D01*
G01X912117Y1726500D02*
Y1729000D01*
X913158D01*
X913492Y1728875D01*
X913700Y1728708D01*
X913783Y1728375D01*
X913700Y1728042D01*
X913450Y1727833D01*
X913158Y1727708D01*
X912117D01*
G01X913158D02*
X913783Y1726500D01*
G01X915133Y1726875D02*
X915383Y1726667D01*
X915675Y1726542D01*
X916050Y1726500D01*
X916425Y1726583D01*
X916717Y1726750D01*
X916925Y1727042D01*
X916967Y1727375D01*
X916883Y1727708D01*
X916675Y1727917D01*
X916383Y1728083D01*
X916092Y1728125D01*
X915800Y1728083D01*
X915425Y1727917D01*
X915550Y1729000D01*
X916675D01*
G01X918233Y1727000D02*
X918483Y1726708D01*
X918817Y1726542D01*
X919192Y1726500D01*
X919525Y1726542D01*
X919858Y1726750D01*
X920067Y1727000D01*
X920108Y1727250D01*
X920025Y1727542D01*
X919733Y1727750D01*
X919442Y1727833D01*
X919067D01*
G01X919442D02*
X919692Y1727958D01*
X919900Y1728167D01*
X919983Y1728417D01*
X919900Y1728667D01*
X919692Y1728875D01*
X919317Y1729000D01*
X918942Y1728958D01*
X918567Y1728792D01*
G01X883401Y1729450D02*
Y1725450D01*
X890801D01*
G01X908217Y1764100D02*
Y1766600D01*
X909258D01*
X909592Y1766475D01*
X909800Y1766308D01*
X909883Y1765975D01*
X909800Y1765642D01*
X909550Y1765433D01*
X909258Y1765308D01*
X908217D01*
G01X909258D02*
X909883Y1764100D01*
G01X912650D02*
Y1766600D01*
X911108Y1764808D01*
X913192D01*
G01X915250Y1764100D02*
X915542Y1764142D01*
X915875Y1764267D01*
X916083Y1764475D01*
X916167Y1764767D01*
X916083Y1765058D01*
X915833Y1765308D01*
X915458Y1765433D01*
X915042D01*
X914792Y1765517D01*
X914583Y1765725D01*
X914500Y1766017D01*
X914625Y1766308D01*
X914917Y1766517D01*
X915250Y1766600D01*
X915583Y1766517D01*
X915875Y1766308D01*
X916000Y1766017D01*
X915917Y1765725D01*
X915708Y1765517D01*
X915458Y1765433D01*
X915042D01*
X914667Y1765308D01*
X914417Y1765058D01*
X914333Y1764767D01*
X914417Y1764475D01*
X914625Y1764267D01*
X914958Y1764142D01*
X915250Y1764100D01*
G01X918350D02*
X918642Y1764142D01*
X918975Y1764267D01*
X919183Y1764475D01*
X919267Y1764767D01*
X919183Y1765058D01*
X918933Y1765308D01*
X918558Y1765433D01*
X918142D01*
X917892Y1765517D01*
X917683Y1765725D01*
X917600Y1766017D01*
X917725Y1766308D01*
X918017Y1766517D01*
X918350Y1766600D01*
X918683Y1766517D01*
X918975Y1766308D01*
X919100Y1766017D01*
X919017Y1765725D01*
X918808Y1765517D01*
X918558Y1765433D01*
X918142D01*
X917767Y1765308D01*
X917517Y1765058D01*
X917433Y1764767D01*
X917517Y1764475D01*
X917725Y1764267D01*
X918058Y1764142D01*
X918350Y1764100D01*
G01X918099Y1769700D02*
Y1773700D01*
X910699D01*
G01X902017Y1732500D02*
Y1735000D01*
X903017D01*
X903350Y1734875D01*
X903600Y1734583D01*
X903683Y1734250D01*
X903600Y1733917D01*
X903392Y1733667D01*
X903017Y1733542D01*
X902017D01*
G01X906867Y1734792D02*
X906617Y1734917D01*
X906325Y1735000D01*
X905992D01*
X905617Y1734875D01*
X905325Y1734667D01*
X905117Y1734417D01*
X904950Y1734000D01*
X904908Y1733625D01*
X904992Y1733250D01*
X905117Y1733000D01*
X905367Y1732750D01*
X905658Y1732583D01*
X905950Y1732500D01*
X906242D01*
X906533Y1732583D01*
X906783Y1732708D01*
X906992Y1732875D01*
G01X909550Y1732500D02*
Y1735000D01*
X908008Y1733208D01*
X910092D01*
G01X912150Y1735000D02*
X911817Y1734917D01*
X911567Y1734708D01*
X911400Y1734458D01*
X911275Y1734125D01*
X911233Y1733750D01*
X911275Y1733375D01*
X911400Y1733042D01*
X911567Y1732792D01*
X911817Y1732583D01*
X912150Y1732500D01*
X912483Y1732583D01*
X912733Y1732792D01*
X912900Y1733042D01*
X913025Y1733375D01*
X913067Y1733750D01*
X913025Y1734125D01*
X912900Y1734458D01*
X912733Y1734708D01*
X912483Y1734917D01*
X912150Y1735000D01*
G01X885500Y1737800D02*
X891000D01*
Y1729800D01*
X885400D01*
G01X873400Y1737800D02*
X878900D01*
G01X873400D02*
Y1729800D01*
X878900D01*
G01X910799Y1774500D02*
X924799D01*
G01X910799Y1787500D02*
Y1774500D01*
G01X924799Y1787500D02*
X910799D01*
G01X872969Y1807865D02*
Y1969065D01*
X886569D01*
Y1982015D01*
X904769D01*
Y1969065D01*
X933669D01*
Y1958715D01*
X926969D01*
Y1818215D01*
X933669D01*
Y1807865D01*
X904769D01*
Y1794915D01*
X886569D01*
Y1807865D01*
X872969D01*
G01X846081Y1847905D02*
X845831Y1848030D01*
X845539Y1848113D01*
X845206D01*
X844831Y1847988D01*
X844539Y1847780D01*
X844331Y1847530D01*
X844164Y1847113D01*
X844122Y1846738D01*
X844206Y1846363D01*
X844331Y1846113D01*
X844581Y1845863D01*
X844872Y1845696D01*
X845164Y1845613D01*
X845456D01*
X845747Y1845696D01*
X845997Y1845821D01*
X846206Y1845988D01*
G01X848264Y1845613D02*
Y1848113D01*
X847764Y1847613D01*
G01Y1845613D02*
X848764D01*
G01X851364Y1848113D02*
X851031Y1848030D01*
X850781Y1847821D01*
X850614Y1847571D01*
X850489Y1847238D01*
X850447Y1846863D01*
X850489Y1846488D01*
X850614Y1846155D01*
X850781Y1845905D01*
X851031Y1845696D01*
X851364Y1845613D01*
X851697Y1845696D01*
X851947Y1845905D01*
X852114Y1846155D01*
X852239Y1846488D01*
X852281Y1846863D01*
X852239Y1847238D01*
X852114Y1847571D01*
X851947Y1847821D01*
X851697Y1848030D01*
X851364Y1848113D01*
G01X854464D02*
X854131Y1848030D01*
X853881Y1847821D01*
X853714Y1847571D01*
X853589Y1847238D01*
X853547Y1846863D01*
X853589Y1846488D01*
X853714Y1846155D01*
X853881Y1845905D01*
X854131Y1845696D01*
X854464Y1845613D01*
X854797Y1845696D01*
X855047Y1845905D01*
X855214Y1846155D01*
X855339Y1846488D01*
X855381Y1846863D01*
X855339Y1847238D01*
X855214Y1847571D01*
X855047Y1847821D01*
X854797Y1848030D01*
X854464Y1848113D01*
G01X846067Y1852192D02*
X845817Y1852317D01*
X845525Y1852400D01*
X845192D01*
X844817Y1852275D01*
X844525Y1852067D01*
X844317Y1851817D01*
X844150Y1851400D01*
X844108Y1851025D01*
X844192Y1850650D01*
X844317Y1850400D01*
X844567Y1850150D01*
X844858Y1849983D01*
X845150Y1849900D01*
X845442D01*
X845733Y1849983D01*
X845983Y1850108D01*
X846192Y1850275D01*
G01X848250Y1849900D02*
Y1852400D01*
X847750Y1851900D01*
G01Y1849900D02*
X848750D01*
G01X851350Y1852400D02*
X851017Y1852317D01*
X850767Y1852108D01*
X850600Y1851858D01*
X850475Y1851525D01*
X850433Y1851150D01*
X850475Y1850775D01*
X850600Y1850442D01*
X850767Y1850192D01*
X851017Y1849983D01*
X851350Y1849900D01*
X851683Y1849983D01*
X851933Y1850192D01*
X852100Y1850442D01*
X852225Y1850775D01*
X852267Y1851150D01*
X852225Y1851525D01*
X852100Y1851858D01*
X851933Y1852108D01*
X851683Y1852317D01*
X851350Y1852400D01*
G01X853533Y1850400D02*
X853783Y1850108D01*
X854117Y1849942D01*
X854492Y1849900D01*
X854825Y1849942D01*
X855158Y1850150D01*
X855367Y1850400D01*
X855408Y1850650D01*
X855325Y1850942D01*
X855033Y1851150D01*
X854742Y1851233D01*
X854367D01*
G01X854742D02*
X854992Y1851358D01*
X855200Y1851567D01*
X855283Y1851817D01*
X855200Y1852067D01*
X854992Y1852275D01*
X854617Y1852400D01*
X854242Y1852358D01*
X853867Y1852192D01*
G01X857167Y1863692D02*
X856917Y1863817D01*
X856625Y1863900D01*
X856292D01*
X855917Y1863775D01*
X855625Y1863567D01*
X855417Y1863317D01*
X855250Y1862900D01*
X855208Y1862525D01*
X855292Y1862150D01*
X855417Y1861900D01*
X855667Y1861650D01*
X855958Y1861483D01*
X856250Y1861400D01*
X856542D01*
X856833Y1861483D01*
X857083Y1861608D01*
X857292Y1861775D01*
G01X859350Y1861400D02*
Y1863900D01*
X858850Y1863400D01*
G01Y1861400D02*
X859850D01*
G01X862450Y1863900D02*
X862117Y1863817D01*
X861867Y1863608D01*
X861700Y1863358D01*
X861575Y1863025D01*
X861533Y1862650D01*
X861575Y1862275D01*
X861700Y1861942D01*
X861867Y1861692D01*
X862117Y1861483D01*
X862450Y1861400D01*
X862783Y1861483D01*
X863033Y1861692D01*
X863200Y1861942D01*
X863325Y1862275D01*
X863367Y1862650D01*
X863325Y1863025D01*
X863200Y1863358D01*
X863033Y1863608D01*
X862783Y1863817D01*
X862450Y1863900D01*
G01X866050Y1861400D02*
Y1863900D01*
X864508Y1862108D01*
X866592D01*
G01X857081Y1867905D02*
X856831Y1868030D01*
X856539Y1868113D01*
X856206D01*
X855831Y1867988D01*
X855539Y1867780D01*
X855331Y1867530D01*
X855164Y1867113D01*
X855122Y1866738D01*
X855206Y1866363D01*
X855331Y1866113D01*
X855581Y1865863D01*
X855872Y1865696D01*
X856164Y1865613D01*
X856456D01*
X856747Y1865696D01*
X856997Y1865821D01*
X857206Y1865988D01*
G01X859264Y1865613D02*
Y1868113D01*
X858764Y1867613D01*
G01Y1865613D02*
X859764D01*
G01X862364Y1868113D02*
X862031Y1868030D01*
X861781Y1867821D01*
X861614Y1867571D01*
X861489Y1867238D01*
X861447Y1866863D01*
X861489Y1866488D01*
X861614Y1866155D01*
X861781Y1865905D01*
X862031Y1865696D01*
X862364Y1865613D01*
X862697Y1865696D01*
X862947Y1865905D01*
X863114Y1866155D01*
X863239Y1866488D01*
X863281Y1866863D01*
X863239Y1867238D01*
X863114Y1867571D01*
X862947Y1867821D01*
X862697Y1868030D01*
X862364Y1868113D01*
G01X864547Y1865988D02*
X864797Y1865780D01*
X865089Y1865655D01*
X865464Y1865613D01*
X865839Y1865696D01*
X866131Y1865863D01*
X866339Y1866155D01*
X866381Y1866488D01*
X866297Y1866821D01*
X866089Y1867030D01*
X865797Y1867196D01*
X865506Y1867238D01*
X865214Y1867196D01*
X864839Y1867030D01*
X864964Y1868113D01*
X866089D01*
G01X852517Y1882000D02*
Y1884500D01*
X853558D01*
X853892Y1884375D01*
X854100Y1884208D01*
X854183Y1883875D01*
X854100Y1883542D01*
X853850Y1883333D01*
X853558Y1883208D01*
X852517D01*
G01X853558D02*
X854183Y1882000D01*
G01X856450D02*
Y1884500D01*
X855950Y1884000D01*
G01Y1882000D02*
X856950D01*
G01X859550Y1884500D02*
X859217Y1884417D01*
X858967Y1884208D01*
X858800Y1883958D01*
X858675Y1883625D01*
X858633Y1883250D01*
X858675Y1882875D01*
X858800Y1882542D01*
X858967Y1882292D01*
X859217Y1882083D01*
X859550Y1882000D01*
X859883Y1882083D01*
X860133Y1882292D01*
X860300Y1882542D01*
X860425Y1882875D01*
X860467Y1883250D01*
X860425Y1883625D01*
X860300Y1883958D01*
X860133Y1884208D01*
X859883Y1884417D01*
X859550Y1884500D01*
G01X861858Y1883042D02*
X862150Y1883333D01*
X862400Y1883500D01*
X862733Y1883583D01*
X863025Y1883500D01*
X863233Y1883333D01*
X863400Y1883083D01*
X863442Y1882792D01*
X863400Y1882542D01*
X863233Y1882292D01*
X862983Y1882083D01*
X862692Y1882000D01*
X862358Y1882083D01*
X862067Y1882333D01*
X861900Y1882708D01*
X861858Y1883125D01*
X861942Y1883667D01*
X862067Y1883958D01*
X862275Y1884250D01*
X862567Y1884458D01*
X862858Y1884500D01*
X863150Y1884417D01*
X863358Y1884208D01*
G01X852517Y1878000D02*
Y1880500D01*
X853558D01*
X853892Y1880375D01*
X854100Y1880208D01*
X854183Y1879875D01*
X854100Y1879542D01*
X853850Y1879333D01*
X853558Y1879208D01*
X852517D01*
G01X853558D02*
X854183Y1878000D01*
G01X855533Y1878500D02*
X855783Y1878208D01*
X856117Y1878042D01*
X856492Y1878000D01*
X856825Y1878042D01*
X857158Y1878250D01*
X857367Y1878500D01*
X857408Y1878750D01*
X857325Y1879042D01*
X857033Y1879250D01*
X856742Y1879333D01*
X856367D01*
G01X856742D02*
X856992Y1879458D01*
X857200Y1879667D01*
X857283Y1879917D01*
X857200Y1880167D01*
X856992Y1880375D01*
X856617Y1880500D01*
X856242Y1880458D01*
X855867Y1880292D01*
G01X860050Y1878000D02*
Y1880500D01*
X858508Y1878708D01*
X860592D01*
G01X861733Y1878500D02*
X861983Y1878208D01*
X862317Y1878042D01*
X862692Y1878000D01*
X863025Y1878042D01*
X863358Y1878250D01*
X863567Y1878500D01*
X863608Y1878750D01*
X863525Y1879042D01*
X863233Y1879250D01*
X862942Y1879333D01*
X862567D01*
G01X862942D02*
X863192Y1879458D01*
X863400Y1879667D01*
X863483Y1879917D01*
X863400Y1880167D01*
X863192Y1880375D01*
X862817Y1880500D01*
X862442Y1880458D01*
X862067Y1880292D01*
G01X842300Y1875000D02*
X841967Y1875042D01*
X841675Y1875208D01*
X841425Y1875458D01*
X841258Y1875750D01*
X841175Y1876083D01*
Y1876417D01*
X841258Y1876750D01*
X841425Y1877042D01*
X841675Y1877292D01*
X841967Y1877458D01*
X842300Y1877500D01*
X842633Y1877458D01*
X842925Y1877292D01*
X843175Y1877042D01*
X843342Y1876750D01*
X843425Y1876417D01*
Y1876083D01*
X843342Y1875750D01*
X843175Y1875458D01*
X842925Y1875208D01*
X842633Y1875042D01*
X842300Y1875000D01*
G01X842633Y1875667D02*
X843133Y1875000D01*
G01X845900D02*
Y1877500D01*
X844358Y1875708D01*
X846442D01*
G01X847792Y1875292D02*
X848083Y1875083D01*
X848417Y1875000D01*
X848750Y1875083D01*
X849042Y1875333D01*
X849250Y1875708D01*
X849333Y1876083D01*
Y1876542D01*
X849250Y1876917D01*
X849042Y1877250D01*
X848792Y1877417D01*
X848500Y1877500D01*
X848167Y1877417D01*
X847917Y1877250D01*
X847750Y1877000D01*
X847667Y1876667D01*
X847750Y1876375D01*
X847958Y1876083D01*
X848208Y1875917D01*
X848500Y1875875D01*
X848833Y1875958D01*
X849083Y1876167D01*
X849333Y1876542D01*
G01X843999Y1881550D02*
Y1895550D01*
G01X867208Y1890767D02*
X867083Y1890517D01*
X867000Y1890225D01*
Y1889892D01*
X867125Y1889517D01*
X867333Y1889225D01*
X867583Y1889017D01*
X868000Y1888850D01*
X868375Y1888808D01*
X868750Y1888892D01*
X869000Y1889017D01*
X869250Y1889267D01*
X869417Y1889558D01*
X869500Y1889850D01*
Y1890142D01*
X869417Y1890433D01*
X869292Y1890683D01*
X869125Y1890892D01*
G01X869500Y1892950D02*
X867000D01*
X867500Y1892450D01*
G01X869500D02*
Y1893450D01*
G01X867000Y1896050D02*
X867083Y1895717D01*
X867292Y1895467D01*
X867542Y1895300D01*
X867875Y1895175D01*
X868250Y1895133D01*
X868625Y1895175D01*
X868958Y1895300D01*
X869208Y1895467D01*
X869417Y1895717D01*
X869500Y1896050D01*
X869417Y1896383D01*
X869208Y1896633D01*
X868958Y1896800D01*
X868625Y1896925D01*
X868250Y1896967D01*
X867875Y1896925D01*
X867542Y1896800D01*
X867292Y1896633D01*
X867083Y1896383D01*
X867000Y1896050D01*
G01X869500Y1899150D02*
X869458Y1899442D01*
X869333Y1899775D01*
X869125Y1899983D01*
X868833Y1900067D01*
X868542Y1899983D01*
X868292Y1899733D01*
X868167Y1899358D01*
Y1898942D01*
X868083Y1898692D01*
X867875Y1898483D01*
X867583Y1898400D01*
X867292Y1898525D01*
X867083Y1898817D01*
X867000Y1899150D01*
X867083Y1899483D01*
X867292Y1899775D01*
X867583Y1899900D01*
X867875Y1899817D01*
X868083Y1899608D01*
X868167Y1899358D01*
Y1898942D01*
X868292Y1898567D01*
X868542Y1898317D01*
X868833Y1898233D01*
X869125Y1898317D01*
X869333Y1898525D01*
X869458Y1898858D01*
X869500Y1899150D01*
G01X865207Y1922317D02*
X865082Y1922067D01*
X864999Y1921775D01*
Y1921442D01*
X865124Y1921067D01*
X865332Y1920775D01*
X865582Y1920567D01*
X865999Y1920400D01*
X866374Y1920358D01*
X866749Y1920442D01*
X866999Y1920567D01*
X867249Y1920817D01*
X867416Y1921108D01*
X867499Y1921400D01*
Y1921692D01*
X867416Y1921983D01*
X867291Y1922233D01*
X867124Y1922442D01*
G01X867499Y1924500D02*
X864999D01*
X865499Y1924000D01*
G01X867499D02*
Y1925000D01*
G01X864999Y1927600D02*
X865082Y1927267D01*
X865291Y1927017D01*
X865541Y1926850D01*
X865874Y1926725D01*
X866249Y1926683D01*
X866624Y1926725D01*
X866957Y1926850D01*
X867207Y1927017D01*
X867416Y1927267D01*
X867499Y1927600D01*
X867416Y1927933D01*
X867207Y1928183D01*
X866957Y1928350D01*
X866624Y1928475D01*
X866249Y1928517D01*
X865874Y1928475D01*
X865541Y1928350D01*
X865291Y1928183D01*
X865082Y1927933D01*
X864999Y1927600D01*
G01X866457Y1929908D02*
X866166Y1930200D01*
X865999Y1930450D01*
X865916Y1930783D01*
X865999Y1931075D01*
X866166Y1931283D01*
X866416Y1931450D01*
X866707Y1931492D01*
X866957Y1931450D01*
X867207Y1931283D01*
X867416Y1931033D01*
X867499Y1930742D01*
X867416Y1930408D01*
X867166Y1930117D01*
X866791Y1929950D01*
X866374Y1929908D01*
X865832Y1929992D01*
X865541Y1930117D01*
X865249Y1930325D01*
X865041Y1930617D01*
X864999Y1930908D01*
X865082Y1931200D01*
X865291Y1931408D01*
G01X863893Y1968604D02*
X863768Y1968354D01*
X863685Y1968062D01*
Y1967729D01*
X863810Y1967354D01*
X864018Y1967062D01*
X864268Y1966854D01*
X864685Y1966687D01*
X865060Y1966645D01*
X865435Y1966729D01*
X865685Y1966854D01*
X865935Y1967104D01*
X866102Y1967395D01*
X866185Y1967687D01*
Y1967979D01*
X866102Y1968270D01*
X865977Y1968520D01*
X865810Y1968729D01*
G01X866185Y1970787D02*
X863685D01*
X864185Y1970287D01*
G01X866185D02*
Y1971287D01*
G01Y1973887D02*
X863685D01*
X864185Y1973387D01*
G01X866185D02*
Y1974387D01*
G01X865810Y1976070D02*
X866018Y1976320D01*
X866143Y1976612D01*
X866185Y1976987D01*
X866102Y1977362D01*
X865935Y1977654D01*
X865643Y1977862D01*
X865310Y1977904D01*
X864977Y1977820D01*
X864768Y1977612D01*
X864602Y1977320D01*
X864560Y1977029D01*
X864602Y1976737D01*
X864768Y1976362D01*
X863685Y1976487D01*
Y1977612D01*
G01X865500Y1903017D02*
X863000D01*
Y1904058D01*
X863125Y1904392D01*
X863292Y1904600D01*
X863625Y1904683D01*
X863958Y1904600D01*
X864167Y1904350D01*
X864292Y1904058D01*
Y1903017D01*
G01Y1904058D02*
X865500Y1904683D01*
G01Y1906950D02*
X863000D01*
X863500Y1906450D01*
G01X865500D02*
Y1907450D01*
G01X863000Y1910050D02*
X863083Y1909717D01*
X863292Y1909467D01*
X863542Y1909300D01*
X863875Y1909175D01*
X864250Y1909133D01*
X864625Y1909175D01*
X864958Y1909300D01*
X865208Y1909467D01*
X865417Y1909717D01*
X865500Y1910050D01*
X865417Y1910383D01*
X865208Y1910633D01*
X864958Y1910800D01*
X864625Y1910925D01*
X864250Y1910967D01*
X863875Y1910925D01*
X863542Y1910800D01*
X863292Y1910633D01*
X863083Y1910383D01*
X863000Y1910050D01*
G01Y1913150D02*
X863083Y1912817D01*
X863292Y1912567D01*
X863542Y1912400D01*
X863875Y1912275D01*
X864250Y1912233D01*
X864625Y1912275D01*
X864958Y1912400D01*
X865208Y1912567D01*
X865417Y1912817D01*
X865500Y1913150D01*
X865417Y1913483D01*
X865208Y1913733D01*
X864958Y1913900D01*
X864625Y1914025D01*
X864250Y1914067D01*
X863875Y1914025D01*
X863542Y1913900D01*
X863292Y1913733D01*
X863083Y1913483D01*
X863000Y1913150D01*
G01X860564Y1900813D02*
Y1913813D01*
G01X868000Y1935517D02*
X865500D01*
Y1936558D01*
X865625Y1936892D01*
X865792Y1937100D01*
X866125Y1937183D01*
X866458Y1937100D01*
X866667Y1936850D01*
X866792Y1936558D01*
Y1935517D01*
G01Y1936558D02*
X868000Y1937183D01*
G01Y1939450D02*
X865500D01*
X866000Y1938950D01*
G01X868000D02*
Y1939950D01*
G01Y1942550D02*
X865500D01*
X866000Y1942050D01*
G01X868000D02*
Y1943050D01*
G01X865500Y1945650D02*
X865583Y1945317D01*
X865792Y1945067D01*
X866042Y1944900D01*
X866375Y1944775D01*
X866750Y1944733D01*
X867125Y1944775D01*
X867458Y1944900D01*
X867708Y1945067D01*
X867917Y1945317D01*
X868000Y1945650D01*
X867917Y1945983D01*
X867708Y1946233D01*
X867458Y1946400D01*
X867125Y1946525D01*
X866750Y1946567D01*
X866375Y1946525D01*
X866042Y1946400D01*
X865792Y1946233D01*
X865583Y1945983D01*
X865500Y1945650D01*
G01X863499Y1934050D02*
Y1947050D01*
G01X844614Y1900113D02*
Y1896113D01*
X852014D01*
G01X851999Y1891850D02*
Y1895850D01*
X844599D01*
G01X865500Y1889017D02*
X863000D01*
Y1890058D01*
X863125Y1890392D01*
X863292Y1890600D01*
X863625Y1890683D01*
X863958Y1890600D01*
X864167Y1890350D01*
X864292Y1890058D01*
Y1889017D01*
G01Y1890058D02*
X865500Y1890683D01*
G01Y1892950D02*
X863000D01*
X863500Y1892450D01*
G01X865500D02*
Y1893450D01*
G01Y1896050D02*
X863000D01*
X863500Y1895550D01*
G01X865500D02*
Y1896550D01*
G01Y1899150D02*
X863000D01*
X863500Y1898650D01*
G01X865500D02*
Y1899650D01*
G01X844400Y1956200D02*
Y1950700D01*
G01Y1968300D02*
Y1962800D01*
G01X847808Y1972167D02*
X847683Y1971917D01*
X847600Y1971625D01*
Y1971292D01*
X847725Y1970917D01*
X847933Y1970625D01*
X848183Y1970417D01*
X848600Y1970250D01*
X848975Y1970208D01*
X849350Y1970292D01*
X849600Y1970417D01*
X849850Y1970667D01*
X850017Y1970958D01*
X850100Y1971250D01*
Y1971542D01*
X850017Y1971833D01*
X849892Y1972083D01*
X849725Y1972292D01*
G01X850100Y1974350D02*
X847600D01*
X848100Y1973850D01*
G01X850100D02*
Y1974850D01*
G01Y1977450D02*
X847600D01*
X848100Y1976950D01*
G01X850100D02*
Y1977950D01*
G01X849600Y1979633D02*
X849892Y1979883D01*
X850058Y1980217D01*
X850100Y1980592D01*
X850058Y1980925D01*
X849850Y1981258D01*
X849600Y1981467D01*
X849350Y1981508D01*
X849058Y1981425D01*
X848850Y1981133D01*
X848767Y1980842D01*
Y1980467D01*
G01Y1980842D02*
X848642Y1981092D01*
X848433Y1981300D01*
X848183Y1981383D01*
X847933Y1981300D01*
X847725Y1981092D01*
X847600Y1980717D01*
X847642Y1980342D01*
X847808Y1979967D01*
G01X845100Y1950700D02*
Y1956200D01*
G01X853100Y1950700D02*
X845100D01*
G01X853100Y1956200D02*
Y1950700D01*
G01Y1968300D02*
Y1962800D01*
G01X845100Y1968300D02*
X853100D01*
G01X845100Y1962800D02*
Y1968300D01*
G01X856508Y1972167D02*
X856383Y1971917D01*
X856300Y1971625D01*
Y1971292D01*
X856425Y1970917D01*
X856633Y1970625D01*
X856883Y1970417D01*
X857300Y1970250D01*
X857675Y1970208D01*
X858050Y1970292D01*
X858300Y1970417D01*
X858550Y1970667D01*
X858717Y1970958D01*
X858800Y1971250D01*
Y1971542D01*
X858717Y1971833D01*
X858592Y1972083D01*
X858425Y1972292D01*
G01X858800Y1974350D02*
X856300D01*
X856800Y1973850D01*
G01X858800D02*
Y1974850D01*
G01Y1977450D02*
X856300D01*
X856800Y1976950D01*
G01X858800D02*
Y1977950D01*
G01Y1981050D02*
X856300D01*
X858092Y1979508D01*
Y1981592D01*
G01X853800Y1950700D02*
Y1956200D01*
G01X861800Y1950700D02*
X853800D01*
G01X861800Y1956200D02*
Y1950700D01*
G01Y1968300D02*
Y1962800D01*
G01X853800Y1968300D02*
X861800D01*
G01X853800Y1962800D02*
Y1968300D01*
G01X861208Y1922267D02*
X861083Y1922017D01*
X861000Y1921725D01*
Y1921392D01*
X861125Y1921017D01*
X861333Y1920725D01*
X861583Y1920517D01*
X862000Y1920350D01*
X862375Y1920308D01*
X862750Y1920392D01*
X863000Y1920517D01*
X863250Y1920767D01*
X863417Y1921058D01*
X863500Y1921350D01*
Y1921642D01*
X863417Y1921933D01*
X863292Y1922183D01*
X863125Y1922392D01*
G01X863500Y1924450D02*
X861000D01*
X861500Y1923950D01*
G01X863500D02*
Y1924950D01*
G01X861000Y1927550D02*
X861083Y1927217D01*
X861292Y1926967D01*
X861542Y1926800D01*
X861875Y1926675D01*
X862250Y1926633D01*
X862625Y1926675D01*
X862958Y1926800D01*
X863208Y1926967D01*
X863417Y1927217D01*
X863500Y1927550D01*
X863417Y1927883D01*
X863208Y1928133D01*
X862958Y1928300D01*
X862625Y1928425D01*
X862250Y1928467D01*
X861875Y1928425D01*
X861542Y1928300D01*
X861292Y1928133D01*
X861083Y1927883D01*
X861000Y1927550D01*
G01X863500Y1930567D02*
X862958Y1930650D01*
X862500Y1930775D01*
X862083Y1930942D01*
X861625Y1931150D01*
X861000Y1931483D01*
Y1929817D01*
G01X846314Y1914813D02*
Y1920313D01*
G01X854314Y1914813D02*
X846314D01*
G01X854314Y1920313D02*
Y1914813D01*
G01Y1932413D02*
Y1926913D01*
G01X846314Y1932413D02*
X854314D01*
G01X846314Y1926913D02*
Y1932413D01*
G01X934799Y39450D02*
Y49650D01*
G01Y39450D02*
Y49650D01*
G01X924267Y66000D02*
Y68500D01*
X925267D01*
X925600Y68375D01*
X925850Y68083D01*
X925933Y67750D01*
X925850Y67417D01*
X925642Y67167D01*
X925267Y67042D01*
X924267D01*
G01X927283Y68500D02*
Y66708D01*
X927450Y66333D01*
X927783Y66083D01*
X928200Y66000D01*
X928617Y66083D01*
X928950Y66333D01*
X929117Y66708D01*
Y68500D01*
G01X931300Y66000D02*
Y68500D01*
X930800Y68000D01*
G01Y66000D02*
X931800D01*
G01X965167Y44100D02*
Y46600D01*
X966167D01*
X966500Y46475D01*
X966750Y46183D01*
X966833Y45850D01*
X966750Y45517D01*
X966542Y45267D01*
X966167Y45142D01*
X965167D01*
G01X970017Y46392D02*
X969767Y46517D01*
X969475Y46600D01*
X969142D01*
X968767Y46475D01*
X968475Y46267D01*
X968267Y46017D01*
X968100Y45600D01*
X968058Y45225D01*
X968142Y44850D01*
X968267Y44600D01*
X968517Y44350D01*
X968808Y44183D01*
X969100Y44100D01*
X969392D01*
X969683Y44183D01*
X969933Y44308D01*
X970142Y44475D01*
G01X971283D02*
X971533Y44267D01*
X971825Y44142D01*
X972200Y44100D01*
X972575Y44183D01*
X972867Y44350D01*
X973075Y44642D01*
X973117Y44975D01*
X973033Y45308D01*
X972825Y45517D01*
X972533Y45683D01*
X972242Y45725D01*
X971950Y45683D01*
X971575Y45517D01*
X971700Y46600D01*
X972825D01*
G01X964867Y62400D02*
Y64900D01*
X965867D01*
X966200Y64775D01*
X966450Y64483D01*
X966533Y64150D01*
X966450Y63817D01*
X966242Y63567D01*
X965867Y63442D01*
X964867D01*
G01X969717Y64692D02*
X969467Y64817D01*
X969175Y64900D01*
X968842D01*
X968467Y64775D01*
X968175Y64567D01*
X967967Y64317D01*
X967800Y63900D01*
X967758Y63525D01*
X967842Y63150D01*
X967967Y62900D01*
X968217Y62650D01*
X968508Y62483D01*
X968800Y62400D01*
X969092D01*
X969383Y62483D01*
X969633Y62608D01*
X969842Y62775D01*
G01X972400Y62400D02*
Y64900D01*
X970858Y63108D01*
X972942D01*
G01X964567Y53700D02*
Y56200D01*
X965567D01*
X965900Y56075D01*
X966150Y55783D01*
X966233Y55450D01*
X966150Y55117D01*
X965942Y54867D01*
X965567Y54742D01*
X964567D01*
G01X969417Y55992D02*
X969167Y56117D01*
X968875Y56200D01*
X968542D01*
X968167Y56075D01*
X967875Y55867D01*
X967667Y55617D01*
X967500Y55200D01*
X967458Y54825D01*
X967542Y54450D01*
X967667Y54200D01*
X967917Y53950D01*
X968208Y53783D01*
X968500Y53700D01*
X968792D01*
X969083Y53783D01*
X969333Y53908D01*
X969542Y54075D01*
G01X971600Y53700D02*
Y56200D01*
X971100Y55700D01*
G01Y53700D02*
X972100D01*
G01X929900Y117417D02*
X927400D01*
Y118417D01*
X927525Y118750D01*
X927817Y119000D01*
X928150Y119083D01*
X928483Y119000D01*
X928733Y118792D01*
X928858Y118417D01*
Y117417D01*
G01X927608Y122267D02*
X927483Y122017D01*
X927400Y121725D01*
Y121392D01*
X927525Y121017D01*
X927733Y120725D01*
X927983Y120517D01*
X928400Y120350D01*
X928775Y120308D01*
X929150Y120392D01*
X929400Y120517D01*
X929650Y120767D01*
X929817Y121058D01*
X929900Y121350D01*
Y121642D01*
X929817Y121933D01*
X929692Y122183D01*
X929525Y122392D01*
G01X929900Y124450D02*
X927400D01*
X927900Y123950D01*
G01X929900D02*
Y124950D01*
G01X929400Y126633D02*
X929692Y126883D01*
X929858Y127217D01*
X929900Y127592D01*
X929858Y127925D01*
X929650Y128258D01*
X929400Y128467D01*
X929150Y128508D01*
X928858Y128425D01*
X928650Y128133D01*
X928567Y127842D01*
Y127467D01*
G01Y127842D02*
X928442Y128092D01*
X928233Y128300D01*
X927983Y128383D01*
X927733Y128300D01*
X927525Y128092D01*
X927400Y127717D01*
X927442Y127342D01*
X927608Y126967D01*
G01X970716Y95350D02*
Y97850D01*
X971716D01*
X972049Y97725D01*
X972299Y97433D01*
X972382Y97100D01*
X972299Y96767D01*
X972091Y96517D01*
X971716Y96392D01*
X970716D01*
G01X975566Y97642D02*
X975316Y97767D01*
X975024Y97850D01*
X974691D01*
X974316Y97725D01*
X974024Y97517D01*
X973816Y97267D01*
X973649Y96850D01*
X973607Y96475D01*
X973691Y96100D01*
X973816Y95850D01*
X974066Y95600D01*
X974357Y95433D01*
X974649Y95350D01*
X974941D01*
X975232Y95433D01*
X975482Y95558D01*
X975691Y95725D01*
G01X977749Y95350D02*
Y97850D01*
X977249Y97350D01*
G01Y95350D02*
X978249D01*
G01X980849Y97850D02*
X980516Y97767D01*
X980266Y97558D01*
X980099Y97308D01*
X979974Y96975D01*
X979932Y96600D01*
X979974Y96225D01*
X980099Y95892D01*
X980266Y95642D01*
X980516Y95433D01*
X980849Y95350D01*
X981182Y95433D01*
X981432Y95642D01*
X981599Y95892D01*
X981724Y96225D01*
X981766Y96600D01*
X981724Y96975D01*
X981599Y97308D01*
X981432Y97558D01*
X981182Y97767D01*
X980849Y97850D01*
G01X942400Y117417D02*
X939900D01*
Y118417D01*
X940025Y118750D01*
X940317Y119000D01*
X940650Y119083D01*
X940983Y119000D01*
X941233Y118792D01*
X941358Y118417D01*
Y117417D01*
G01X942400Y120517D02*
X939900D01*
Y121558D01*
X940025Y121892D01*
X940192Y122100D01*
X940525Y122183D01*
X940858Y122100D01*
X941067Y121850D01*
X941192Y121558D01*
Y120517D01*
G01Y121558D02*
X942400Y122183D01*
G01Y124450D02*
X939900D01*
X940400Y123950D01*
G01X942400D02*
Y124950D01*
G01X941358Y126758D02*
X941067Y127050D01*
X940900Y127300D01*
X940817Y127633D01*
X940900Y127925D01*
X941067Y128133D01*
X941317Y128300D01*
X941608Y128342D01*
X941858Y128300D01*
X942108Y128133D01*
X942317Y127883D01*
X942400Y127592D01*
X942317Y127258D01*
X942067Y126967D01*
X941692Y126800D01*
X941275Y126758D01*
X940733Y126842D01*
X940442Y126967D01*
X940150Y127175D01*
X939942Y127467D01*
X939900Y127758D01*
X939983Y128050D01*
X940192Y128258D01*
G01X938499Y106350D02*
X942499D01*
Y113750D01*
G01X960300Y107917D02*
X957800D01*
Y108917D01*
X957925Y109250D01*
X958217Y109500D01*
X958550Y109583D01*
X958883Y109500D01*
X959133Y109292D01*
X959258Y108917D01*
Y107917D01*
G01X960300Y111017D02*
X957800D01*
Y112058D01*
X957925Y112392D01*
X958092Y112600D01*
X958425Y112683D01*
X958758Y112600D01*
X958967Y112350D01*
X959092Y112058D01*
Y111017D01*
G01Y112058D02*
X960300Y112683D01*
G01Y114950D02*
X957800D01*
X958300Y114450D01*
G01X960300D02*
Y115450D01*
G01X959800Y117133D02*
X960092Y117383D01*
X960258Y117717D01*
X960300Y118092D01*
X960258Y118425D01*
X960050Y118758D01*
X959800Y118967D01*
X959550Y119008D01*
X959258Y118925D01*
X959050Y118633D01*
X958967Y118342D01*
Y117967D01*
G01Y118342D02*
X958842Y118592D01*
X958633Y118800D01*
X958383Y118883D01*
X958133Y118800D01*
X957925Y118592D01*
X957800Y118217D01*
X957842Y117842D01*
X958008Y117467D01*
G01X942499Y106350D02*
X946499D01*
Y113750D01*
G01X938000Y117217D02*
X935500D01*
Y118217D01*
X935625Y118550D01*
X935917Y118800D01*
X936250Y118883D01*
X936583Y118800D01*
X936833Y118592D01*
X936958Y118217D01*
Y117217D01*
G01X938000Y120317D02*
X935500D01*
Y121358D01*
X935625Y121692D01*
X935792Y121900D01*
X936125Y121983D01*
X936458Y121900D01*
X936667Y121650D01*
X936792Y121358D01*
Y120317D01*
G01Y121358D02*
X938000Y121983D01*
G01Y124250D02*
X935500D01*
X936000Y123750D01*
G01X938000D02*
Y124750D01*
G01X935917Y126558D02*
X935667Y126808D01*
X935542Y127100D01*
X935500Y127433D01*
X935583Y127850D01*
X935792Y128142D01*
X936042Y128225D01*
X936292Y128183D01*
X936500Y128017D01*
X936917Y127183D01*
X937208Y126808D01*
X937625Y126558D01*
X938000Y126475D01*
Y128225D01*
G01X938499Y113750D02*
X934499D01*
Y106350D01*
G01X933700Y117417D02*
X931200D01*
Y118417D01*
X931325Y118750D01*
X931617Y119000D01*
X931950Y119083D01*
X932283Y119000D01*
X932533Y118792D01*
X932658Y118417D01*
Y117417D01*
G01X933700Y120517D02*
X931200D01*
Y121558D01*
X931325Y121892D01*
X931492Y122100D01*
X931825Y122183D01*
X932158Y122100D01*
X932367Y121850D01*
X932492Y121558D01*
Y120517D01*
G01Y121558D02*
X933700Y122183D01*
G01Y124450D02*
X931200D01*
X931700Y123950D01*
G01X933700D02*
Y124950D01*
G01Y127550D02*
X931200D01*
X931700Y127050D01*
G01X933700D02*
Y128050D01*
G01X930499Y106350D02*
X934499D01*
Y113750D01*
G01X970100Y108017D02*
X967600D01*
Y109017D01*
X967725Y109350D01*
X968017Y109600D01*
X968350Y109683D01*
X968683Y109600D01*
X968933Y109392D01*
X969058Y109017D01*
Y108017D01*
G01X970100Y111117D02*
X967600D01*
Y112158D01*
X967725Y112492D01*
X967892Y112700D01*
X968225Y112783D01*
X968558Y112700D01*
X968767Y112450D01*
X968892Y112158D01*
Y111117D01*
G01Y112158D02*
X970100Y112783D01*
G01Y115050D02*
X967600D01*
X968100Y114550D01*
G01X970100D02*
Y115550D01*
G01X967600Y118150D02*
X967683Y117817D01*
X967892Y117567D01*
X968142Y117400D01*
X968475Y117275D01*
X968850Y117233D01*
X969225Y117275D01*
X969558Y117400D01*
X969808Y117567D01*
X970017Y117817D01*
X970100Y118150D01*
X970017Y118483D01*
X969808Y118733D01*
X969558Y118900D01*
X969225Y119025D01*
X968850Y119067D01*
X968475Y119025D01*
X968142Y118900D01*
X967892Y118733D01*
X967683Y118483D01*
X967600Y118150D01*
G01X950499Y106350D02*
X954499D01*
Y113750D01*
G01X964900Y109067D02*
X962400D01*
Y110067D01*
X962525Y110400D01*
X962817Y110650D01*
X963150Y110733D01*
X963483Y110650D01*
X963733Y110442D01*
X963858Y110067D01*
Y109067D01*
G01X964900Y112167D02*
X962400D01*
Y113208D01*
X962525Y113542D01*
X962692Y113750D01*
X963025Y113833D01*
X963358Y113750D01*
X963567Y113500D01*
X963692Y113208D01*
Y112167D01*
G01Y113208D02*
X964900Y113833D01*
G01Y116017D02*
X964358Y116100D01*
X963900Y116225D01*
X963483Y116392D01*
X963025Y116600D01*
X962400Y116933D01*
Y115267D01*
G01X950499Y113750D02*
X946499D01*
Y106350D01*
G01X965367Y87900D02*
Y90400D01*
X966367D01*
X966700Y90275D01*
X966950Y89983D01*
X967033Y89650D01*
X966950Y89317D01*
X966742Y89067D01*
X966367Y88942D01*
X965367D01*
G01X968467Y87900D02*
Y90400D01*
X969508D01*
X969842Y90275D01*
X970050Y90108D01*
X970133Y89775D01*
X970050Y89442D01*
X969800Y89233D01*
X969508Y89108D01*
X968467D01*
G01X969508D02*
X970133Y87900D01*
G01X972400D02*
Y90400D01*
X971900Y89900D01*
G01Y87900D02*
X972900D01*
G01X965766Y100950D02*
Y103450D01*
X966766D01*
X967099Y103325D01*
X967349Y103033D01*
X967432Y102700D01*
X967349Y102367D01*
X967141Y102117D01*
X966766Y101992D01*
X965766D01*
G01X970616Y103242D02*
X970366Y103367D01*
X970074Y103450D01*
X969741D01*
X969366Y103325D01*
X969074Y103117D01*
X968866Y102867D01*
X968699Y102450D01*
X968657Y102075D01*
X968741Y101700D01*
X968866Y101450D01*
X969116Y101200D01*
X969407Y101033D01*
X969699Y100950D01*
X969991D01*
X970282Y101033D01*
X970532Y101158D01*
X970741Y101325D01*
G01X972007Y101992D02*
X972299Y102283D01*
X972549Y102450D01*
X972882Y102533D01*
X973174Y102450D01*
X973382Y102283D01*
X973549Y102033D01*
X973591Y101742D01*
X973549Y101492D01*
X973382Y101242D01*
X973132Y101033D01*
X972841Y100950D01*
X972507Y101033D01*
X972216Y101283D01*
X972049Y101658D01*
X972007Y102075D01*
X972091Y102617D01*
X972216Y102908D01*
X972424Y103200D01*
X972716Y103408D01*
X973007Y103450D01*
X973299Y103367D01*
X973507Y103158D01*
G01X948400Y123567D02*
X945900D01*
Y124567D01*
X946025Y124900D01*
X946317Y125150D01*
X946650Y125233D01*
X946983Y125150D01*
X947233Y124942D01*
X947358Y124567D01*
Y123567D01*
G01X947150Y127750D02*
Y128583D01*
X947900D01*
X948150Y128333D01*
X948317Y128042D01*
X948400Y127625D01*
X948317Y127208D01*
X948150Y126917D01*
X947900Y126667D01*
X947608Y126500D01*
X947275Y126417D01*
X946983D01*
X946733Y126500D01*
X946442Y126667D01*
X946192Y126917D01*
X946025Y127167D01*
X945900Y127500D01*
Y127792D01*
X945983Y128125D01*
X946150Y128375D01*
G01X948400Y130600D02*
X945900D01*
X946400Y130100D01*
G01X948400D02*
Y131100D01*
G01X942349Y94550D02*
Y99550D01*
X937349D01*
G01Y71550D02*
X942349D01*
Y76550D01*
G01X941342Y91456D02*
X944342D01*
G01X941342Y81613D02*
X943342D01*
G01X965467Y72000D02*
Y74500D01*
X966467D01*
X966800Y74375D01*
X967050Y74083D01*
X967133Y73750D01*
X967050Y73417D01*
X966842Y73167D01*
X966467Y73042D01*
X965467D01*
G01X970317Y74292D02*
X970067Y74417D01*
X969775Y74500D01*
X969442D01*
X969067Y74375D01*
X968775Y74167D01*
X968567Y73917D01*
X968400Y73500D01*
X968358Y73125D01*
X968442Y72750D01*
X968567Y72500D01*
X968817Y72250D01*
X969108Y72083D01*
X969400Y72000D01*
X969692D01*
X969983Y72083D01*
X970233Y72208D01*
X970442Y72375D01*
G01X971583Y72500D02*
X971833Y72208D01*
X972167Y72042D01*
X972542Y72000D01*
X972875Y72042D01*
X973208Y72250D01*
X973417Y72500D01*
X973458Y72750D01*
X973375Y73042D01*
X973083Y73250D01*
X972792Y73333D01*
X972417D01*
G01X972792D02*
X973042Y73458D01*
X973250Y73667D01*
X973333Y73917D01*
X973250Y74167D01*
X973042Y74375D01*
X972667Y74500D01*
X972292Y74458D01*
X971917Y74292D01*
G01X964567Y80700D02*
Y83200D01*
X965567D01*
X965900Y83075D01*
X966150Y82783D01*
X966233Y82450D01*
X966150Y82117D01*
X965942Y81867D01*
X965567Y81742D01*
X964567D01*
G01X969417Y82992D02*
X969167Y83117D01*
X968875Y83200D01*
X968542D01*
X968167Y83075D01*
X967875Y82867D01*
X967667Y82617D01*
X967500Y82200D01*
X967458Y81825D01*
X967542Y81450D01*
X967667Y81200D01*
X967917Y80950D01*
X968208Y80783D01*
X968500Y80700D01*
X968792D01*
X969083Y80783D01*
X969333Y80908D01*
X969542Y81075D01*
G01X970808Y82783D02*
X971058Y83033D01*
X971350Y83158D01*
X971683Y83200D01*
X972100Y83117D01*
X972392Y82908D01*
X972475Y82658D01*
X972433Y82408D01*
X972267Y82200D01*
X971433Y81783D01*
X971058Y81492D01*
X970808Y81075D01*
X970725Y80700D01*
X972475D01*
G01X940499Y184050D02*
Y194050D01*
G01X947499D02*
Y184050D01*
G01Y189050D02*
X940499D01*
G01X950932Y184050D02*
Y194050D01*
X954266D01*
X955599Y193550D01*
X956599Y192883D01*
X957432Y191883D01*
X958099Y190716D01*
X958266Y189050D01*
X958099Y187383D01*
X957432Y186217D01*
X956599Y185216D01*
X955599Y184550D01*
X954266Y184050D01*
X950932D01*
G01X961532D02*
Y194050D01*
X964866D01*
X966199Y193550D01*
X967199Y192883D01*
X968032Y191883D01*
X968699Y190716D01*
X968866Y189050D01*
X968699Y187383D01*
X968032Y186217D01*
X967199Y185216D01*
X966199Y184550D01*
X964866Y184050D01*
X961532D01*
G01X977799D02*
Y194050D01*
X971632Y186883D01*
X979966D01*
G01X981399Y180717D02*
X991399D01*
G01X993666Y194050D02*
Y184050D01*
X1000332D01*
G01X1010932D02*
X1004266D01*
Y194050D01*
X1010932D01*
G01X1008266Y189217D02*
X1004266D01*
G01X1014532Y184050D02*
Y194050D01*
X1017866D01*
X1019199Y193550D01*
X1020199Y192883D01*
X1021032Y191883D01*
X1021699Y190716D01*
X1021866Y189050D01*
X1021699Y187383D01*
X1021032Y186217D01*
X1020199Y185216D01*
X1019199Y184550D01*
X1017866Y184050D01*
X1014532D01*
G01X924016Y152550D02*
Y155050D01*
X925057D01*
X925391Y154925D01*
X925599Y154758D01*
X925682Y154425D01*
X925599Y154092D01*
X925349Y153883D01*
X925057Y153758D01*
X924016D01*
G01X925057D02*
X925682Y152550D01*
G01X928449D02*
Y155050D01*
X926907Y153258D01*
X928991D01*
G01X930341Y152842D02*
X930632Y152633D01*
X930966Y152550D01*
X931299Y152633D01*
X931591Y152883D01*
X931799Y153258D01*
X931882Y153633D01*
Y154092D01*
X931799Y154467D01*
X931591Y154800D01*
X931341Y154967D01*
X931049Y155050D01*
X930716Y154967D01*
X930466Y154800D01*
X930299Y154550D01*
X930216Y154217D01*
X930299Y153925D01*
X930507Y153633D01*
X930757Y153467D01*
X931049Y153425D01*
X931382Y153508D01*
X931632Y153717D01*
X931882Y154092D01*
G01X933357Y154633D02*
X933607Y154883D01*
X933899Y155008D01*
X934232Y155050D01*
X934649Y154967D01*
X934941Y154758D01*
X935024Y154508D01*
X934982Y154258D01*
X934816Y154050D01*
X933982Y153633D01*
X933607Y153342D01*
X933357Y152925D01*
X933274Y152550D01*
X935024D01*
G01X933099Y156500D02*
Y160500D01*
X925699D01*
G01X934584Y176959D02*
X934251Y177001D01*
X933959Y177167D01*
X933709Y177417D01*
X933542Y177709D01*
X933459Y178042D01*
Y178376D01*
X933542Y178709D01*
X933709Y179001D01*
X933959Y179251D01*
X934251Y179417D01*
X934584Y179459D01*
X934917Y179417D01*
X935209Y179251D01*
X935459Y179001D01*
X935626Y178709D01*
X935709Y178376D01*
Y178042D01*
X935626Y177709D01*
X935459Y177417D01*
X935209Y177167D01*
X934917Y177001D01*
X934584Y176959D01*
G01X934917Y177626D02*
X935417Y176959D01*
G01X936767Y177459D02*
X937017Y177167D01*
X937351Y177001D01*
X937726Y176959D01*
X938059Y177001D01*
X938392Y177209D01*
X938601Y177459D01*
X938642Y177709D01*
X938559Y178001D01*
X938267Y178209D01*
X937976Y178292D01*
X937601D01*
G01X937976D02*
X938226Y178417D01*
X938434Y178626D01*
X938517Y178876D01*
X938434Y179126D01*
X938226Y179334D01*
X937851Y179459D01*
X937476Y179417D01*
X937101Y179251D01*
G01X940784Y176959D02*
X941076Y177001D01*
X941409Y177126D01*
X941617Y177334D01*
X941701Y177626D01*
X941617Y177917D01*
X941367Y178167D01*
X940992Y178292D01*
X940576D01*
X940326Y178376D01*
X940117Y178584D01*
X940034Y178876D01*
X940159Y179167D01*
X940451Y179376D01*
X940784Y179459D01*
X941117Y179376D01*
X941409Y179167D01*
X941534Y178876D01*
X941451Y178584D01*
X941242Y178376D01*
X940992Y178292D01*
X940576D01*
X940201Y178167D01*
X939951Y177917D01*
X939867Y177626D01*
X939951Y177334D01*
X940159Y177126D01*
X940492Y177001D01*
X940784Y176959D01*
G01X928799Y161200D02*
X942799D01*
G01X928799Y174200D02*
Y161200D01*
G01X942799Y174200D02*
X928799D01*
G01X942799Y161200D02*
Y174200D01*
G01X936767Y228175D02*
X936975Y228508D01*
X937100Y228883D01*
Y229217D01*
X936975Y229550D01*
X936767Y229800D01*
X936475Y229925D01*
X936183Y229842D01*
X935933Y229633D01*
X935767Y229258D01*
X935683Y228758D01*
X935517Y228467D01*
X935225Y228342D01*
X934933Y228425D01*
X934725Y228633D01*
X934600Y228925D01*
Y229217D01*
X934683Y229508D01*
X934892Y229758D01*
G01X937100Y231233D02*
X934600D01*
G01Y232817D02*
X936142Y231233D01*
G01X937100Y233067D02*
X935433Y231942D01*
G01X934600Y235250D02*
X937100D01*
G01X934600Y234292D02*
Y236208D01*
G01X936725Y237433D02*
X936933Y237683D01*
X937058Y237975D01*
X937100Y238350D01*
X937017Y238725D01*
X936850Y239017D01*
X936558Y239225D01*
X936225Y239267D01*
X935892Y239183D01*
X935683Y238975D01*
X935517Y238683D01*
X935475Y238392D01*
X935517Y238100D01*
X935683Y237725D01*
X934600Y237850D01*
Y238975D01*
G01X996218Y173606D02*
Y176106D01*
G01X997968D02*
Y173606D01*
G01Y174856D02*
X996218D01*
G01X1000193Y173606D02*
Y176106D01*
X999693Y175606D01*
G01Y173606D02*
X1000693D01*
G01X1002501Y174648D02*
X1002793Y174939D01*
X1003043Y175106D01*
X1003376Y175189D01*
X1003668Y175106D01*
X1003876Y174939D01*
X1004043Y174689D01*
X1004085Y174398D01*
X1004043Y174148D01*
X1003876Y173898D01*
X1003626Y173689D01*
X1003335Y173606D01*
X1003001Y173689D01*
X1002710Y173939D01*
X1002543Y174314D01*
X1002501Y174731D01*
X1002585Y175273D01*
X1002710Y175564D01*
X1002918Y175856D01*
X1003210Y176064D01*
X1003501Y176106D01*
X1003793Y176023D01*
X1004001Y175814D01*
G01X937265Y283650D02*
X947265D01*
G01Y276650D02*
X937265D01*
G01X942265D02*
Y283650D01*
G01X937265Y273217D02*
X947265D01*
Y269883D01*
X946765Y268550D01*
X946098Y267550D01*
X945098Y266717D01*
X943931Y266050D01*
X942265Y265883D01*
X940598Y266050D01*
X939432Y266717D01*
X938431Y267550D01*
X937765Y268550D01*
X937265Y269883D01*
Y273217D01*
G01Y262617D02*
X947265D01*
Y259283D01*
X946765Y257950D01*
X946098Y256950D01*
X945098Y256117D01*
X943931Y255450D01*
X942265Y255283D01*
X940598Y255450D01*
X939432Y256117D01*
X938431Y256950D01*
X937765Y257950D01*
X937265Y259283D01*
Y262617D01*
G01Y246350D02*
X947265D01*
X940098Y252517D01*
Y244183D01*
G01X931725Y558099D02*
X931683Y557766D01*
X931517Y557474D01*
X931267Y557224D01*
X930975Y557057D01*
X930642Y556974D01*
X930308D01*
X929975Y557057D01*
X929683Y557224D01*
X929433Y557474D01*
X929267Y557766D01*
X929225Y558099D01*
X929267Y558432D01*
X929433Y558724D01*
X929683Y558974D01*
X929975Y559141D01*
X930308Y559224D01*
X930642D01*
X930975Y559141D01*
X931267Y558974D01*
X931517Y558724D01*
X931683Y558432D01*
X931725Y558099D01*
G01X931058Y558432D02*
X931725Y558932D01*
G01X931225Y560282D02*
X931517Y560532D01*
X931683Y560866D01*
X931725Y561241D01*
X931683Y561574D01*
X931475Y561907D01*
X931225Y562116D01*
X930975Y562157D01*
X930683Y562074D01*
X930475Y561782D01*
X930392Y561491D01*
Y561116D01*
G01Y561491D02*
X930267Y561741D01*
X930058Y561949D01*
X929808Y562032D01*
X929558Y561949D01*
X929350Y561741D01*
X929225Y561366D01*
X929267Y560991D01*
X929433Y560616D01*
G01X931725Y564216D02*
X931183Y564299D01*
X930725Y564424D01*
X930308Y564591D01*
X929850Y564799D01*
X929225Y565132D01*
Y563466D01*
G01X925299Y560400D02*
Y573400D01*
G01X934567Y634775D02*
X934775Y635108D01*
X934900Y635483D01*
Y635817D01*
X934775Y636150D01*
X934567Y636400D01*
X934275Y636525D01*
X933983Y636442D01*
X933733Y636233D01*
X933567Y635858D01*
X933483Y635358D01*
X933317Y635067D01*
X933025Y634942D01*
X932733Y635025D01*
X932525Y635233D01*
X932400Y635525D01*
Y635817D01*
X932483Y636108D01*
X932692Y636358D01*
G01X934900Y637833D02*
X932400D01*
G01Y639417D02*
X933942Y637833D01*
G01X934900Y639667D02*
X933233Y638542D01*
G01X932400Y641850D02*
X934900D01*
G01X932400Y640892D02*
Y642808D01*
G01X934900Y645450D02*
X932400D01*
X934192Y643908D01*
Y645992D01*
G01X941765Y689750D02*
X951765D01*
G01Y682750D02*
X941765D01*
G01X946765D02*
Y689750D01*
G01X941765Y679317D02*
X951765D01*
Y675983D01*
X951265Y674650D01*
X950598Y673650D01*
X949598Y672817D01*
X948431Y672150D01*
X946765Y671983D01*
X945098Y672150D01*
X943932Y672817D01*
X942931Y673650D01*
X942265Y674650D01*
X941765Y675983D01*
Y679317D01*
G01Y668717D02*
X951765D01*
Y665383D01*
X951265Y664050D01*
X950598Y663050D01*
X949598Y662217D01*
X948431Y661550D01*
X946765Y661383D01*
X945098Y661550D01*
X943932Y662217D01*
X942931Y663050D01*
X942265Y664050D01*
X941765Y665383D01*
Y668717D01*
G01X943765Y658117D02*
X942598Y657117D01*
X941932Y655784D01*
X941765Y654283D01*
X941932Y652950D01*
X942765Y651617D01*
X943765Y650783D01*
X944765Y650617D01*
X945931Y650950D01*
X946765Y652117D01*
X947098Y653283D01*
Y654783D01*
G01Y653283D02*
X947598Y652283D01*
X948431Y651450D01*
X949432Y651117D01*
X950432Y651450D01*
X951265Y652283D01*
X951765Y653783D01*
X951598Y655283D01*
X950932Y656783D01*
G01X989318Y700428D02*
Y702928D01*
G01X991068D02*
Y700428D01*
G01Y701678D02*
X989318D01*
G01X993293Y700428D02*
Y702928D01*
X992793Y702428D01*
G01Y700428D02*
X993793D01*
G01X995476Y700803D02*
X995726Y700595D01*
X996018Y700470D01*
X996393Y700428D01*
X996768Y700511D01*
X997060Y700678D01*
X997268Y700970D01*
X997310Y701303D01*
X997226Y701636D01*
X997018Y701845D01*
X996726Y702011D01*
X996435Y702053D01*
X996143Y702011D01*
X995768Y701845D01*
X995893Y702928D01*
X997018D01*
G01X928341Y974830D02*
X928008Y974872D01*
X927716Y975038D01*
X927466Y975288D01*
X927299Y975580D01*
X927216Y975913D01*
Y976247D01*
X927299Y976580D01*
X927466Y976872D01*
X927716Y977122D01*
X928008Y977288D01*
X928341Y977330D01*
X928674Y977288D01*
X928966Y977122D01*
X929216Y976872D01*
X929383Y976580D01*
X929466Y976247D01*
Y975913D01*
X929383Y975580D01*
X929216Y975288D01*
X928966Y975038D01*
X928674Y974872D01*
X928341Y974830D01*
G01X928674Y975497D02*
X929174Y974830D01*
G01X930524Y975330D02*
X930774Y975038D01*
X931108Y974872D01*
X931483Y974830D01*
X931816Y974872D01*
X932149Y975080D01*
X932358Y975330D01*
X932399Y975580D01*
X932316Y975872D01*
X932024Y976080D01*
X931733Y976163D01*
X931358D01*
G01X931733D02*
X931983Y976288D01*
X932191Y976497D01*
X932274Y976747D01*
X932191Y976997D01*
X931983Y977205D01*
X931608Y977330D01*
X931233Y977288D01*
X930858Y977122D01*
G01X933749Y975872D02*
X934041Y976163D01*
X934291Y976330D01*
X934624Y976413D01*
X934916Y976330D01*
X935124Y976163D01*
X935291Y975913D01*
X935333Y975622D01*
X935291Y975372D01*
X935124Y975122D01*
X934874Y974913D01*
X934583Y974830D01*
X934249Y974913D01*
X933958Y975163D01*
X933791Y975538D01*
X933749Y975955D01*
X933833Y976497D01*
X933958Y976788D01*
X934166Y977080D01*
X934458Y977288D01*
X934749Y977330D01*
X935041Y977247D01*
X935249Y977038D01*
G01X925299Y964600D02*
Y977600D01*
G01X944265Y1092350D02*
X954265D01*
G01Y1085350D02*
X944265D01*
G01X949265D02*
Y1092350D01*
G01X944265Y1081917D02*
X954265D01*
Y1078583D01*
X953765Y1077250D01*
X953098Y1076250D01*
X952098Y1075417D01*
X950931Y1074750D01*
X949265Y1074583D01*
X947598Y1074750D01*
X946432Y1075417D01*
X945431Y1076250D01*
X944765Y1077250D01*
X944265Y1078583D01*
Y1081917D01*
G01Y1071317D02*
X954265D01*
Y1067983D01*
X953765Y1066650D01*
X953098Y1065650D01*
X952098Y1064817D01*
X950931Y1064150D01*
X949265Y1063983D01*
X947598Y1064150D01*
X946432Y1064817D01*
X945431Y1065650D01*
X944765Y1066650D01*
X944265Y1067983D01*
Y1071317D01*
G01X952598Y1060217D02*
X953598Y1059217D01*
X954098Y1058050D01*
X954265Y1056717D01*
X953932Y1055050D01*
X953098Y1053883D01*
X952098Y1053550D01*
X951098Y1053717D01*
X950265Y1054383D01*
X948598Y1057717D01*
X947432Y1059217D01*
X945765Y1060217D01*
X944265Y1060550D01*
Y1053550D01*
G01X937367Y1032375D02*
X937575Y1032708D01*
X937700Y1033083D01*
Y1033417D01*
X937575Y1033750D01*
X937367Y1034000D01*
X937075Y1034125D01*
X936783Y1034042D01*
X936533Y1033833D01*
X936367Y1033458D01*
X936283Y1032958D01*
X936117Y1032667D01*
X935825Y1032542D01*
X935533Y1032625D01*
X935325Y1032833D01*
X935200Y1033125D01*
Y1033417D01*
X935283Y1033708D01*
X935492Y1033958D01*
G01X937700Y1035433D02*
X935200D01*
G01Y1037017D02*
X936742Y1035433D01*
G01X937700Y1037267D02*
X936033Y1036142D01*
G01X935200Y1039450D02*
X937700D01*
G01X935200Y1038492D02*
Y1040408D01*
G01X937200Y1041633D02*
X937492Y1041883D01*
X937658Y1042217D01*
X937700Y1042592D01*
X937658Y1042925D01*
X937450Y1043258D01*
X937200Y1043467D01*
X936950Y1043508D01*
X936658Y1043425D01*
X936450Y1043133D01*
X936367Y1042842D01*
Y1042467D01*
G01Y1042842D02*
X936242Y1043092D01*
X936033Y1043300D01*
X935783Y1043383D01*
X935533Y1043300D01*
X935325Y1043092D01*
X935200Y1042717D01*
X935242Y1042342D01*
X935408Y1041967D01*
G01X986519Y1096897D02*
Y1099397D01*
G01X988269D02*
Y1096897D01*
G01Y1098147D02*
X986519D01*
G01X990494Y1096897D02*
Y1099397D01*
X989994Y1098897D01*
G01Y1096897D02*
X990994D01*
G01X994094D02*
Y1099397D01*
X992552Y1097605D01*
X994636D01*
G01X1033464Y1400276D02*
Y1424882D01*
X1029527Y1428819D01*
X1024212D01*
G02X1019291Y1433740I0J4921D01*
G01Y1610886D01*
X1018307Y1611870D01*
X989744D01*
G02Y1616082I0J2106D01*
G01X1018307D01*
X1019291Y1617066D01*
Y1676496D01*
G02X1024212Y1681417I4921J0D01*
G01X1029527D01*
X1033464Y1685354D01*
Y1709976D01*
X1003491D01*
Y1678726D01*
X990691D01*
Y1617076D01*
X986591D01*
Y1611876D01*
X976891D01*
Y1432676D01*
X1003491D01*
Y1400276D01*
X1033464D01*
G01X954800Y1473500D02*
X949300D01*
G01X954800Y1481500D02*
Y1473500D01*
G01X937200D02*
Y1481500D01*
G01X942700Y1473500D02*
X937200D01*
G01X933267Y1448275D02*
X933475Y1448608D01*
X933600Y1448983D01*
Y1449317D01*
X933475Y1449650D01*
X933267Y1449900D01*
X932975Y1450025D01*
X932683Y1449942D01*
X932433Y1449733D01*
X932267Y1449358D01*
X932183Y1448858D01*
X932017Y1448567D01*
X931725Y1448442D01*
X931433Y1448525D01*
X931225Y1448733D01*
X931100Y1449025D01*
Y1449317D01*
X931183Y1449608D01*
X931392Y1449858D01*
G01X933600Y1451333D02*
X931100D01*
G01Y1452917D02*
X932642Y1451333D01*
G01X933600Y1453167D02*
X931933Y1452042D01*
G01X931100Y1455350D02*
X933600D01*
G01X931100Y1454392D02*
Y1456308D01*
G01X931517Y1457658D02*
X931267Y1457908D01*
X931142Y1458200D01*
X931100Y1458533D01*
X931183Y1458950D01*
X931392Y1459242D01*
X931642Y1459325D01*
X931892Y1459283D01*
X932100Y1459117D01*
X932517Y1458283D01*
X932808Y1457908D01*
X933225Y1457658D01*
X933600Y1457575D01*
Y1459325D01*
G01X937000Y1544500D02*
X947000D01*
G01Y1537500D02*
X937000D01*
G01X942000D02*
Y1544500D01*
G01X937000Y1534067D02*
X947000D01*
Y1530733D01*
X946500Y1529400D01*
X945833Y1528400D01*
X944833Y1527567D01*
X943666Y1526900D01*
X942000Y1526733D01*
X940333Y1526900D01*
X939167Y1527567D01*
X938166Y1528400D01*
X937500Y1529400D01*
X937000Y1530733D01*
Y1534067D01*
G01Y1523467D02*
X947000D01*
Y1520133D01*
X946500Y1518800D01*
X945833Y1517800D01*
X944833Y1516967D01*
X943666Y1516300D01*
X942000Y1516133D01*
X940333Y1516300D01*
X939167Y1516967D01*
X938166Y1517800D01*
X937500Y1518800D01*
X937000Y1520133D01*
Y1523467D01*
G01Y1509200D02*
X947000D01*
X945000Y1511200D01*
G01X937000D02*
Y1507200D01*
G01X959267Y1487692D02*
X959017Y1487817D01*
X958725Y1487900D01*
X958392D01*
X958017Y1487775D01*
X957725Y1487567D01*
X957517Y1487317D01*
X957350Y1486900D01*
X957308Y1486525D01*
X957392Y1486150D01*
X957517Y1485900D01*
X957767Y1485650D01*
X958058Y1485483D01*
X958350Y1485400D01*
X958642D01*
X958933Y1485483D01*
X959183Y1485608D01*
X959392Y1485775D01*
G01X960533Y1485900D02*
X960783Y1485608D01*
X961117Y1485442D01*
X961492Y1485400D01*
X961825Y1485442D01*
X962158Y1485650D01*
X962367Y1485900D01*
X962408Y1486150D01*
X962325Y1486442D01*
X962033Y1486650D01*
X961742Y1486733D01*
X961367D01*
G01X961742D02*
X961992Y1486858D01*
X962200Y1487067D01*
X962283Y1487317D01*
X962200Y1487567D01*
X961992Y1487775D01*
X961617Y1487900D01*
X961242Y1487858D01*
X960867Y1487692D01*
G01X965050Y1485400D02*
Y1487900D01*
X963508Y1486108D01*
X965592D01*
G01X967650Y1485400D02*
X967942Y1485442D01*
X968275Y1485567D01*
X968483Y1485775D01*
X968567Y1486067D01*
X968483Y1486358D01*
X968233Y1486608D01*
X967858Y1486733D01*
X967442D01*
X967192Y1486817D01*
X966983Y1487025D01*
X966900Y1487317D01*
X967025Y1487608D01*
X967317Y1487817D01*
X967650Y1487900D01*
X967983Y1487817D01*
X968275Y1487608D01*
X968400Y1487317D01*
X968317Y1487025D01*
X968108Y1486817D01*
X967858Y1486733D01*
X967442D01*
X967067Y1486608D01*
X966817Y1486358D01*
X966733Y1486067D01*
X966817Y1485775D01*
X967025Y1485567D01*
X967358Y1485442D01*
X967650Y1485400D01*
G01X954700Y1482900D02*
X949200D01*
G01X954700Y1490900D02*
Y1482900D01*
G01X949200Y1490900D02*
X954700D01*
G01X937100D02*
X942600D01*
G01X937100Y1482900D02*
Y1490900D01*
G01X942600Y1482900D02*
X937100D01*
G01X959367Y1478292D02*
X959117Y1478417D01*
X958825Y1478500D01*
X958492D01*
X958117Y1478375D01*
X957825Y1478167D01*
X957617Y1477917D01*
X957450Y1477500D01*
X957408Y1477125D01*
X957492Y1476750D01*
X957617Y1476500D01*
X957867Y1476250D01*
X958158Y1476083D01*
X958450Y1476000D01*
X958742D01*
X959033Y1476083D01*
X959283Y1476208D01*
X959492Y1476375D01*
G01X960633Y1476500D02*
X960883Y1476208D01*
X961217Y1476042D01*
X961592Y1476000D01*
X961925Y1476042D01*
X962258Y1476250D01*
X962467Y1476500D01*
X962508Y1476750D01*
X962425Y1477042D01*
X962133Y1477250D01*
X961842Y1477333D01*
X961467D01*
G01X961842D02*
X962092Y1477458D01*
X962300Y1477667D01*
X962383Y1477917D01*
X962300Y1478167D01*
X962092Y1478375D01*
X961717Y1478500D01*
X961342Y1478458D01*
X960967Y1478292D01*
G01X965150Y1476000D02*
Y1478500D01*
X963608Y1476708D01*
X965692D01*
G01X967042Y1476292D02*
X967333Y1476083D01*
X967667Y1476000D01*
X968000Y1476083D01*
X968292Y1476333D01*
X968500Y1476708D01*
X968583Y1477083D01*
Y1477542D01*
X968500Y1477917D01*
X968292Y1478250D01*
X968042Y1478417D01*
X967750Y1478500D01*
X967417Y1478417D01*
X967167Y1478250D01*
X967000Y1478000D01*
X966917Y1477667D01*
X967000Y1477375D01*
X967208Y1477083D01*
X967458Y1476917D01*
X967750Y1476875D01*
X968083Y1476958D01*
X968333Y1477167D01*
X968583Y1477542D01*
G01X949300Y1481500D02*
X954800D01*
G01X937200D02*
X942700D01*
G01X964817Y1610792D02*
X964567Y1610917D01*
X964275Y1611000D01*
X963942D01*
X963567Y1610875D01*
X963275Y1610667D01*
X963067Y1610417D01*
X962900Y1610000D01*
X962858Y1609625D01*
X962942Y1609250D01*
X963067Y1609000D01*
X963317Y1608750D01*
X963608Y1608583D01*
X963900Y1608500D01*
X964192D01*
X964483Y1608583D01*
X964733Y1608708D01*
X964942Y1608875D01*
G01X966042Y1608500D02*
Y1611000D01*
X967958Y1608500D01*
Y1611000D01*
G01X970017Y1608500D02*
X970100Y1609042D01*
X970225Y1609500D01*
X970392Y1609917D01*
X970600Y1610375D01*
X970933Y1611000D01*
X969267D01*
G01X950967Y1666692D02*
X950717Y1666817D01*
X950425Y1666900D01*
X950092D01*
X949717Y1666775D01*
X949425Y1666567D01*
X949217Y1666317D01*
X949050Y1665900D01*
X949008Y1665525D01*
X949092Y1665150D01*
X949217Y1664900D01*
X949467Y1664650D01*
X949758Y1664483D01*
X950050Y1664400D01*
X950342D01*
X950633Y1664483D01*
X950883Y1664608D01*
X951092Y1664775D01*
G01X952233Y1664900D02*
X952483Y1664608D01*
X952817Y1664442D01*
X953192Y1664400D01*
X953525Y1664442D01*
X953858Y1664650D01*
X954067Y1664900D01*
X954108Y1665150D01*
X954025Y1665442D01*
X953733Y1665650D01*
X953442Y1665733D01*
X953067D01*
G01X953442D02*
X953692Y1665858D01*
X953900Y1666067D01*
X953983Y1666317D01*
X953900Y1666567D01*
X953692Y1666775D01*
X953317Y1666900D01*
X952942Y1666858D01*
X952567Y1666692D01*
G01X955333Y1664775D02*
X955583Y1664567D01*
X955875Y1664442D01*
X956250Y1664400D01*
X956625Y1664483D01*
X956917Y1664650D01*
X957125Y1664942D01*
X957167Y1665275D01*
X957083Y1665608D01*
X956875Y1665817D01*
X956583Y1665983D01*
X956292Y1666025D01*
X956000Y1665983D01*
X955625Y1665817D01*
X955750Y1666900D01*
X956875D01*
G01X958558Y1665442D02*
X958850Y1665733D01*
X959100Y1665900D01*
X959433Y1665983D01*
X959725Y1665900D01*
X959933Y1665733D01*
X960100Y1665483D01*
X960142Y1665192D01*
X960100Y1664942D01*
X959933Y1664692D01*
X959683Y1664483D01*
X959392Y1664400D01*
X959058Y1664483D01*
X958767Y1664733D01*
X958600Y1665108D01*
X958558Y1665525D01*
X958642Y1666067D01*
X958767Y1666358D01*
X958975Y1666650D01*
X959267Y1666858D01*
X959558Y1666900D01*
X959850Y1666817D01*
X960058Y1666608D01*
G01X950767Y1661292D02*
X950517Y1661417D01*
X950225Y1661500D01*
X949892D01*
X949517Y1661375D01*
X949225Y1661167D01*
X949017Y1660917D01*
X948850Y1660500D01*
X948808Y1660125D01*
X948892Y1659750D01*
X949017Y1659500D01*
X949267Y1659250D01*
X949558Y1659083D01*
X949850Y1659000D01*
X950142D01*
X950433Y1659083D01*
X950683Y1659208D01*
X950892Y1659375D01*
G01X952033Y1659500D02*
X952283Y1659208D01*
X952617Y1659042D01*
X952992Y1659000D01*
X953325Y1659042D01*
X953658Y1659250D01*
X953867Y1659500D01*
X953908Y1659750D01*
X953825Y1660042D01*
X953533Y1660250D01*
X953242Y1660333D01*
X952867D01*
G01X953242D02*
X953492Y1660458D01*
X953700Y1660667D01*
X953783Y1660917D01*
X953700Y1661167D01*
X953492Y1661375D01*
X953117Y1661500D01*
X952742Y1661458D01*
X952367Y1661292D01*
G01X955133Y1659375D02*
X955383Y1659167D01*
X955675Y1659042D01*
X956050Y1659000D01*
X956425Y1659083D01*
X956717Y1659250D01*
X956925Y1659542D01*
X956967Y1659875D01*
X956883Y1660208D01*
X956675Y1660417D01*
X956383Y1660583D01*
X956092Y1660625D01*
X955800Y1660583D01*
X955425Y1660417D01*
X955550Y1661500D01*
X956675D01*
G01X958233Y1659375D02*
X958483Y1659167D01*
X958775Y1659042D01*
X959150Y1659000D01*
X959525Y1659083D01*
X959817Y1659250D01*
X960025Y1659542D01*
X960067Y1659875D01*
X959983Y1660208D01*
X959775Y1660417D01*
X959483Y1660583D01*
X959192Y1660625D01*
X958900Y1660583D01*
X958525Y1660417D01*
X958650Y1661500D01*
X959775D01*
G01X929499Y1780450D02*
X929457Y1780117D01*
X929291Y1779825D01*
X929041Y1779575D01*
X928749Y1779408D01*
X928416Y1779325D01*
X928082D01*
X927749Y1779408D01*
X927457Y1779575D01*
X927207Y1779825D01*
X927041Y1780117D01*
X926999Y1780450D01*
X927041Y1780783D01*
X927207Y1781075D01*
X927457Y1781325D01*
X927749Y1781492D01*
X928082Y1781575D01*
X928416D01*
X928749Y1781492D01*
X929041Y1781325D01*
X929291Y1781075D01*
X929457Y1780783D01*
X929499Y1780450D01*
G01X928832Y1780783D02*
X929499Y1781283D01*
G01X928999Y1782633D02*
X929291Y1782883D01*
X929457Y1783217D01*
X929499Y1783592D01*
X929457Y1783925D01*
X929249Y1784258D01*
X928999Y1784467D01*
X928749Y1784508D01*
X928457Y1784425D01*
X928249Y1784133D01*
X928166Y1783842D01*
Y1783467D01*
G01Y1783842D02*
X928041Y1784092D01*
X927832Y1784300D01*
X927582Y1784383D01*
X927332Y1784300D01*
X927124Y1784092D01*
X926999Y1783717D01*
X927041Y1783342D01*
X927207Y1782967D01*
G01X929499Y1787150D02*
X926999D01*
X928791Y1785608D01*
Y1787692D01*
G01X924799Y1774500D02*
Y1787500D01*
G01X932567Y1881275D02*
X932775Y1881608D01*
X932900Y1881983D01*
Y1882317D01*
X932775Y1882650D01*
X932567Y1882900D01*
X932275Y1883025D01*
X931983Y1882942D01*
X931733Y1882733D01*
X931567Y1882358D01*
X931483Y1881858D01*
X931317Y1881567D01*
X931025Y1881442D01*
X930733Y1881525D01*
X930525Y1881733D01*
X930400Y1882025D01*
Y1882317D01*
X930483Y1882608D01*
X930692Y1882858D01*
G01X932900Y1884333D02*
X930400D01*
G01Y1885917D02*
X931942Y1884333D01*
G01X932900Y1886167D02*
X931233Y1885042D01*
G01X930400Y1888350D02*
X932900D01*
G01X930400Y1887392D02*
Y1889308D01*
G01X932900Y1891450D02*
X930400D01*
X930900Y1890950D01*
G01X932900D02*
Y1891950D01*
G01X942431Y1951450D02*
X952431D01*
G01Y1944450D02*
X942431D01*
G01X947431D02*
Y1951450D01*
G01X942431Y1941017D02*
X952431D01*
Y1937683D01*
X951931Y1936350D01*
X951264Y1935350D01*
X950264Y1934517D01*
X949097Y1933850D01*
X947431Y1933683D01*
X945764Y1933850D01*
X944598Y1934517D01*
X943597Y1935350D01*
X942931Y1936350D01*
X942431Y1937683D01*
Y1941017D01*
G01Y1930417D02*
X952431D01*
Y1927083D01*
X951931Y1925750D01*
X951264Y1924750D01*
X950264Y1923917D01*
X949097Y1923250D01*
X947431Y1923083D01*
X945764Y1923250D01*
X944598Y1923917D01*
X943597Y1924750D01*
X942931Y1925750D01*
X942431Y1927083D01*
Y1930417D01*
G01X952431Y1916150D02*
X952098Y1917484D01*
X951264Y1918483D01*
X950264Y1919150D01*
X948931Y1919650D01*
X947431Y1919817D01*
X945931Y1919650D01*
X944598Y1919150D01*
X943597Y1918483D01*
X942764Y1917484D01*
X942431Y1916150D01*
X942764Y1914817D01*
X943597Y1913817D01*
X944598Y1913150D01*
X945931Y1912650D01*
X947431Y1912483D01*
X948931Y1912650D01*
X950264Y1913150D01*
X951264Y1913817D01*
X952098Y1914817D01*
X952431Y1916150D01*
G01X995560Y1912076D02*
Y1914576D01*
G01X997310D02*
Y1912076D01*
G01Y1913326D02*
X995560D01*
G01X999535Y1912076D02*
Y1914576D01*
X999035Y1914076D01*
G01Y1912076D02*
X1000035D01*
G01X1002635D02*
Y1914576D01*
X1002135Y1914076D01*
G01Y1912076D02*
X1003135D01*
G01X1038542Y1546026D02*
X1038875Y1546559D01*
X1039075Y1547159D01*
Y1547693D01*
X1038875Y1548226D01*
X1038542Y1548626D01*
X1038075Y1548826D01*
X1037608Y1548693D01*
X1037208Y1548359D01*
X1036942Y1547759D01*
X1036808Y1546959D01*
X1036542Y1546493D01*
X1036075Y1546293D01*
X1035608Y1546426D01*
X1035275Y1546759D01*
X1035075Y1547226D01*
Y1547693D01*
X1035208Y1548159D01*
X1035542Y1548559D01*
G01X1039075Y1552026D02*
X1035075D01*
G01X1036408Y1556626D02*
X1039075D01*
G01X1035342D02*
X1035275Y1556493D01*
X1035142D01*
X1035075Y1556626D01*
X1035142Y1556759D01*
X1035275D01*
X1035342Y1556626D01*
G01X1035075Y1561226D02*
X1039075D01*
G01X1036408Y1560293D02*
Y1562159D01*
G01X1106971Y471923D02*
X1107438Y472389D01*
X1107838Y472656D01*
X1108371Y472789D01*
X1108838Y472656D01*
X1109171Y472389D01*
X1109438Y471989D01*
X1109505Y471523D01*
X1109438Y471123D01*
X1109171Y470723D01*
X1108771Y470389D01*
X1108305Y470256D01*
X1107771Y470389D01*
X1107305Y470789D01*
X1107038Y471389D01*
X1106971Y472056D01*
X1107105Y472923D01*
X1107305Y473389D01*
X1107638Y473856D01*
X1108105Y474189D01*
X1108571Y474256D01*
X1109038Y474123D01*
X1109371Y473789D01*
G01X1106853Y501018D02*
X1107253Y500685D01*
X1107720Y500485D01*
X1108320Y500418D01*
X1108920Y500551D01*
X1109387Y500818D01*
X1109720Y501285D01*
X1109787Y501818D01*
X1109653Y502351D01*
X1109320Y502685D01*
X1108853Y502951D01*
X1108387Y503018D01*
X1107920Y502951D01*
X1107320Y502685D01*
X1107520Y504418D01*
X1109320D01*
G01X1109565Y532365D02*
Y536365D01*
X1107098Y533498D01*
X1110432D01*
G01X1107061Y564683D02*
X1107461Y564216D01*
X1107995Y563950D01*
X1108595Y563883D01*
X1109128Y563950D01*
X1109661Y564283D01*
X1109995Y564683D01*
X1110061Y565083D01*
X1109928Y565550D01*
X1109461Y565883D01*
X1108995Y566016D01*
X1108395D01*
G01X1108995D02*
X1109395Y566216D01*
X1109728Y566550D01*
X1109861Y566950D01*
X1109728Y567350D01*
X1109395Y567683D01*
X1108795Y567883D01*
X1108195Y567816D01*
X1107595Y567550D01*
G01X1107511Y598945D02*
X1107911Y599345D01*
X1108378Y599545D01*
X1108911Y599612D01*
X1109578Y599479D01*
X1110045Y599145D01*
X1110178Y598745D01*
X1110111Y598345D01*
X1109845Y598012D01*
X1108511Y597345D01*
X1107911Y596879D01*
X1107511Y596212D01*
X1107378Y595612D01*
X1110178D01*
G01X1108140Y627159D02*
Y631159D01*
X1107340Y630359D01*
G01Y627159D02*
X1108940D01*
M02*
